G04 ================== begin FILE IDENTIFICATION RECORD ==================*
G04 Layout Name:  D:/<user>/Wistron_project/16317-1/gbr/16317-1.brd*
G04 Film Name:    NOTICE*
G04 File Format:  Gerber RS274X*
G04 File Origin:  Cadence Allegro 16.5-S056*
G04 Origin Date:  Fri Jun 09 15:53:11 2017*
G04 *
G04 Layer:  MANUFACTURING/THERMAL*
G04 *
G04 Offset:    (0.00 0.00)*
G04 Mirror:    No*
G04 Mode:      Positive*
G04 Rotation:  0*
G04 FullContactRelief:  No*
G04 UndefLineWidth:     6.00*
G04 ================== end FILE IDENTIFICATION RECORD ====================*
%FSLAX35Y35*MOIN*%
%IR0*IPPOS*OFA0.00000B0.00000*MIA0B0*SFA1.00000B1.00000*%
%ADD10C,.004*%
%ADD11C,.006*%
%ADD12C,.0033*%
%ADD13C,.008*%
%ADD14C,.0055*%
G75*
%LPD*%
G75*
G36*
G01X301800Y213890D02*
G02X352500Y214150I25558J-40503D01*
G01X341350Y192820D01*
X312850D01*
X301800Y213890D01*
G37*
G36*
G01X298620Y274980D02*
X307300D01*
G03X341410Y274970I17058J11442D01*
G01X348960D01*
X338090Y253970D01*
X309590D01*
X298620Y274980D01*
G37*
G54D10*
G01X852594Y151868D02*
Y155868D01*
G01X840009Y167889D02*
X890009D01*
G01X840009Y225249D02*
Y167889D01*
G01X859454Y153868D02*
X840594D01*
G01X852594Y155868D02*
X840594Y153868D01*
G01Y141868D02*
Y161868D01*
G01Y153868D02*
X852594Y151868D01*
G01X820594Y153868D02*
X808594Y155868D01*
G01X820009Y224740D02*
Y167889D01*
G01X820594Y161868D02*
Y141868D01*
G01X808594Y155868D02*
Y151868D01*
G01D02*
X820594Y153868D01*
G01X790009Y177889D02*
Y207889D01*
G01X796594Y153868D02*
X820594D01*
G01X770009Y177889D02*
X790009D01*
G01X820009Y167889D02*
X770009D01*
G01D02*
Y177889D01*
G01X845009Y225249D02*
X961000D01*
G01X850009Y297889D02*
Y235249D01*
G01D02*
X840009Y225249D01*
G01X810005Y234744D02*
X810009Y234740D01*
G01Y297889D02*
Y234740D01*
G01D02*
X820009Y224740D01*
G01X790009Y257889D02*
Y287889D01*
G01Y217889D02*
Y247889D01*
G01X770009Y257889D02*
X790009D01*
G01X770009Y247889D02*
Y257889D01*
G01X790009Y247889D02*
X770009D01*
G01Y217889D02*
X790009D01*
G01X770009Y207889D02*
Y217889D01*
G01X790009Y207889D02*
X770009D01*
G01X850514Y319548D02*
Y299548D01*
G01Y307548D02*
X859374D01*
G01X838514Y309548D02*
Y305548D01*
G01X850514Y307548D02*
X838514Y309548D01*
G01Y305548D02*
X850514Y307548D01*
G01X890009Y297889D02*
X850009D01*
G01X810514Y319548D02*
Y299548D01*
G01X822514Y305548D02*
Y309548D01*
G01X810514Y307548D02*
X822514Y305548D01*
G01Y309548D02*
X810514Y307548D01*
G01D02*
X850514D01*
G01X770009Y297889D02*
X810009D01*
G01X770009Y287889D02*
Y297889D01*
G01X790009Y287889D02*
X770009D01*
G01X890009Y167889D02*
Y177889D01*
G01X870009D02*
Y207889D01*
G01X890009Y177889D02*
X870009D01*
G01X954000Y237249D02*
X956000Y225249D01*
X958000Y237249D01*
X954000D01*
G01X956000Y249249D02*
Y225249D01*
G01X958000Y205889D02*
X956000Y217889D01*
X954000Y205889D01*
X958000D01*
G01X956000Y193889D02*
Y217889D01*
G01X895009D02*
X961000D01*
G01X890009Y247889D02*
Y257889D01*
G01Y207889D02*
X890000Y217800D01*
G01X870009Y257889D02*
Y287889D01*
G01X890009Y257889D02*
X870009D01*
G01Y247889D02*
X890009D01*
G01X870009Y217889D02*
Y247889D01*
G01X890009Y217889D02*
X870009D01*
G01Y207889D02*
X890009D01*
G01Y287889D02*
Y297889D01*
G01X870009Y287889D02*
X890009D01*
G01X1121654Y169388D02*
Y232028D01*
G01X1133654Y149388D02*
Y153388D01*
G01X1121654Y151388D02*
X1133654Y149388D01*
G01Y153388D02*
X1121654Y151388D01*
G01D02*
X1161654D01*
G01X1121654Y163388D02*
Y143388D01*
G01X1101654Y209388D02*
Y179388D01*
G01D02*
X1081654D01*
G01Y169388D02*
X1121654D01*
G01X1081654Y179388D02*
Y169388D01*
G01X1131654Y242028D02*
Y299388D01*
G01X1121654Y232028D02*
X1131654Y242028D01*
G01X1101654Y289388D02*
Y259388D01*
G01Y249388D02*
Y219388D01*
G01X1081654Y249388D02*
X1101654D01*
G01X1081654Y259388D02*
Y249388D01*
G01X1101654Y259388D02*
X1081654D01*
G01Y209388D02*
X1101654D01*
G01X1081654Y219388D02*
Y209388D01*
G01X1101654Y219388D02*
X1081654D01*
G01X1119654Y321388D02*
Y317388D01*
G01X1131654Y319388D02*
X1119654Y321388D01*
G01Y317388D02*
X1131654Y319388D01*
G01Y327388D02*
Y307388D01*
G01X1107654Y319388D02*
X1131654D01*
G01Y299388D02*
X1081654D01*
G01Y289388D02*
X1101654D01*
G01X1081654Y299388D02*
Y289388D01*
G01X1201654Y179388D02*
Y169388D01*
G01X1181654Y179388D02*
X1201654D01*
G01X1181654Y209388D02*
Y179388D01*
G01X1161654Y169388D02*
Y232537D01*
G01X1201654Y169388D02*
X1161654D01*
G01X1149654Y153388D02*
Y149388D01*
G01X1161654Y151388D02*
X1149654Y153388D01*
G01Y149388D02*
X1161654Y151388D01*
G01D02*
X1170514D01*
G01X1161654Y163388D02*
Y143388D01*
G01X1201654Y259388D02*
Y249388D01*
G01Y219388D02*
Y209388D01*
G01Y249388D02*
X1181654D01*
G01Y259388D02*
X1201654D01*
G01X1181654Y289388D02*
Y259388D01*
G01X1201654Y209388D02*
X1181654D01*
G01Y219388D02*
X1201654D01*
G01X1181654Y249388D02*
Y219388D01*
G01X1161658Y232533D02*
X1161654Y232537D01*
G01X1151654Y242537D02*
Y299388D01*
G01X1161654Y232537D02*
X1151654Y242537D01*
G01X1201654Y299388D02*
Y289388D01*
G01X1163654Y317388D02*
Y321388D01*
G01X1201654Y289388D02*
X1181654D01*
G01X1170514Y319388D02*
X1151654D01*
G01D02*
X1163654Y317388D01*
G01Y321388D02*
X1151654Y319388D01*
G01Y307388D02*
Y327388D01*
G01Y299388D02*
X1201654D01*
G54D11*
G01X4300Y524700D02*
X4250D01*
G01X54300Y770700D02*
X54250D01*
G01X288350Y208820D02*
X283350D01*
Y182820D01*
X288350D01*
G01Y187820D02*
X307850D01*
X296850Y208820D01*
X288350D01*
Y213820D01*
X301850D01*
X312850Y192820D01*
X341350D01*
X352350Y213820D01*
X365850D01*
Y208820D01*
X357350D01*
X346350Y187820D01*
X365850D01*
G01X288350D02*
Y182820D01*
X365850D01*
Y187820D01*
G01X285090Y269970D02*
X280090D01*
Y243970D01*
X285090D01*
G01Y248970D02*
X304590D01*
X293590Y269970D01*
X285090D01*
Y274970D01*
X298590D01*
X309590Y253970D01*
X338090D01*
X349090Y274970D01*
X362590D01*
Y269970D01*
X354090D01*
X343090Y248970D01*
X362590D01*
G01X285090D02*
Y243970D01*
X362590D01*
Y248970D01*
G01X283590Y340830D02*
X278590D01*
Y314830D01*
X283590D01*
G01Y319830D02*
Y314830D01*
X361090D01*
Y319830D01*
G01X283590D02*
X303090D01*
X292090Y340830D01*
X283590D01*
Y345830D01*
X297090D01*
X308090Y324830D01*
X336590D01*
X347590Y345830D01*
X361090D01*
Y340830D01*
X352590D01*
X341590Y319830D01*
X361090D01*
G01X365850Y208820D02*
X370850D01*
Y182820D01*
X365850D01*
G01X385140Y233310D02*
X383140Y221310D01*
X381140Y233310D01*
X385140D01*
G01X383140Y237850D02*
Y221310D01*
G01X385140Y202130D02*
X383140Y214130D01*
X381140Y202130D01*
X385140D01*
G01X383140Y197250D02*
Y214130D01*
G01X357370D02*
X388140D01*
G01X332370Y221310D02*
X388140D01*
G01X384990Y287010D02*
X382990Y275010D01*
X380990Y287010D01*
X384990D01*
G01X382990Y275010D02*
Y290150D01*
G01X384990Y254000D02*
X382990Y266000D01*
X380990Y254000D01*
X384990D01*
G01X382990Y250500D02*
Y266000D01*
G01X329290D02*
X387990D01*
G01X346210Y275010D02*
X387990D01*
G01X362590Y269970D02*
X367590D01*
Y243970D01*
X362590D01*
G01X329590Y306830D02*
X341590Y308830D01*
X329590Y310830D01*
Y306830D01*
G01X339890Y308830D02*
X341590D01*
G01X315090Y310830D02*
X303090Y308830D01*
X315090Y306830D01*
Y310830D01*
G01X306290Y308830D02*
X303090D01*
G01X340590Y350830D02*
X352590Y352830D01*
X340590Y354830D01*
Y350830D01*
G01X334890Y352830D02*
X352590D01*
G01X304090Y354830D02*
X292090Y352830D01*
X304090Y350830D01*
Y354830D01*
G01X311290Y352830D02*
X292090D01*
G01X339590Y308830D02*
X304090D01*
G01X361090Y340830D02*
X366090D01*
Y314830D01*
X361090D01*
G01X849500Y-12500D02*
Y59500D01*
X893500D01*
Y-12500D01*
X849500D01*
G01Y-12451D02*
X821000Y-12500D01*
G01X837503Y-14472D02*
X849500Y-12451D01*
X837497Y-10472D01*
X837503Y-14472D01*
G01X864500Y72000D02*
X849500Y69500D01*
X864500Y67000D01*
Y72000D01*
G01X893500Y69500D02*
X849500D01*
G01Y64500D02*
Y79500D01*
G01X827500Y639629D02*
X830000Y624629D01*
X832500Y639629D01*
X827500D01*
G01X830000Y661875D02*
Y624629D01*
G01X931340D02*
X820000D01*
G01X832500Y710829D02*
X830000Y725829D01*
X827500Y710829D01*
X832500D01*
G01X830000Y693125D02*
Y725829D01*
G01X846340D02*
X820000D01*
G01X932000Y2500D02*
X934500Y-12500D01*
X937000Y2500D01*
X932000D01*
G01X934500Y11875D02*
Y-12500D01*
G01X903500D02*
X944500D01*
G01X937000Y44500D02*
X934500Y59500D01*
X932000Y44500D01*
X937000D01*
G01X934500Y43125D02*
Y59500D01*
G01X903500D02*
X944500D01*
G01X878500Y67000D02*
X893500Y69500D01*
X878500Y72000D01*
Y67000D01*
G01X901475Y69500D02*
X893500D01*
G01Y64500D02*
Y79500D01*
G01X1114953Y628479D02*
X1131500Y617000D01*
X1132500D01*
G01X1119916Y626861D02*
X1114953Y628479D01*
X1118206Y624397D01*
X1119916Y626861D01*
G01X1156654Y242537D02*
X1274500D01*
G01X1206654Y249388D02*
X1274500D01*
G01X1267500Y261388D02*
X1269500Y249388D01*
X1271500Y261388D01*
X1267500D01*
G01X1269500Y277200D02*
Y249388D01*
G01X1271500Y230537D02*
X1269500Y242537D01*
X1267500Y230537D01*
X1271500D01*
G01X1269500Y218537D02*
Y242537D01*
G01X0Y-24500D02*
X694500D01*
G01X0Y716000D02*
Y-69500D01*
G01D02*
X694500D01*
G01X0Y19500D02*
X694500D01*
G01X1500Y175500D02*
X694500D01*
G01X0Y105500D02*
X694500D01*
G01X0Y120500D02*
X694500D01*
G01X0Y599000D02*
X694500D01*
G01X-1000Y654000D02*
X694500D01*
G01X0Y679000D02*
X694500D01*
G01X0Y850500D02*
Y709000D01*
X694500D01*
Y850500D01*
G01X0Y820500D02*
X694500D01*
G01X0Y850500D02*
X694500D01*
G01X11750Y-48833D02*
X12417Y-49250D01*
X13167Y-49500D01*
X13833D01*
X14500Y-49250D01*
X15000Y-48833D01*
X15250Y-48250D01*
X15083Y-47667D01*
X14667Y-47167D01*
X13917Y-46833D01*
X12917Y-46667D01*
X12333Y-46333D01*
X12083Y-45750D01*
X12250Y-45167D01*
X12667Y-44750D01*
X13250Y-44500D01*
X13833D01*
X14417Y-44667D01*
X14917Y-45083D01*
G01X19100Y-46167D02*
Y-49500D01*
G01Y-44833D02*
X18933Y-44750D01*
Y-44583D01*
X19100Y-44500D01*
X19267Y-44583D01*
Y-44750D01*
X19100Y-44833D01*
G01X24700Y-49500D02*
Y-44500D01*
G01X28883Y-49500D02*
Y-44500D01*
G01X31550Y-46167D02*
X28883Y-48083D01*
G01X29967Y-47333D02*
X31717Y-49500D01*
G01X34650Y-48917D02*
X35067Y-49250D01*
X35650Y-49500D01*
X36150D01*
X36650Y-49333D01*
X36983Y-49083D01*
X37150Y-48750D01*
X37067Y-48250D01*
X36733Y-48000D01*
X35233Y-47500D01*
X34900Y-46917D01*
X35067Y-46500D01*
X35400Y-46250D01*
X35900Y-46167D01*
X36400Y-46250D01*
X36900Y-46500D01*
G01X42833Y-46583D02*
X42250Y-46250D01*
X41750Y-46167D01*
X41083Y-46333D01*
X40583Y-46667D01*
X40250Y-47250D01*
X40167Y-47833D01*
X40250Y-48417D01*
X40583Y-48917D01*
X41083Y-49333D01*
X41750Y-49500D01*
X42333Y-49333D01*
X42833Y-49000D01*
G01X45933Y-49500D02*
Y-46167D01*
G01Y-46833D02*
X46350Y-46500D01*
X46767Y-46250D01*
X47350Y-46167D01*
X47767Y-46250D01*
X48267Y-46500D01*
G01X51450Y-47250D02*
X54117D01*
X53867Y-46667D01*
X53450Y-46333D01*
X52867Y-46167D01*
X52283Y-46250D01*
X51783Y-46500D01*
X51450Y-47083D01*
X51283Y-47583D01*
Y-48083D01*
X51450Y-48583D01*
X51867Y-49083D01*
X52367Y-49417D01*
X52950Y-49500D01*
X53533Y-49333D01*
X54117Y-48833D01*
G01X57050Y-47250D02*
X59717D01*
X59467Y-46667D01*
X59050Y-46333D01*
X58467Y-46167D01*
X57883Y-46250D01*
X57383Y-46500D01*
X57050Y-47083D01*
X56883Y-47583D01*
Y-48083D01*
X57050Y-48583D01*
X57467Y-49083D01*
X57967Y-49417D01*
X58550Y-49500D01*
X59133Y-49333D01*
X59717Y-48833D01*
G01X62483Y-49500D02*
Y-46167D01*
G01Y-47000D02*
X62817Y-46583D01*
X63317Y-46250D01*
X63983Y-46167D01*
X64567Y-46250D01*
X65067Y-46583D01*
X65317Y-47167D01*
Y-49500D01*
G01X11750Y-3833D02*
X12417Y-4250D01*
X13167Y-4500D01*
X13833D01*
X14500Y-4250D01*
X15000Y-3833D01*
X15250Y-3250D01*
X15083Y-2667D01*
X14667Y-2167D01*
X13917Y-1833D01*
X12917Y-1667D01*
X12333Y-1333D01*
X12083Y-750D01*
X12250Y-167D01*
X12667Y250D01*
X13250Y500D01*
X13833D01*
X14417Y333D01*
X14917Y-83D01*
G01X19100Y-4500D02*
X18600Y-4417D01*
X18100Y-4083D01*
X17767Y-3500D01*
X17600Y-2833D01*
X17767Y-2167D01*
X18100Y-1583D01*
X18600Y-1250D01*
X19100Y-1167D01*
X19600Y-1250D01*
X20100Y-1583D01*
X20433Y-2167D01*
X20517Y-2833D01*
X20433Y-3500D01*
X20100Y-4083D01*
X19600Y-4417D01*
X19100Y-4500D01*
G01X24700D02*
Y500D01*
G01X31800D02*
Y-4500D01*
G01Y-3750D02*
X31467Y-4167D01*
X30967Y-4417D01*
X30383Y-4500D01*
X29717Y-4333D01*
X29217Y-3917D01*
X28883Y-3417D01*
X28800Y-2833D01*
X28883Y-2250D01*
X29217Y-1750D01*
X29717Y-1333D01*
X30383Y-1167D01*
X30967Y-1250D01*
X31383Y-1417D01*
X31800Y-1750D01*
G01X34650Y-2250D02*
X37317D01*
X37067Y-1667D01*
X36650Y-1333D01*
X36067Y-1167D01*
X35483Y-1250D01*
X34983Y-1500D01*
X34650Y-2083D01*
X34483Y-2583D01*
Y-3083D01*
X34650Y-3583D01*
X35067Y-4083D01*
X35567Y-4417D01*
X36150Y-4500D01*
X36733Y-4333D01*
X37317Y-3833D01*
G01X40333Y-4500D02*
Y-1167D01*
G01Y-1833D02*
X40750Y-1500D01*
X41167Y-1250D01*
X41750Y-1167D01*
X42167Y-1250D01*
X42667Y-1500D01*
G01X50200Y-4500D02*
Y-1167D01*
G01Y-2083D02*
X50450Y-1667D01*
X50867Y-1333D01*
X51450Y-1167D01*
X52033Y-1333D01*
X52450Y-1667D01*
X52700Y-2083D01*
Y-4500D01*
G01Y-2083D02*
X52950Y-1667D01*
X53367Y-1333D01*
X53950Y-1167D01*
X54533Y-1333D01*
X54950Y-1667D01*
X55200Y-2167D01*
Y-4500D01*
G01X59800D02*
Y-1167D01*
G01Y-1750D02*
X59467Y-1417D01*
X58967Y-1250D01*
X58383Y-1167D01*
X57800Y-1333D01*
X57300Y-1667D01*
X56967Y-2167D01*
X56800Y-2833D01*
X56967Y-3500D01*
X57300Y-4000D01*
X57800Y-4333D01*
X58383Y-4500D01*
X58967Y-4417D01*
X59467Y-4167D01*
X59800Y-3833D01*
G01X62650Y-3917D02*
X63067Y-4250D01*
X63650Y-4500D01*
X64150D01*
X64650Y-4333D01*
X64983Y-4083D01*
X65150Y-3750D01*
X65067Y-3250D01*
X64733Y-3000D01*
X63233Y-2500D01*
X62900Y-1917D01*
X63067Y-1500D01*
X63400Y-1250D01*
X63900Y-1167D01*
X64400Y-1250D01*
X64900Y-1500D01*
G01X68083Y-4500D02*
Y500D01*
G01X70750Y-1167D02*
X68083Y-3083D01*
G01X69167Y-2333D02*
X70917Y-4500D01*
G01X15167Y64000D02*
X11833D01*
Y69000D01*
X15167D01*
G01X13833Y66583D02*
X11833D01*
G01X19100Y69000D02*
Y64000D01*
G01X17933Y67333D02*
X20267D01*
G01X26033Y66917D02*
X25450Y67250D01*
X24950Y67333D01*
X24283Y67167D01*
X23783Y66833D01*
X23450Y66250D01*
X23367Y65667D01*
X23450Y65083D01*
X23783Y64583D01*
X24283Y64167D01*
X24950Y64000D01*
X25533Y64167D01*
X26033Y64500D01*
G01X28883Y64000D02*
Y69000D01*
G01Y66583D02*
X29300Y67000D01*
X29717Y67250D01*
X30383Y67333D01*
X30883Y67250D01*
X31467Y66917D01*
X31717Y66417D01*
Y64000D01*
G01X15167Y111500D02*
X11833D01*
Y116500D01*
X15167D01*
G01X13833Y114083D02*
X11833D01*
G01X17850Y114833D02*
X20350Y111500D01*
G01Y114833D02*
X17850Y111500D01*
G01X24700Y116500D02*
Y111500D01*
G01X23533Y114833D02*
X25867D01*
G01X29050Y113750D02*
X31717D01*
X31467Y114333D01*
X31050Y114667D01*
X30467Y114833D01*
X29883Y114750D01*
X29383Y114500D01*
X29050Y113917D01*
X28883Y113417D01*
Y112917D01*
X29050Y112417D01*
X29467Y111917D01*
X29967Y111583D01*
X30550Y111500D01*
X31133Y111667D01*
X31717Y112167D01*
G01X34733Y111500D02*
Y114833D01*
G01Y114167D02*
X35150Y114500D01*
X35567Y114750D01*
X36150Y114833D01*
X36567Y114750D01*
X37067Y114500D01*
G01X40083Y111500D02*
Y114833D01*
G01Y114000D02*
X40417Y114417D01*
X40917Y114750D01*
X41583Y114833D01*
X42167Y114750D01*
X42667Y114417D01*
X42917Y113833D01*
Y111500D01*
G01X48600D02*
Y114833D01*
G01Y114250D02*
X48267Y114583D01*
X47767Y114750D01*
X47183Y114833D01*
X46600Y114667D01*
X46100Y114333D01*
X45767Y113833D01*
X45600Y113167D01*
X45767Y112500D01*
X46100Y112000D01*
X46600Y111667D01*
X47183Y111500D01*
X47767Y111583D01*
X48267Y111833D01*
X48600Y112167D01*
G01X52700Y111500D02*
Y116500D01*
G01X63900Y111500D02*
Y116500D01*
G01X71000Y111500D02*
Y114833D01*
G01Y114250D02*
X70667Y114583D01*
X70167Y114750D01*
X69583Y114833D01*
X69000Y114667D01*
X68500Y114333D01*
X68167Y113833D01*
X68000Y113167D01*
X68167Y112500D01*
X68500Y112000D01*
X69000Y111667D01*
X69583Y111500D01*
X70167Y111583D01*
X70667Y111833D01*
X71000Y112167D01*
G01X73350Y110000D02*
X73850Y109833D01*
X74517Y110000D01*
X74933Y110333D01*
X75267Y110750D01*
X75767Y112083D01*
X76850Y114833D01*
G01X74183D02*
X75767Y112083D01*
G01X79450Y113750D02*
X82117D01*
X81867Y114333D01*
X81450Y114667D01*
X80867Y114833D01*
X80283Y114750D01*
X79783Y114500D01*
X79450Y113917D01*
X79283Y113417D01*
Y112917D01*
X79450Y112417D01*
X79867Y111917D01*
X80367Y111583D01*
X80950Y111500D01*
X81533Y111667D01*
X82117Y112167D01*
G01X85133Y111500D02*
Y114833D01*
G01Y114167D02*
X85550Y114500D01*
X85967Y114750D01*
X86550Y114833D01*
X86967Y114750D01*
X87467Y114500D01*
G01X15333Y146083D02*
X14833Y146333D01*
X14250Y146500D01*
X13583D01*
X12833Y146250D01*
X12250Y145833D01*
X11833Y145333D01*
X11500Y144500D01*
X11417Y143750D01*
X11583Y143000D01*
X11833Y142500D01*
X12333Y142000D01*
X12917Y141667D01*
X13500Y141500D01*
X14083D01*
X14667Y141667D01*
X15167Y141917D01*
X15583Y142250D01*
G01X19100Y141500D02*
X18600Y141583D01*
X18100Y141917D01*
X17767Y142500D01*
X17600Y143167D01*
X17767Y143833D01*
X18100Y144417D01*
X18600Y144750D01*
X19100Y144833D01*
X19600Y144750D01*
X20100Y144417D01*
X20433Y143833D01*
X20517Y143167D01*
X20433Y142500D01*
X20100Y141917D01*
X19600Y141583D01*
X19100Y141500D01*
G01X23200Y139833D02*
Y144833D01*
G01Y144083D02*
X23617Y144500D01*
X24033Y144750D01*
X24700Y144833D01*
X25283Y144750D01*
X25867Y144333D01*
X26117Y143750D01*
X26200Y143167D01*
X26117Y142583D01*
X25867Y142000D01*
X25367Y141667D01*
X24700Y141500D01*
X24117Y141583D01*
X23533Y141833D01*
X23200Y142167D01*
G01X28800Y139833D02*
Y144833D01*
G01Y144083D02*
X29217Y144500D01*
X29633Y144750D01*
X30300Y144833D01*
X30883Y144750D01*
X31467Y144333D01*
X31717Y143750D01*
X31800Y143167D01*
X31717Y142583D01*
X31467Y142000D01*
X30967Y141667D01*
X30300Y141500D01*
X29717Y141583D01*
X29133Y141833D01*
X28800Y142167D01*
G01X34650Y143750D02*
X37317D01*
X37067Y144333D01*
X36650Y144667D01*
X36067Y144833D01*
X35483Y144750D01*
X34983Y144500D01*
X34650Y143917D01*
X34483Y143417D01*
Y142917D01*
X34650Y142417D01*
X35067Y141917D01*
X35567Y141583D01*
X36150Y141500D01*
X36733Y141667D01*
X37317Y142167D01*
G01X40333Y141500D02*
Y144833D01*
G01Y144167D02*
X40750Y144500D01*
X41167Y144750D01*
X41750Y144833D01*
X42167Y144750D01*
X42667Y144500D01*
G01X51033Y141500D02*
Y146500D01*
X53033D01*
X53700Y146250D01*
X54200Y145667D01*
X54367Y145000D01*
X54200Y144333D01*
X53783Y143833D01*
X53033Y143583D01*
X51033D01*
G01X58300Y141500D02*
Y146500D01*
G01X65400Y141500D02*
Y144833D01*
G01Y144250D02*
X65067Y144583D01*
X64567Y144750D01*
X63983Y144833D01*
X63400Y144667D01*
X62900Y144333D01*
X62567Y143833D01*
X62400Y143167D01*
X62567Y142500D01*
X62900Y142000D01*
X63400Y141667D01*
X63983Y141500D01*
X64567Y141583D01*
X65067Y141833D01*
X65400Y142167D01*
G01X69500Y146500D02*
Y141500D01*
G01X68333Y144833D02*
X70667D01*
G01X75100D02*
Y141500D01*
G01Y146167D02*
X74933Y146250D01*
Y146417D01*
X75100Y146500D01*
X75267Y146417D01*
Y146250D01*
X75100Y146167D01*
G01X79283Y141500D02*
Y144833D01*
G01Y144000D02*
X79617Y144417D01*
X80117Y144750D01*
X80783Y144833D01*
X81367Y144750D01*
X81867Y144417D01*
X82117Y143833D01*
Y141500D01*
G01X85133Y140250D02*
X85717Y139917D01*
X86383Y139833D01*
X86967Y139917D01*
X87467Y140333D01*
X87800Y140917D01*
Y144833D01*
G01Y144167D02*
X87467Y144500D01*
X86967Y144750D01*
X86383Y144833D01*
X85717Y144667D01*
X85300Y144333D01*
X84967Y143750D01*
X84800Y143167D01*
X84883Y142667D01*
X85217Y142083D01*
X85717Y141667D01*
X86383Y141500D01*
X86883Y141583D01*
X87467Y141917D01*
X87800Y142250D01*
G01X11667Y459000D02*
Y464000D01*
X13333D01*
X14000Y463750D01*
X14500Y463417D01*
X14917Y462917D01*
X15250Y462333D01*
X15333Y461500D01*
X15250Y460667D01*
X14917Y460083D01*
X14500Y459583D01*
X14000Y459250D01*
X13333Y459000D01*
X11667D01*
G01X17933D02*
Y462333D01*
G01Y461667D02*
X18350Y462000D01*
X18767Y462250D01*
X19350Y462333D01*
X19767Y462250D01*
X20267Y462000D01*
G01X24700Y462333D02*
Y459000D01*
G01Y463667D02*
X24533Y463750D01*
Y463917D01*
X24700Y464000D01*
X24867Y463917D01*
Y463750D01*
X24700Y463667D01*
G01X30300Y459000D02*
Y464000D01*
G01X35900Y459000D02*
Y464000D01*
G01X24960Y626740D02*
X26960D01*
G01X25960D02*
Y621740D01*
G01X24960D02*
X26960D01*
G01X30143D02*
Y625073D01*
G01Y624240D02*
X30477Y624657D01*
X30977Y624990D01*
X31643Y625073D01*
X32227Y624990D01*
X32727Y624657D01*
X32977Y624073D01*
Y621740D01*
G01X35743D02*
Y625073D01*
G01Y624240D02*
X36077Y624657D01*
X36577Y624990D01*
X37243Y625073D01*
X37827Y624990D01*
X38327Y624657D01*
X38577Y624073D01*
Y621740D01*
G01X41510Y623990D02*
X44177D01*
X43927Y624573D01*
X43510Y624907D01*
X42927Y625073D01*
X42343Y624990D01*
X41843Y624740D01*
X41510Y624157D01*
X41343Y623657D01*
Y623157D01*
X41510Y622657D01*
X41927Y622157D01*
X42427Y621823D01*
X43010Y621740D01*
X43593Y621907D01*
X44177Y622407D01*
G01X47193Y621740D02*
Y625073D01*
G01Y624407D02*
X47610Y624740D01*
X48027Y624990D01*
X48610Y625073D01*
X49027Y624990D01*
X49527Y624740D01*
G01X59560Y621740D02*
Y626740D01*
G01X66660Y621740D02*
Y625073D01*
G01Y624490D02*
X66327Y624823D01*
X65827Y624990D01*
X65243Y625073D01*
X64660Y624907D01*
X64160Y624573D01*
X63827Y624073D01*
X63660Y623407D01*
X63827Y622740D01*
X64160Y622240D01*
X64660Y621907D01*
X65243Y621740D01*
X65827Y621823D01*
X66327Y622073D01*
X66660Y622407D01*
G01X69010Y620240D02*
X69510Y620073D01*
X70177Y620240D01*
X70593Y620573D01*
X70927Y620990D01*
X71427Y622323D01*
X72510Y625073D01*
G01X69843D02*
X71427Y622323D01*
G01X75110Y623990D02*
X77777D01*
X77527Y624573D01*
X77110Y624907D01*
X76527Y625073D01*
X75943Y624990D01*
X75443Y624740D01*
X75110Y624157D01*
X74943Y623657D01*
Y623157D01*
X75110Y622657D01*
X75527Y622157D01*
X76027Y621823D01*
X76610Y621740D01*
X77193Y621907D01*
X77777Y622407D01*
G01X80793Y621740D02*
Y625073D01*
G01Y624407D02*
X81210Y624740D01*
X81627Y624990D01*
X82210Y625073D01*
X82627Y624990D01*
X83127Y624740D01*
G01X34000Y663333D02*
Y668333D01*
G01Y667583D02*
X34417Y668000D01*
X34833Y668250D01*
X35500Y668333D01*
X36083Y668250D01*
X36667Y667833D01*
X36917Y667250D01*
X37000Y666667D01*
X36917Y666083D01*
X36667Y665500D01*
X36167Y665167D01*
X35500Y665000D01*
X34917Y665083D01*
X34333Y665333D01*
X34000Y665667D01*
G01X39933Y665000D02*
Y668333D01*
G01Y667667D02*
X40350Y668000D01*
X40767Y668250D01*
X41350Y668333D01*
X41767Y668250D01*
X42267Y668000D01*
G01X46700Y665000D02*
X46200Y665083D01*
X45700Y665417D01*
X45367Y666000D01*
X45200Y666667D01*
X45367Y667333D01*
X45700Y667917D01*
X46200Y668250D01*
X46700Y668333D01*
X47200Y668250D01*
X47700Y667917D01*
X48033Y667333D01*
X48117Y666667D01*
X48033Y666000D01*
X47700Y665417D01*
X47200Y665083D01*
X46700Y665000D01*
G01X53633Y667917D02*
X53050Y668250D01*
X52550Y668333D01*
X51883Y668167D01*
X51383Y667833D01*
X51050Y667250D01*
X50967Y666667D01*
X51050Y666083D01*
X51383Y665583D01*
X51883Y665167D01*
X52550Y665000D01*
X53133Y665167D01*
X53633Y665500D01*
G01X56650Y667250D02*
X59317D01*
X59067Y667833D01*
X58650Y668167D01*
X58067Y668333D01*
X57483Y668250D01*
X56983Y668000D01*
X56650Y667417D01*
X56483Y666917D01*
Y666417D01*
X56650Y665917D01*
X57067Y665417D01*
X57567Y665083D01*
X58150Y665000D01*
X58733Y665167D01*
X59317Y665667D01*
G01X62250Y665583D02*
X62667Y665250D01*
X63250Y665000D01*
X63750D01*
X64250Y665167D01*
X64583Y665417D01*
X64750Y665750D01*
X64667Y666250D01*
X64333Y666500D01*
X62833Y667000D01*
X62500Y667583D01*
X62667Y668000D01*
X63000Y668250D01*
X63500Y668333D01*
X64000Y668250D01*
X64500Y668000D01*
G01X67850Y665583D02*
X68267Y665250D01*
X68850Y665000D01*
X69350D01*
X69850Y665167D01*
X70183Y665417D01*
X70350Y665750D01*
X70267Y666250D01*
X69933Y666500D01*
X68433Y667000D01*
X68100Y667583D01*
X68267Y668000D01*
X68600Y668250D01*
X69100Y668333D01*
X69600Y668250D01*
X70100Y668000D01*
G01X9917Y693667D02*
X10417Y694167D01*
X11000Y694417D01*
X11667Y694500D01*
X12500Y694333D01*
X13083Y693917D01*
X13250Y693417D01*
X13167Y692917D01*
X12833Y692500D01*
X11167Y691667D01*
X10417Y691083D01*
X9917Y690250D01*
X9750Y689500D01*
X13250D01*
G01X17100Y689333D02*
X16933Y689417D01*
Y689583D01*
X17100Y689667D01*
X17267Y689583D01*
Y689417D01*
X17100Y689333D01*
G01X22700Y694500D02*
Y689500D01*
G01X20783Y694500D02*
X24617D01*
G01X28300Y689500D02*
X27800Y689583D01*
X27300Y689917D01*
X26967Y690500D01*
X26800Y691167D01*
X26967Y691833D01*
X27300Y692417D01*
X27800Y692750D01*
X28300Y692833D01*
X28800Y692750D01*
X29300Y692417D01*
X29633Y691833D01*
X29717Y691167D01*
X29633Y690500D01*
X29300Y689917D01*
X28800Y689583D01*
X28300Y689500D01*
G01X33900D02*
Y694500D01*
G01X38250Y691750D02*
X40917D01*
X40667Y692333D01*
X40250Y692667D01*
X39667Y692833D01*
X39083Y692750D01*
X38583Y692500D01*
X38250Y691917D01*
X38083Y691417D01*
Y690917D01*
X38250Y690417D01*
X38667Y689917D01*
X39167Y689583D01*
X39750Y689500D01*
X40333Y689667D01*
X40917Y690167D01*
G01X43933Y689500D02*
Y692833D01*
G01Y692167D02*
X44350Y692500D01*
X44767Y692750D01*
X45350Y692833D01*
X45767Y692750D01*
X46267Y692500D01*
G01X52200Y689500D02*
Y692833D01*
G01Y692250D02*
X51867Y692583D01*
X51367Y692750D01*
X50783Y692833D01*
X50200Y692667D01*
X49700Y692333D01*
X49367Y691833D01*
X49200Y691167D01*
X49367Y690500D01*
X49700Y690000D01*
X50200Y689667D01*
X50783Y689500D01*
X51367Y689583D01*
X51867Y689833D01*
X52200Y690167D01*
G01X54883Y689500D02*
Y692833D01*
G01Y692000D02*
X55217Y692417D01*
X55717Y692750D01*
X56383Y692833D01*
X56967Y692750D01*
X57467Y692417D01*
X57717Y691833D01*
Y689500D01*
G01X63233Y692417D02*
X62650Y692750D01*
X62150Y692833D01*
X61483Y692667D01*
X60983Y692333D01*
X60650Y691750D01*
X60567Y691167D01*
X60650Y690583D01*
X60983Y690083D01*
X61483Y689667D01*
X62150Y689500D01*
X62733Y689667D01*
X63233Y690000D01*
G01X66250Y691750D02*
X68917D01*
X68667Y692333D01*
X68250Y692667D01*
X67667Y692833D01*
X67083Y692750D01*
X66583Y692500D01*
X66250Y691917D01*
X66083Y691417D01*
Y690917D01*
X66250Y690417D01*
X66667Y689917D01*
X67167Y689583D01*
X67750Y689500D01*
X68333Y689667D01*
X68917Y690167D01*
G01X78700Y694500D02*
Y689500D01*
G01X77533Y692833D02*
X79867D01*
G01X85800Y689500D02*
Y692833D01*
G01Y692250D02*
X85467Y692583D01*
X84967Y692750D01*
X84383Y692833D01*
X83800Y692667D01*
X83300Y692333D01*
X82967Y691833D01*
X82800Y691167D01*
X82967Y690500D01*
X83300Y690000D01*
X83800Y689667D01*
X84383Y689500D01*
X84967Y689583D01*
X85467Y689833D01*
X85800Y690167D01*
G01X88400Y689500D02*
Y694500D01*
G01Y692000D02*
X88817Y692500D01*
X89317Y692750D01*
X89817Y692833D01*
X90567Y692667D01*
X91067Y692333D01*
X91400Y691750D01*
Y691083D01*
X91233Y690417D01*
X90900Y689917D01*
X90317Y689583D01*
X89817Y689500D01*
X89317Y689583D01*
X88817Y689833D01*
X88400Y690250D01*
G01X95500Y689500D02*
Y694500D01*
G01X99850Y691750D02*
X102517D01*
X102267Y692333D01*
X101850Y692667D01*
X101267Y692833D01*
X100683Y692750D01*
X100183Y692500D01*
X99850Y691917D01*
X99683Y691417D01*
Y690917D01*
X99850Y690417D01*
X100267Y689917D01*
X100767Y689583D01*
X101350Y689500D01*
X101933Y689667D01*
X102517Y690167D01*
G01X106700Y689333D02*
X106533Y689417D01*
Y689583D01*
X106700Y689667D01*
X106867Y689583D01*
Y689417D01*
X106700Y689333D01*
G01Y691583D02*
X106533Y691667D01*
Y691833D01*
X106700Y691917D01*
X106867Y691833D01*
Y691667D01*
X106700Y691583D01*
G01X67000Y725433D02*
X66833Y725517D01*
Y725683D01*
X67000Y725767D01*
X67167Y725683D01*
Y725517D01*
X67000Y725433D01*
G01Y734433D02*
X66833Y734517D01*
Y734683D01*
X67000Y734767D01*
X67167Y734683D01*
Y734517D01*
X67000Y734433D01*
G01Y743433D02*
X66833Y743517D01*
Y743683D01*
X67000Y743767D01*
X67167Y743683D01*
Y743517D01*
X67000Y743433D01*
G01Y752433D02*
X66833Y752517D01*
Y752683D01*
X67000Y752767D01*
X67167Y752683D01*
Y752517D01*
X67000Y752433D01*
G01Y761433D02*
X66833Y761517D01*
Y761683D01*
X67000Y761767D01*
X67167Y761683D01*
Y761517D01*
X67000Y761433D01*
G01X71000Y729600D02*
X73000D01*
G01X72000D02*
Y724600D01*
G01X71000D02*
X73000D01*
G01X75933D02*
Y729600D01*
X77933D01*
X78600Y729350D01*
X79100Y728767D01*
X79267Y728100D01*
X79100Y727433D01*
X78683Y726933D01*
X77933Y726683D01*
X75933D01*
G01X85033Y729183D02*
X84533Y729433D01*
X83950Y729600D01*
X83283D01*
X82533Y729350D01*
X81950Y728933D01*
X81533Y728433D01*
X81200Y727600D01*
X81117Y726850D01*
X81283Y726100D01*
X81533Y725600D01*
X82033Y725100D01*
X82617Y724767D01*
X83200Y724600D01*
X83783D01*
X84367Y724767D01*
X84867Y725017D01*
X85283Y725350D01*
G01X87717Y726267D02*
X89883D01*
G01X92733Y729600D02*
Y724600D01*
X96067D01*
G01X98917Y726267D02*
X101083D01*
G01X105600Y724600D02*
Y729600D01*
X104600Y728600D01*
G01Y724600D02*
X106600D01*
G01X111200Y729600D02*
X110533Y729433D01*
X110033Y729017D01*
X109700Y728517D01*
X109450Y727850D01*
X109367Y727100D01*
X109450Y726350D01*
X109700Y725683D01*
X110033Y725183D01*
X110533Y724767D01*
X111200Y724600D01*
X111867Y724767D01*
X112367Y725183D01*
X112700Y725683D01*
X112950Y726350D01*
X113033Y727100D01*
X112950Y727850D01*
X112700Y728517D01*
X112367Y729017D01*
X111867Y729433D01*
X111200Y729600D01*
G01X115383Y725183D02*
X115967Y724767D01*
X116633Y724600D01*
X117300Y724767D01*
X117883Y725267D01*
X118300Y726017D01*
X118467Y726767D01*
Y727683D01*
X118300Y728433D01*
X117883Y729100D01*
X117383Y729433D01*
X116800Y729600D01*
X116133Y729433D01*
X115633Y729100D01*
X115300Y728600D01*
X115133Y727933D01*
X115300Y727350D01*
X115717Y726767D01*
X116217Y726433D01*
X116800Y726350D01*
X117467Y726517D01*
X117967Y726933D01*
X118467Y727683D01*
G01X126250Y725267D02*
X126917Y724850D01*
X127667Y724600D01*
X128333D01*
X129000Y724850D01*
X129500Y725267D01*
X129750Y725850D01*
X129583Y726433D01*
X129167Y726933D01*
X128417Y727267D01*
X127417Y727433D01*
X126833Y727767D01*
X126583Y728350D01*
X126750Y728933D01*
X127167Y729350D01*
X127750Y729600D01*
X128333D01*
X128917Y729433D01*
X129417Y729017D01*
G01X132100Y722933D02*
Y727933D01*
G01Y727183D02*
X132517Y727600D01*
X132933Y727850D01*
X133600Y727933D01*
X134183Y727850D01*
X134767Y727433D01*
X135017Y726850D01*
X135100Y726267D01*
X135017Y725683D01*
X134767Y725100D01*
X134267Y724767D01*
X133600Y724600D01*
X133017Y724683D01*
X132433Y724933D01*
X132100Y725267D01*
G01X137950Y726850D02*
X140617D01*
X140367Y727433D01*
X139950Y727767D01*
X139367Y727933D01*
X138783Y727850D01*
X138283Y727600D01*
X137950Y727017D01*
X137783Y726517D01*
Y726017D01*
X137950Y725517D01*
X138367Y725017D01*
X138867Y724683D01*
X139450Y724600D01*
X140033Y724767D01*
X140617Y725267D01*
G01X146133Y727517D02*
X145550Y727850D01*
X145050Y727933D01*
X144383Y727767D01*
X143883Y727433D01*
X143550Y726850D01*
X143467Y726267D01*
X143550Y725683D01*
X143883Y725183D01*
X144383Y724767D01*
X145050Y724600D01*
X145633Y724767D01*
X146133Y725100D01*
G01X150400Y727933D02*
Y724600D01*
G01Y729267D02*
X150233Y729350D01*
Y729517D01*
X150400Y729600D01*
X150567Y729517D01*
Y729350D01*
X150400Y729267D01*
G01X155500Y724600D02*
Y728850D01*
X155667Y729267D01*
X156000Y729517D01*
X156500Y729600D01*
X157000Y729433D01*
X157250Y729017D01*
G01X156250Y727600D02*
X154583D01*
G01X161600Y727933D02*
Y724600D01*
G01Y729267D02*
X161433Y729350D01*
Y729517D01*
X161600Y729600D01*
X161767Y729517D01*
Y729350D01*
X161600Y729267D01*
G01X168533Y727517D02*
X167950Y727850D01*
X167450Y727933D01*
X166783Y727767D01*
X166283Y727433D01*
X165950Y726850D01*
X165867Y726267D01*
X165950Y725683D01*
X166283Y725183D01*
X166783Y724767D01*
X167450Y724600D01*
X168033Y724767D01*
X168533Y725100D01*
G01X174300Y724600D02*
Y727933D01*
G01Y727350D02*
X173967Y727683D01*
X173467Y727850D01*
X172883Y727933D01*
X172300Y727767D01*
X171800Y727433D01*
X171467Y726933D01*
X171300Y726267D01*
X171467Y725600D01*
X171800Y725100D01*
X172300Y724767D01*
X172883Y724600D01*
X173467Y724683D01*
X173967Y724933D01*
X174300Y725267D01*
G01X178400Y729600D02*
Y724600D01*
G01X177233Y727933D02*
X179567D01*
G01X184000D02*
Y724600D01*
G01Y729267D02*
X183833Y729350D01*
Y729517D01*
X184000Y729600D01*
X184167Y729517D01*
Y729350D01*
X184000Y729267D01*
G01X189600Y724600D02*
X189100Y724683D01*
X188600Y725017D01*
X188267Y725600D01*
X188100Y726267D01*
X188267Y726933D01*
X188600Y727517D01*
X189100Y727850D01*
X189600Y727933D01*
X190100Y727850D01*
X190600Y727517D01*
X190933Y726933D01*
X191017Y726267D01*
X190933Y725600D01*
X190600Y725017D01*
X190100Y724683D01*
X189600Y724600D01*
G01X193783D02*
Y727933D01*
G01Y727100D02*
X194117Y727517D01*
X194617Y727850D01*
X195283Y727933D01*
X195867Y727850D01*
X196367Y727517D01*
X196617Y726933D01*
Y724600D01*
G01X205900D02*
Y728850D01*
X206067Y729267D01*
X206400Y729517D01*
X206900Y729600D01*
X207400Y729433D01*
X207650Y729017D01*
G01X206650Y727600D02*
X204983D01*
G01X212000Y724600D02*
X211500Y724683D01*
X211000Y725017D01*
X210667Y725600D01*
X210500Y726267D01*
X210667Y726933D01*
X211000Y727517D01*
X211500Y727850D01*
X212000Y727933D01*
X212500Y727850D01*
X213000Y727517D01*
X213333Y726933D01*
X213417Y726267D01*
X213333Y725600D01*
X213000Y725017D01*
X212500Y724683D01*
X212000Y724600D01*
G01X216433D02*
Y727933D01*
G01Y727267D02*
X216850Y727600D01*
X217267Y727850D01*
X217850Y727933D01*
X218267Y727850D01*
X218767Y727600D01*
G01X227133Y724600D02*
Y729600D01*
X229217D01*
X229883Y729350D01*
X230300Y729017D01*
X230467Y728350D01*
X230300Y727683D01*
X229800Y727267D01*
X229217Y727017D01*
X227133D01*
G01X229217D02*
X230467Y724600D01*
G01X233150Y726850D02*
X235817D01*
X235567Y727433D01*
X235150Y727767D01*
X234567Y727933D01*
X233983Y727850D01*
X233483Y727600D01*
X233150Y727017D01*
X232983Y726517D01*
Y726017D01*
X233150Y725517D01*
X233567Y725017D01*
X234067Y724683D01*
X234650Y724600D01*
X235233Y724767D01*
X235817Y725267D01*
G01X238750Y725183D02*
X239167Y724850D01*
X239750Y724600D01*
X240250D01*
X240750Y724767D01*
X241083Y725017D01*
X241250Y725350D01*
X241167Y725850D01*
X240833Y726100D01*
X239333Y726600D01*
X239000Y727183D01*
X239167Y727600D01*
X239500Y727850D01*
X240000Y727933D01*
X240500Y727850D01*
X241000Y727600D01*
G01X245600Y727933D02*
Y724600D01*
G01Y729267D02*
X245433Y729350D01*
Y729517D01*
X245600Y729600D01*
X245767Y729517D01*
Y729350D01*
X245600Y729267D01*
G01X249783Y724600D02*
Y727933D01*
G01Y727100D02*
X250117Y727517D01*
X250617Y727850D01*
X251283Y727933D01*
X251867Y727850D01*
X252367Y727517D01*
X252617Y726933D01*
Y724600D01*
G01X261400Y729600D02*
X263400D01*
G01X262400D02*
Y724600D01*
G01X261400D02*
X263400D01*
G01X265500D02*
Y727933D01*
G01Y727017D02*
X265750Y727433D01*
X266167Y727767D01*
X266750Y727933D01*
X267333Y727767D01*
X267750Y727433D01*
X268000Y727017D01*
Y724600D01*
G01Y727017D02*
X268250Y727433D01*
X268667Y727767D01*
X269250Y727933D01*
X269833Y727767D01*
X270250Y727433D01*
X270500Y726933D01*
Y724600D01*
G01X272100Y722933D02*
Y727933D01*
G01Y727183D02*
X272517Y727600D01*
X272933Y727850D01*
X273600Y727933D01*
X274183Y727850D01*
X274767Y727433D01*
X275017Y726850D01*
X275100Y726267D01*
X275017Y725683D01*
X274767Y725100D01*
X274267Y724767D01*
X273600Y724600D01*
X273017Y724683D01*
X272433Y724933D01*
X272100Y725267D01*
G01X278033Y724600D02*
Y727933D01*
G01Y727267D02*
X278450Y727600D01*
X278867Y727850D01*
X279450Y727933D01*
X279867Y727850D01*
X280367Y727600D01*
G01X283550Y726850D02*
X286217D01*
X285967Y727433D01*
X285550Y727767D01*
X284967Y727933D01*
X284383Y727850D01*
X283883Y727600D01*
X283550Y727017D01*
X283383Y726517D01*
Y726017D01*
X283550Y725517D01*
X283967Y725017D01*
X284467Y724683D01*
X285050Y724600D01*
X285633Y724767D01*
X286217Y725267D01*
G01X289233Y723350D02*
X289817Y723017D01*
X290483Y722933D01*
X291067Y723017D01*
X291567Y723433D01*
X291900Y724017D01*
Y727933D01*
G01Y727267D02*
X291567Y727600D01*
X291067Y727850D01*
X290483Y727933D01*
X289817Y727767D01*
X289400Y727433D01*
X289067Y726850D01*
X288900Y726267D01*
X288983Y725767D01*
X289317Y725183D01*
X289817Y724767D01*
X290483Y724600D01*
X290983Y724683D01*
X291567Y725017D01*
X291900Y725350D01*
G01X294583Y724600D02*
Y727933D01*
G01Y727100D02*
X294917Y727517D01*
X295417Y727850D01*
X296083Y727933D01*
X296667Y727850D01*
X297167Y727517D01*
X297417Y726933D01*
Y724600D01*
G01X303100D02*
Y727933D01*
G01Y727350D02*
X302767Y727683D01*
X302267Y727850D01*
X301683Y727933D01*
X301100Y727767D01*
X300600Y727433D01*
X300267Y726933D01*
X300100Y726267D01*
X300267Y725600D01*
X300600Y725100D01*
X301100Y724767D01*
X301683Y724600D01*
X302267Y724683D01*
X302767Y724933D01*
X303100Y725267D01*
G01X307200Y729600D02*
Y724600D01*
G01X306033Y727933D02*
X308367D01*
G01X311550Y726850D02*
X314217D01*
X313967Y727433D01*
X313550Y727767D01*
X312967Y727933D01*
X312383Y727850D01*
X311883Y727600D01*
X311550Y727017D01*
X311383Y726517D01*
Y726017D01*
X311550Y725517D01*
X311967Y725017D01*
X312467Y724683D01*
X313050Y724600D01*
X313633Y724767D01*
X314217Y725267D01*
G01X319900Y729600D02*
Y724600D01*
G01Y725350D02*
X319567Y724933D01*
X319067Y724683D01*
X318483Y724600D01*
X317817Y724767D01*
X317317Y725183D01*
X316983Y725683D01*
X316900Y726267D01*
X316983Y726850D01*
X317317Y727350D01*
X317817Y727767D01*
X318483Y727933D01*
X319067Y727850D01*
X319483Y727683D01*
X319900Y727350D01*
G01X328017Y724600D02*
Y729600D01*
X331183D01*
G01X330017Y727183D02*
X328017D01*
G01X336700Y724600D02*
Y727933D01*
G01Y727350D02*
X336367Y727683D01*
X335867Y727850D01*
X335283Y727933D01*
X334700Y727767D01*
X334200Y727433D01*
X333867Y726933D01*
X333700Y726267D01*
X333867Y725600D01*
X334200Y725100D01*
X334700Y724767D01*
X335283Y724600D01*
X335867Y724683D01*
X336367Y724933D01*
X336700Y725267D01*
G01X339300Y724600D02*
Y729600D01*
G01Y727100D02*
X339717Y727600D01*
X340217Y727850D01*
X340717Y727933D01*
X341467Y727767D01*
X341967Y727433D01*
X342300Y726850D01*
Y726183D01*
X342133Y725517D01*
X341800Y725017D01*
X341217Y724683D01*
X340717Y724600D01*
X340217Y724683D01*
X339717Y724933D01*
X339300Y725350D01*
G01X345233Y724600D02*
Y727933D01*
G01Y727267D02*
X345650Y727600D01*
X346067Y727850D01*
X346650Y727933D01*
X347067Y727850D01*
X347567Y727600D01*
G01X352000Y727933D02*
Y724600D01*
G01Y729267D02*
X351833Y729350D01*
Y729517D01*
X352000Y729600D01*
X352167Y729517D01*
Y729350D01*
X352000Y729267D01*
G01X358933Y727517D02*
X358350Y727850D01*
X357850Y727933D01*
X357183Y727767D01*
X356683Y727433D01*
X356350Y726850D01*
X356267Y726267D01*
X356350Y725683D01*
X356683Y725183D01*
X357183Y724767D01*
X357850Y724600D01*
X358433Y724767D01*
X358933Y725100D01*
G01X362783Y722933D02*
X361950Y723767D01*
X361533Y724600D01*
Y727933D01*
X361950Y728767D01*
X362783Y729600D01*
G01X367133Y724600D02*
Y729600D01*
X369133D01*
X369800Y729350D01*
X370300Y728767D01*
X370467Y728100D01*
X370300Y727433D01*
X369883Y726933D01*
X369133Y726683D01*
X367133D01*
G01X373233Y724600D02*
Y727933D01*
G01Y727267D02*
X373650Y727600D01*
X374067Y727850D01*
X374650Y727933D01*
X375067Y727850D01*
X375567Y727600D01*
G01X378750Y726850D02*
X381417D01*
X381167Y727433D01*
X380750Y727767D01*
X380167Y727933D01*
X379583Y727850D01*
X379083Y727600D01*
X378750Y727017D01*
X378583Y726517D01*
Y726017D01*
X378750Y725517D01*
X379167Y725017D01*
X379667Y724683D01*
X380250Y724600D01*
X380833Y724767D01*
X381417Y725267D01*
G01X384100Y722933D02*
Y727933D01*
G01Y727183D02*
X384517Y727600D01*
X384933Y727850D01*
X385600Y727933D01*
X386183Y727850D01*
X386767Y727433D01*
X387017Y726850D01*
X387100Y726267D01*
X387017Y725683D01*
X386767Y725100D01*
X386267Y724767D01*
X385600Y724600D01*
X385017Y724683D01*
X384433Y724933D01*
X384100Y725267D01*
G01X390033Y724600D02*
Y727933D01*
G01Y727267D02*
X390450Y727600D01*
X390867Y727850D01*
X391450Y727933D01*
X391867Y727850D01*
X392367Y727600D01*
G01X395550Y726850D02*
X398217D01*
X397967Y727433D01*
X397550Y727767D01*
X396967Y727933D01*
X396383Y727850D01*
X395883Y727600D01*
X395550Y727017D01*
X395383Y726517D01*
Y726017D01*
X395550Y725517D01*
X395967Y725017D01*
X396467Y724683D01*
X397050Y724600D01*
X397633Y724767D01*
X398217Y725267D01*
G01X401233Y723350D02*
X401817Y723017D01*
X402483Y722933D01*
X403067Y723017D01*
X403567Y723433D01*
X403900Y724017D01*
Y727933D01*
G01Y727267D02*
X403567Y727600D01*
X403067Y727850D01*
X402483Y727933D01*
X401817Y727767D01*
X401400Y727433D01*
X401067Y726850D01*
X400900Y726267D01*
X400983Y725767D01*
X401317Y725183D01*
X401817Y724767D01*
X402483Y724600D01*
X402983Y724683D01*
X403567Y725017D01*
X403900Y725350D01*
G01X408417Y722933D02*
X409250Y723767D01*
X409667Y724600D01*
Y727933D01*
X409250Y728767D01*
X408417Y729600D01*
G01X418700Y724600D02*
Y728850D01*
X418867Y729267D01*
X419200Y729517D01*
X419700Y729600D01*
X420200Y729433D01*
X420450Y729017D01*
G01X419450Y727600D02*
X417783D01*
G01X424800Y724600D02*
X424300Y724683D01*
X423800Y725017D01*
X423467Y725600D01*
X423300Y726267D01*
X423467Y726933D01*
X423800Y727517D01*
X424300Y727850D01*
X424800Y727933D01*
X425300Y727850D01*
X425800Y727517D01*
X426133Y726933D01*
X426217Y726267D01*
X426133Y725600D01*
X425800Y725017D01*
X425300Y724683D01*
X424800Y724600D01*
G01X429233D02*
Y727933D01*
G01Y727267D02*
X429650Y727600D01*
X430067Y727850D01*
X430650Y727933D01*
X431067Y727850D01*
X431567Y727600D01*
G01X439433Y724600D02*
Y729600D01*
X441600Y725433D01*
X443767Y729600D01*
Y724600D01*
G01X445783Y727933D02*
Y725600D01*
X446117Y725017D01*
X446617Y724683D01*
X447200Y724600D01*
X447783Y724683D01*
X448283Y725017D01*
X448617Y725600D01*
G01Y724600D02*
Y727933D01*
G01X452800Y724600D02*
Y729600D01*
G01X458400D02*
Y724600D01*
G01X457233Y727933D02*
X459567D01*
G01X464000D02*
Y724600D01*
G01Y729267D02*
X463833Y729350D01*
Y729517D01*
X464000Y729600D01*
X464167Y729517D01*
Y729350D01*
X464000Y729267D01*
G01X469600Y724600D02*
Y729600D01*
G01X476700Y724600D02*
Y727933D01*
G01Y727350D02*
X476367Y727683D01*
X475867Y727850D01*
X475283Y727933D01*
X474700Y727767D01*
X474200Y727433D01*
X473867Y726933D01*
X473700Y726267D01*
X473867Y725600D01*
X474200Y725100D01*
X474700Y724767D01*
X475283Y724600D01*
X475867Y724683D01*
X476367Y724933D01*
X476700Y725267D01*
G01X479050Y723100D02*
X479550Y722933D01*
X480217Y723100D01*
X480633Y723433D01*
X480967Y723850D01*
X481467Y725183D01*
X482550Y727933D01*
G01X479883D02*
X481467Y725183D01*
G01X485150Y726850D02*
X487817D01*
X487567Y727433D01*
X487150Y727767D01*
X486567Y727933D01*
X485983Y727850D01*
X485483Y727600D01*
X485150Y727017D01*
X484983Y726517D01*
Y726017D01*
X485150Y725517D01*
X485567Y725017D01*
X486067Y724683D01*
X486650Y724600D01*
X487233Y724767D01*
X487817Y725267D01*
G01X490833Y724600D02*
Y727933D01*
G01Y727267D02*
X491250Y727600D01*
X491667Y727850D01*
X492250Y727933D01*
X492667Y727850D01*
X493167Y727600D01*
G01X501533Y724600D02*
Y729600D01*
X503533D01*
X504200Y729350D01*
X504700Y728767D01*
X504867Y728100D01*
X504700Y727433D01*
X504283Y726933D01*
X503533Y726683D01*
X501533D01*
G01X507633Y724600D02*
Y727933D01*
G01Y727267D02*
X508050Y727600D01*
X508467Y727850D01*
X509050Y727933D01*
X509467Y727850D01*
X509967Y727600D01*
G01X514400Y727933D02*
Y724600D01*
G01Y729267D02*
X514233Y729350D01*
Y729517D01*
X514400Y729600D01*
X514567Y729517D01*
Y729350D01*
X514400Y729267D01*
G01X518583Y724600D02*
Y727933D01*
G01Y727100D02*
X518917Y727517D01*
X519417Y727850D01*
X520083Y727933D01*
X520667Y727850D01*
X521167Y727517D01*
X521417Y726933D01*
Y724600D01*
G01X525600Y729600D02*
Y724600D01*
G01X524433Y727933D02*
X526767D01*
G01X529950Y726850D02*
X532617D01*
X532367Y727433D01*
X531950Y727767D01*
X531367Y727933D01*
X530783Y727850D01*
X530283Y727600D01*
X529950Y727017D01*
X529783Y726517D01*
Y726017D01*
X529950Y725517D01*
X530367Y725017D01*
X530867Y724683D01*
X531450Y724600D01*
X532033Y724767D01*
X532617Y725267D01*
G01X538300Y729600D02*
Y724600D01*
G01Y725350D02*
X537967Y724933D01*
X537467Y724683D01*
X536883Y724600D01*
X536217Y724767D01*
X535717Y725183D01*
X535383Y725683D01*
X535300Y726267D01*
X535383Y726850D01*
X535717Y727350D01*
X536217Y727767D01*
X536883Y727933D01*
X537467Y727850D01*
X537883Y727683D01*
X538300Y727350D01*
G01X548667Y727267D02*
X549000Y727517D01*
X549250Y727933D01*
X549417Y728517D01*
X549250Y729017D01*
X548917Y729350D01*
X548333Y729600D01*
X546083D01*
Y724600D01*
X548833D01*
X549417Y724933D01*
X549750Y725433D01*
X549917Y726017D01*
X549750Y726600D01*
X549250Y727100D01*
X548667Y727267D01*
X546083D01*
G01X553600Y724600D02*
X553100Y724683D01*
X552600Y725017D01*
X552267Y725600D01*
X552100Y726267D01*
X552267Y726933D01*
X552600Y727517D01*
X553100Y727850D01*
X553600Y727933D01*
X554100Y727850D01*
X554600Y727517D01*
X554933Y726933D01*
X555017Y726267D01*
X554933Y725600D01*
X554600Y725017D01*
X554100Y724683D01*
X553600Y724600D01*
G01X560700D02*
Y727933D01*
G01Y727350D02*
X560367Y727683D01*
X559867Y727850D01*
X559283Y727933D01*
X558700Y727767D01*
X558200Y727433D01*
X557867Y726933D01*
X557700Y726267D01*
X557867Y725600D01*
X558200Y725100D01*
X558700Y724767D01*
X559283Y724600D01*
X559867Y724683D01*
X560367Y724933D01*
X560700Y725267D01*
G01X563633Y724600D02*
Y727933D01*
G01Y727267D02*
X564050Y727600D01*
X564467Y727850D01*
X565050Y727933D01*
X565467Y727850D01*
X565967Y727600D01*
G01X571900Y729600D02*
Y724600D01*
G01Y725350D02*
X571567Y724933D01*
X571067Y724683D01*
X570483Y724600D01*
X569817Y724767D01*
X569317Y725183D01*
X568983Y725683D01*
X568900Y726267D01*
X568983Y726850D01*
X569317Y727350D01*
X569817Y727767D01*
X570483Y727933D01*
X571067Y727850D01*
X571483Y727683D01*
X571900Y727350D01*
G01X574750Y725183D02*
X575167Y724850D01*
X575750Y724600D01*
X576250D01*
X576750Y724767D01*
X577083Y725017D01*
X577250Y725350D01*
X577167Y725850D01*
X576833Y726100D01*
X575333Y726600D01*
X575000Y727183D01*
X575167Y727600D01*
X575500Y727850D01*
X576000Y727933D01*
X576500Y727850D01*
X577000Y727600D01*
G01X71000Y738600D02*
X73000D01*
G01X72000D02*
Y733600D01*
G01X71000D02*
X73000D01*
G01X75933D02*
Y738600D01*
X77933D01*
X78600Y738350D01*
X79100Y737767D01*
X79267Y737100D01*
X79100Y736433D01*
X78683Y735933D01*
X77933Y735683D01*
X75933D01*
G01X85033Y738183D02*
X84533Y738433D01*
X83950Y738600D01*
X83283D01*
X82533Y738350D01*
X81950Y737933D01*
X81533Y737433D01*
X81200Y736600D01*
X81117Y735850D01*
X81283Y735100D01*
X81533Y734600D01*
X82033Y734100D01*
X82617Y733767D01*
X83200Y733600D01*
X83783D01*
X84367Y733767D01*
X84867Y734017D01*
X85283Y734350D01*
G01X87717Y735267D02*
X89883D01*
G01X92233Y733600D02*
Y738600D01*
X94400Y734433D01*
X96567Y738600D01*
Y733600D01*
G01X98417D02*
Y738600D01*
X101583D01*
G01X100417Y736183D02*
X98417D01*
G01X104517Y735267D02*
X106683D01*
G01X111200Y733600D02*
Y738600D01*
X110200Y737600D01*
G01Y733600D02*
X112200D01*
G01X114967Y734350D02*
X115467Y733933D01*
X116050Y733683D01*
X116800Y733600D01*
X117550Y733767D01*
X118133Y734100D01*
X118550Y734683D01*
X118633Y735350D01*
X118467Y736017D01*
X118050Y736433D01*
X117467Y736767D01*
X116883Y736850D01*
X116300Y736767D01*
X115550Y736433D01*
X115800Y738600D01*
X118050D01*
G01X122400D02*
X121733Y738433D01*
X121233Y738017D01*
X120900Y737517D01*
X120650Y736850D01*
X120567Y736100D01*
X120650Y735350D01*
X120900Y734683D01*
X121233Y734183D01*
X121733Y733767D01*
X122400Y733600D01*
X123067Y733767D01*
X123567Y734183D01*
X123900Y734683D01*
X124150Y735350D01*
X124233Y736100D01*
X124150Y736850D01*
X123900Y737517D01*
X123567Y738017D01*
X123067Y738433D01*
X122400Y738600D01*
G01X131433Y733600D02*
Y738600D01*
X133600Y734433D01*
X135767Y738600D01*
Y733600D01*
G01X137950Y735850D02*
X140617D01*
X140367Y736433D01*
X139950Y736767D01*
X139367Y736933D01*
X138783Y736850D01*
X138283Y736600D01*
X137950Y736017D01*
X137783Y735517D01*
Y735017D01*
X137950Y734517D01*
X138367Y734017D01*
X138867Y733683D01*
X139450Y733600D01*
X140033Y733767D01*
X140617Y734267D01*
G01X144800Y738600D02*
Y733600D01*
G01X143633Y736933D02*
X145967D01*
G01X151900Y733600D02*
Y736933D01*
G01Y736350D02*
X151567Y736683D01*
X151067Y736850D01*
X150483Y736933D01*
X149900Y736767D01*
X149400Y736433D01*
X149067Y735933D01*
X148900Y735267D01*
X149067Y734600D01*
X149400Y734100D01*
X149900Y733767D01*
X150483Y733600D01*
X151067Y733683D01*
X151567Y733933D01*
X151900Y734267D01*
G01X156000Y733600D02*
Y738600D01*
G01X165617Y733600D02*
Y738600D01*
X168783D01*
G01X167617Y736183D02*
X165617D01*
G01X172800Y733600D02*
X172300Y733683D01*
X171800Y734017D01*
X171467Y734600D01*
X171300Y735267D01*
X171467Y735933D01*
X171800Y736517D01*
X172300Y736850D01*
X172800Y736933D01*
X173300Y736850D01*
X173800Y736517D01*
X174133Y735933D01*
X174217Y735267D01*
X174133Y734600D01*
X173800Y734017D01*
X173300Y733683D01*
X172800Y733600D01*
G01X178400Y736933D02*
Y733600D01*
G01Y738267D02*
X178233Y738350D01*
Y738517D01*
X178400Y738600D01*
X178567Y738517D01*
Y738350D01*
X178400Y738267D01*
G01X184000Y733600D02*
Y738600D01*
G01X194700Y733600D02*
Y737850D01*
X194867Y738267D01*
X195200Y738517D01*
X195700Y738600D01*
X196200Y738433D01*
X196450Y738017D01*
G01X195450Y736600D02*
X193783D01*
G01X200800Y733600D02*
X200300Y733683D01*
X199800Y734017D01*
X199467Y734600D01*
X199300Y735267D01*
X199467Y735933D01*
X199800Y736517D01*
X200300Y736850D01*
X200800Y736933D01*
X201300Y736850D01*
X201800Y736517D01*
X202133Y735933D01*
X202217Y735267D01*
X202133Y734600D01*
X201800Y734017D01*
X201300Y733683D01*
X200800Y733600D01*
G01X205233D02*
Y736933D01*
G01Y736267D02*
X205650Y736600D01*
X206067Y736850D01*
X206650Y736933D01*
X207067Y736850D01*
X207567Y736600D01*
G01X215933Y733600D02*
Y738600D01*
X217933D01*
X218600Y738350D01*
X219100Y737767D01*
X219267Y737100D01*
X219100Y736433D01*
X218683Y735933D01*
X217933Y735683D01*
X215933D01*
G01X222033Y733600D02*
Y736933D01*
G01Y736267D02*
X222450Y736600D01*
X222867Y736850D01*
X223450Y736933D01*
X223867Y736850D01*
X224367Y736600D01*
G01X228800Y736933D02*
Y733600D01*
G01Y738267D02*
X228633Y738350D01*
Y738517D01*
X228800Y738600D01*
X228967Y738517D01*
Y738350D01*
X228800Y738267D01*
G01X232983Y733600D02*
Y736933D01*
G01Y736100D02*
X233317Y736517D01*
X233817Y736850D01*
X234483Y736933D01*
X235067Y736850D01*
X235567Y736517D01*
X235817Y735933D01*
Y733600D01*
G01X240000Y738600D02*
Y733600D01*
G01X238833Y736933D02*
X241167D01*
G01X244350Y735850D02*
X247017D01*
X246767Y736433D01*
X246350Y736767D01*
X245767Y736933D01*
X245183Y736850D01*
X244683Y736600D01*
X244350Y736017D01*
X244183Y735517D01*
Y735017D01*
X244350Y734517D01*
X244767Y734017D01*
X245267Y733683D01*
X245850Y733600D01*
X246433Y733767D01*
X247017Y734267D01*
G01X252700Y738600D02*
Y733600D01*
G01Y734350D02*
X252367Y733933D01*
X251867Y733683D01*
X251283Y733600D01*
X250617Y733767D01*
X250117Y734183D01*
X249783Y734683D01*
X249700Y735267D01*
X249783Y735850D01*
X250117Y736350D01*
X250617Y736767D01*
X251283Y736933D01*
X251867Y736850D01*
X252283Y736683D01*
X252700Y736350D01*
G01X259900Y738600D02*
X261067Y733600D01*
X262400Y738600D01*
X263733Y733600D01*
X264900Y738600D01*
G01X268000Y736933D02*
Y733600D01*
G01Y738267D02*
X267833Y738350D01*
Y738517D01*
X268000Y738600D01*
X268167Y738517D01*
Y738350D01*
X268000Y738267D01*
G01X272433Y733600D02*
Y736933D01*
G01Y736267D02*
X272850Y736600D01*
X273267Y736850D01*
X273850Y736933D01*
X274267Y736850D01*
X274767Y736600D01*
G01X279200Y736933D02*
Y733600D01*
G01Y738267D02*
X279033Y738350D01*
Y738517D01*
X279200Y738600D01*
X279367Y738517D01*
Y738350D01*
X279200Y738267D01*
G01X283383Y733600D02*
Y736933D01*
G01Y736100D02*
X283717Y736517D01*
X284217Y736850D01*
X284883Y736933D01*
X285467Y736850D01*
X285967Y736517D01*
X286217Y735933D01*
Y733600D01*
G01X289233Y732350D02*
X289817Y732017D01*
X290483Y731933D01*
X291067Y732017D01*
X291567Y732433D01*
X291900Y733017D01*
Y736933D01*
G01Y736267D02*
X291567Y736600D01*
X291067Y736850D01*
X290483Y736933D01*
X289817Y736767D01*
X289400Y736433D01*
X289067Y735850D01*
X288900Y735267D01*
X288983Y734767D01*
X289317Y734183D01*
X289817Y733767D01*
X290483Y733600D01*
X290983Y733683D01*
X291567Y734017D01*
X291900Y734350D01*
G01X299517Y733600D02*
X301600Y738600D01*
X303683Y733600D01*
G01X302933Y735350D02*
X300267D01*
G01X305700Y731933D02*
Y736933D01*
G01Y736183D02*
X306117Y736600D01*
X306533Y736850D01*
X307200Y736933D01*
X307783Y736850D01*
X308367Y736433D01*
X308617Y735850D01*
X308700Y735267D01*
X308617Y734683D01*
X308367Y734100D01*
X307867Y733767D01*
X307200Y733600D01*
X306617Y733683D01*
X306033Y733933D01*
X305700Y734267D01*
G01X311300Y731933D02*
Y736933D01*
G01Y736183D02*
X311717Y736600D01*
X312133Y736850D01*
X312800Y736933D01*
X313383Y736850D01*
X313967Y736433D01*
X314217Y735850D01*
X314300Y735267D01*
X314217Y734683D01*
X313967Y734100D01*
X313467Y733767D01*
X312800Y733600D01*
X312217Y733683D01*
X311633Y733933D01*
X311300Y734267D01*
G01X318400Y733600D02*
Y738600D01*
G01X324000Y736933D02*
Y733600D01*
G01Y738267D02*
X323833Y738350D01*
Y738517D01*
X324000Y738600D01*
X324167Y738517D01*
Y738350D01*
X324000Y738267D01*
G01X330933Y736517D02*
X330350Y736850D01*
X329850Y736933D01*
X329183Y736767D01*
X328683Y736433D01*
X328350Y735850D01*
X328267Y735267D01*
X328350Y734683D01*
X328683Y734183D01*
X329183Y733767D01*
X329850Y733600D01*
X330433Y733767D01*
X330933Y734100D01*
G01X336700Y733600D02*
Y736933D01*
G01Y736350D02*
X336367Y736683D01*
X335867Y736850D01*
X335283Y736933D01*
X334700Y736767D01*
X334200Y736433D01*
X333867Y735933D01*
X333700Y735267D01*
X333867Y734600D01*
X334200Y734100D01*
X334700Y733767D01*
X335283Y733600D01*
X335867Y733683D01*
X336367Y733933D01*
X336700Y734267D01*
G01X340800Y738600D02*
Y733600D01*
G01X339633Y736933D02*
X341967D01*
G01X346400D02*
Y733600D01*
G01Y738267D02*
X346233Y738350D01*
Y738517D01*
X346400Y738600D01*
X346567Y738517D01*
Y738350D01*
X346400Y738267D01*
G01X352000Y733600D02*
X351500Y733683D01*
X351000Y734017D01*
X350667Y734600D01*
X350500Y735267D01*
X350667Y735933D01*
X351000Y736517D01*
X351500Y736850D01*
X352000Y736933D01*
X352500Y736850D01*
X353000Y736517D01*
X353333Y735933D01*
X353417Y735267D01*
X353333Y734600D01*
X353000Y734017D01*
X352500Y733683D01*
X352000Y733600D01*
G01X356183D02*
Y736933D01*
G01Y736100D02*
X356517Y736517D01*
X357017Y736850D01*
X357683Y736933D01*
X358267Y736850D01*
X358767Y736517D01*
X359017Y735933D01*
Y733600D01*
G01X361950Y734183D02*
X362367Y733850D01*
X362950Y733600D01*
X363450D01*
X363950Y733767D01*
X364283Y734017D01*
X364450Y734350D01*
X364367Y734850D01*
X364033Y735100D01*
X362533Y735600D01*
X362200Y736183D01*
X362367Y736600D01*
X362700Y736850D01*
X363200Y736933D01*
X363700Y736850D01*
X364200Y736600D01*
G01X71000Y747600D02*
X73000D01*
G01X72000D02*
Y742600D01*
G01X71000D02*
X73000D01*
G01X75933D02*
Y747600D01*
X77933D01*
X78600Y747350D01*
X79100Y746767D01*
X79267Y746100D01*
X79100Y745433D01*
X78683Y744933D01*
X77933Y744683D01*
X75933D01*
G01X85033Y747183D02*
X84533Y747433D01*
X83950Y747600D01*
X83283D01*
X82533Y747350D01*
X81950Y746933D01*
X81533Y746433D01*
X81200Y745600D01*
X81117Y744850D01*
X81283Y744100D01*
X81533Y743600D01*
X82033Y743100D01*
X82617Y742767D01*
X83200Y742600D01*
X83783D01*
X84367Y742767D01*
X84867Y743017D01*
X85283Y743350D01*
G01X87717Y744267D02*
X89883D01*
G01X95400Y742600D02*
Y747600D01*
X92317Y744017D01*
X96483D01*
G01X100000Y742600D02*
Y747600D01*
X99000Y746600D01*
G01Y742600D02*
X101000D01*
G01X105600Y747600D02*
X104933Y747433D01*
X104433Y747017D01*
X104100Y746517D01*
X103850Y745850D01*
X103767Y745100D01*
X103850Y744350D01*
X104100Y743683D01*
X104433Y743183D01*
X104933Y742767D01*
X105600Y742600D01*
X106267Y742767D01*
X106767Y743183D01*
X107100Y743683D01*
X107350Y744350D01*
X107433Y745100D01*
X107350Y745850D01*
X107100Y746517D01*
X106767Y747017D01*
X106267Y747433D01*
X105600Y747600D01*
G01X111200Y742600D02*
Y747600D01*
X110200Y746600D01*
G01Y742600D02*
X112200D01*
G01X120650Y743267D02*
X121317Y742850D01*
X122067Y742600D01*
X122733D01*
X123400Y742850D01*
X123900Y743267D01*
X124150Y743850D01*
X123983Y744433D01*
X123567Y744933D01*
X122817Y745267D01*
X121817Y745433D01*
X121233Y745767D01*
X120983Y746350D01*
X121150Y746933D01*
X121567Y747350D01*
X122150Y747600D01*
X122733D01*
X123317Y747433D01*
X123817Y747017D01*
G01X126500Y740933D02*
Y745933D01*
G01Y745183D02*
X126917Y745600D01*
X127333Y745850D01*
X128000Y745933D01*
X128583Y745850D01*
X129167Y745433D01*
X129417Y744850D01*
X129500Y744267D01*
X129417Y743683D01*
X129167Y743100D01*
X128667Y742767D01*
X128000Y742600D01*
X127417Y742683D01*
X126833Y742933D01*
X126500Y743267D01*
G01X132350Y744850D02*
X135017D01*
X134767Y745433D01*
X134350Y745767D01*
X133767Y745933D01*
X133183Y745850D01*
X132683Y745600D01*
X132350Y745017D01*
X132183Y744517D01*
Y744017D01*
X132350Y743517D01*
X132767Y743017D01*
X133267Y742683D01*
X133850Y742600D01*
X134433Y742767D01*
X135017Y743267D01*
G01X140533Y745517D02*
X139950Y745850D01*
X139450Y745933D01*
X138783Y745767D01*
X138283Y745433D01*
X137950Y744850D01*
X137867Y744267D01*
X137950Y743683D01*
X138283Y743183D01*
X138783Y742767D01*
X139450Y742600D01*
X140033Y742767D01*
X140533Y743100D01*
G01X144800Y745933D02*
Y742600D01*
G01Y747267D02*
X144633Y747350D01*
Y747517D01*
X144800Y747600D01*
X144967Y747517D01*
Y747350D01*
X144800Y747267D01*
G01X149900Y742600D02*
Y746850D01*
X150067Y747267D01*
X150400Y747517D01*
X150900Y747600D01*
X151400Y747433D01*
X151650Y747017D01*
G01X150650Y745600D02*
X148983D01*
G01X156000Y745933D02*
Y742600D01*
G01Y747267D02*
X155833Y747350D01*
Y747517D01*
X156000Y747600D01*
X156167Y747517D01*
Y747350D01*
X156000Y747267D01*
G01X162933Y745517D02*
X162350Y745850D01*
X161850Y745933D01*
X161183Y745767D01*
X160683Y745433D01*
X160350Y744850D01*
X160267Y744267D01*
X160350Y743683D01*
X160683Y743183D01*
X161183Y742767D01*
X161850Y742600D01*
X162433Y742767D01*
X162933Y743100D01*
G01X168700Y742600D02*
Y745933D01*
G01Y745350D02*
X168367Y745683D01*
X167867Y745850D01*
X167283Y745933D01*
X166700Y745767D01*
X166200Y745433D01*
X165867Y744933D01*
X165700Y744267D01*
X165867Y743600D01*
X166200Y743100D01*
X166700Y742767D01*
X167283Y742600D01*
X167867Y742683D01*
X168367Y742933D01*
X168700Y743267D01*
G01X172800Y747600D02*
Y742600D01*
G01X171633Y745933D02*
X173967D01*
G01X178400D02*
Y742600D01*
G01Y747267D02*
X178233Y747350D01*
Y747517D01*
X178400Y747600D01*
X178567Y747517D01*
Y747350D01*
X178400Y747267D01*
G01X184000Y742600D02*
X183500Y742683D01*
X183000Y743017D01*
X182667Y743600D01*
X182500Y744267D01*
X182667Y744933D01*
X183000Y745517D01*
X183500Y745850D01*
X184000Y745933D01*
X184500Y745850D01*
X185000Y745517D01*
X185333Y744933D01*
X185417Y744267D01*
X185333Y743600D01*
X185000Y743017D01*
X184500Y742683D01*
X184000Y742600D01*
G01X188183D02*
Y745933D01*
G01Y745100D02*
X188517Y745517D01*
X189017Y745850D01*
X189683Y745933D01*
X190267Y745850D01*
X190767Y745517D01*
X191017Y744933D01*
Y742600D01*
G01X200300D02*
Y746850D01*
X200467Y747267D01*
X200800Y747517D01*
X201300Y747600D01*
X201800Y747433D01*
X202050Y747017D01*
G01X201050Y745600D02*
X199383D01*
G01X206400Y742600D02*
X205900Y742683D01*
X205400Y743017D01*
X205067Y743600D01*
X204900Y744267D01*
X205067Y744933D01*
X205400Y745517D01*
X205900Y745850D01*
X206400Y745933D01*
X206900Y745850D01*
X207400Y745517D01*
X207733Y744933D01*
X207817Y744267D01*
X207733Y743600D01*
X207400Y743017D01*
X206900Y742683D01*
X206400Y742600D01*
G01X210833D02*
Y745933D01*
G01Y745267D02*
X211250Y745600D01*
X211667Y745850D01*
X212250Y745933D01*
X212667Y745850D01*
X213167Y745600D01*
G01X223867Y745267D02*
X224200Y745517D01*
X224450Y745933D01*
X224617Y746517D01*
X224450Y747017D01*
X224117Y747350D01*
X223533Y747600D01*
X221283D01*
Y742600D01*
X224033D01*
X224617Y742933D01*
X224950Y743433D01*
X225117Y744017D01*
X224950Y744600D01*
X224450Y745100D01*
X223867Y745267D01*
X221283D01*
G01X230300Y742600D02*
Y745933D01*
G01Y745350D02*
X229967Y745683D01*
X229467Y745850D01*
X228883Y745933D01*
X228300Y745767D01*
X227800Y745433D01*
X227467Y744933D01*
X227300Y744267D01*
X227467Y743600D01*
X227800Y743100D01*
X228300Y742767D01*
X228883Y742600D01*
X229467Y742683D01*
X229967Y742933D01*
X230300Y743267D01*
G01X233150Y743183D02*
X233567Y742850D01*
X234150Y742600D01*
X234650D01*
X235150Y742767D01*
X235483Y743017D01*
X235650Y743350D01*
X235567Y743850D01*
X235233Y744100D01*
X233733Y744600D01*
X233400Y745183D01*
X233567Y745600D01*
X233900Y745850D01*
X234400Y745933D01*
X234900Y745850D01*
X235400Y745600D01*
G01X238750Y744850D02*
X241417D01*
X241167Y745433D01*
X240750Y745767D01*
X240167Y745933D01*
X239583Y745850D01*
X239083Y745600D01*
X238750Y745017D01*
X238583Y744517D01*
Y744017D01*
X238750Y743517D01*
X239167Y743017D01*
X239667Y742683D01*
X240250Y742600D01*
X240833Y742767D01*
X241417Y743267D01*
G01X249033Y742600D02*
Y747600D01*
X251200Y743433D01*
X253367Y747600D01*
Y742600D01*
G01X258300D02*
Y745933D01*
G01Y745350D02*
X257967Y745683D01*
X257467Y745850D01*
X256883Y745933D01*
X256300Y745767D01*
X255800Y745433D01*
X255467Y744933D01*
X255300Y744267D01*
X255467Y743600D01*
X255800Y743100D01*
X256300Y742767D01*
X256883Y742600D01*
X257467Y742683D01*
X257967Y742933D01*
X258300Y743267D01*
G01X262400Y747600D02*
Y742600D01*
G01X261233Y745933D02*
X263567D01*
G01X266750Y744850D02*
X269417D01*
X269167Y745433D01*
X268750Y745767D01*
X268167Y745933D01*
X267583Y745850D01*
X267083Y745600D01*
X266750Y745017D01*
X266583Y744517D01*
Y744017D01*
X266750Y743517D01*
X267167Y743017D01*
X267667Y742683D01*
X268250Y742600D01*
X268833Y742767D01*
X269417Y743267D01*
G01X272433Y742600D02*
Y745933D01*
G01Y745267D02*
X272850Y745600D01*
X273267Y745850D01*
X273850Y745933D01*
X274267Y745850D01*
X274767Y745600D01*
G01X279200Y745933D02*
Y742600D01*
G01Y747267D02*
X279033Y747350D01*
Y747517D01*
X279200Y747600D01*
X279367Y747517D01*
Y747350D01*
X279200Y747267D01*
G01X286300Y742600D02*
Y745933D01*
G01Y745350D02*
X285967Y745683D01*
X285467Y745850D01*
X284883Y745933D01*
X284300Y745767D01*
X283800Y745433D01*
X283467Y744933D01*
X283300Y744267D01*
X283467Y743600D01*
X283800Y743100D01*
X284300Y742767D01*
X284883Y742600D01*
X285467Y742683D01*
X285967Y742933D01*
X286300Y743267D01*
G01X290400Y742600D02*
Y747600D01*
G01X294750Y743183D02*
X295167Y742850D01*
X295750Y742600D01*
X296250D01*
X296750Y742767D01*
X297083Y743017D01*
X297250Y743350D01*
X297167Y743850D01*
X296833Y744100D01*
X295333Y744600D01*
X295000Y745183D01*
X295167Y745600D01*
X295500Y745850D01*
X296000Y745933D01*
X296500Y745850D01*
X297000Y745600D01*
G01X306700Y742600D02*
Y746850D01*
X306867Y747267D01*
X307200Y747517D01*
X307700Y747600D01*
X308200Y747433D01*
X308450Y747017D01*
G01X307450Y745600D02*
X305783D01*
G01X312800Y742600D02*
X312300Y742683D01*
X311800Y743017D01*
X311467Y743600D01*
X311300Y744267D01*
X311467Y744933D01*
X311800Y745517D01*
X312300Y745850D01*
X312800Y745933D01*
X313300Y745850D01*
X313800Y745517D01*
X314133Y744933D01*
X314217Y744267D01*
X314133Y743600D01*
X313800Y743017D01*
X313300Y742683D01*
X312800Y742600D01*
G01X317233D02*
Y745933D01*
G01Y745267D02*
X317650Y745600D01*
X318067Y745850D01*
X318650Y745933D01*
X319067Y745850D01*
X319567Y745600D01*
G01X327933Y742600D02*
Y747600D01*
X330017D01*
X330683Y747350D01*
X331100Y747017D01*
X331267Y746350D01*
X331100Y745683D01*
X330600Y745267D01*
X330017Y745017D01*
X327933D01*
G01X330017D02*
X331267Y742600D01*
G01X335200Y745933D02*
Y742600D01*
G01Y747267D02*
X335033Y747350D01*
Y747517D01*
X335200Y747600D01*
X335367Y747517D01*
Y747350D01*
X335200Y747267D01*
G01X339633Y741350D02*
X340217Y741017D01*
X340883Y740933D01*
X341467Y741017D01*
X341967Y741433D01*
X342300Y742017D01*
Y745933D01*
G01Y745267D02*
X341967Y745600D01*
X341467Y745850D01*
X340883Y745933D01*
X340217Y745767D01*
X339800Y745433D01*
X339467Y744850D01*
X339300Y744267D01*
X339383Y743767D01*
X339717Y743183D01*
X340217Y742767D01*
X340883Y742600D01*
X341383Y742683D01*
X341967Y743017D01*
X342300Y743350D01*
G01X346400Y745933D02*
Y742600D01*
G01Y747267D02*
X346233Y747350D01*
Y747517D01*
X346400Y747600D01*
X346567Y747517D01*
Y747350D01*
X346400Y747267D01*
G01X353500Y747600D02*
Y742600D01*
G01Y743350D02*
X353167Y742933D01*
X352667Y742683D01*
X352083Y742600D01*
X351417Y742767D01*
X350917Y743183D01*
X350583Y743683D01*
X350500Y744267D01*
X350583Y744850D01*
X350917Y745350D01*
X351417Y745767D01*
X352083Y745933D01*
X352667Y745850D01*
X353083Y745683D01*
X353500Y745350D01*
G01X364700Y742600D02*
Y745933D01*
G01Y745350D02*
X364367Y745683D01*
X363867Y745850D01*
X363283Y745933D01*
X362700Y745767D01*
X362200Y745433D01*
X361867Y744933D01*
X361700Y744267D01*
X361867Y743600D01*
X362200Y743100D01*
X362700Y742767D01*
X363283Y742600D01*
X363867Y742683D01*
X364367Y742933D01*
X364700Y743267D01*
G01X367383Y742600D02*
Y745933D01*
G01Y745100D02*
X367717Y745517D01*
X368217Y745850D01*
X368883Y745933D01*
X369467Y745850D01*
X369967Y745517D01*
X370217Y744933D01*
Y742600D01*
G01X375900Y747600D02*
Y742600D01*
G01Y743350D02*
X375567Y742933D01*
X375067Y742683D01*
X374483Y742600D01*
X373817Y742767D01*
X373317Y743183D01*
X372983Y743683D01*
X372900Y744267D01*
X372983Y744850D01*
X373317Y745350D01*
X373817Y745767D01*
X374483Y745933D01*
X375067Y745850D01*
X375483Y745683D01*
X375900Y745350D01*
G01X383433Y742600D02*
Y747600D01*
X385600Y743433D01*
X387767Y747600D01*
Y742600D01*
G01X389783Y745933D02*
Y743600D01*
X390117Y743017D01*
X390617Y742683D01*
X391200Y742600D01*
X391783Y742683D01*
X392283Y743017D01*
X392617Y743600D01*
G01Y742600D02*
Y745933D01*
G01X396800Y742600D02*
Y747600D01*
G01X402400D02*
Y742600D01*
G01X401233Y745933D02*
X403567D01*
G01X408000D02*
Y742600D01*
G01Y747267D02*
X407833Y747350D01*
Y747517D01*
X408000Y747600D01*
X408167Y747517D01*
Y747350D01*
X408000Y747267D01*
G01X413600Y742600D02*
Y747600D01*
G01X420700Y742600D02*
Y745933D01*
G01Y745350D02*
X420367Y745683D01*
X419867Y745850D01*
X419283Y745933D01*
X418700Y745767D01*
X418200Y745433D01*
X417867Y744933D01*
X417700Y744267D01*
X417867Y743600D01*
X418200Y743100D01*
X418700Y742767D01*
X419283Y742600D01*
X419867Y742683D01*
X420367Y742933D01*
X420700Y743267D01*
G01X423050Y741100D02*
X423550Y740933D01*
X424217Y741100D01*
X424633Y741433D01*
X424967Y741850D01*
X425467Y743183D01*
X426550Y745933D01*
G01X423883D02*
X425467Y743183D01*
G01X429150Y744850D02*
X431817D01*
X431567Y745433D01*
X431150Y745767D01*
X430567Y745933D01*
X429983Y745850D01*
X429483Y745600D01*
X429150Y745017D01*
X428983Y744517D01*
Y744017D01*
X429150Y743517D01*
X429567Y743017D01*
X430067Y742683D01*
X430650Y742600D01*
X431233Y742767D01*
X431817Y743267D01*
G01X434833Y742600D02*
Y745933D01*
G01Y745267D02*
X435250Y745600D01*
X435667Y745850D01*
X436250Y745933D01*
X436667Y745850D01*
X437167Y745600D01*
G01X445533Y742600D02*
Y747600D01*
X447533D01*
X448200Y747350D01*
X448700Y746767D01*
X448867Y746100D01*
X448700Y745433D01*
X448283Y744933D01*
X447533Y744683D01*
X445533D01*
G01X451633Y742600D02*
Y745933D01*
G01Y745267D02*
X452050Y745600D01*
X452467Y745850D01*
X453050Y745933D01*
X453467Y745850D01*
X453967Y745600D01*
G01X458400Y745933D02*
Y742600D01*
G01Y747267D02*
X458233Y747350D01*
Y747517D01*
X458400Y747600D01*
X458567Y747517D01*
Y747350D01*
X458400Y747267D01*
G01X462583Y742600D02*
Y745933D01*
G01Y745100D02*
X462917Y745517D01*
X463417Y745850D01*
X464083Y745933D01*
X464667Y745850D01*
X465167Y745517D01*
X465417Y744933D01*
Y742600D01*
G01X469600Y747600D02*
Y742600D01*
G01X468433Y745933D02*
X470767D01*
G01X473950Y744850D02*
X476617D01*
X476367Y745433D01*
X475950Y745767D01*
X475367Y745933D01*
X474783Y745850D01*
X474283Y745600D01*
X473950Y745017D01*
X473783Y744517D01*
Y744017D01*
X473950Y743517D01*
X474367Y743017D01*
X474867Y742683D01*
X475450Y742600D01*
X476033Y742767D01*
X476617Y743267D01*
G01X482300Y747600D02*
Y742600D01*
G01Y743350D02*
X481967Y742933D01*
X481467Y742683D01*
X480883Y742600D01*
X480217Y742767D01*
X479717Y743183D01*
X479383Y743683D01*
X479300Y744267D01*
X479383Y744850D01*
X479717Y745350D01*
X480217Y745767D01*
X480883Y745933D01*
X481467Y745850D01*
X481883Y745683D01*
X482300Y745350D01*
G01X492667Y745267D02*
X493000Y745517D01*
X493250Y745933D01*
X493417Y746517D01*
X493250Y747017D01*
X492917Y747350D01*
X492333Y747600D01*
X490083D01*
Y742600D01*
X492833D01*
X493417Y742933D01*
X493750Y743433D01*
X493917Y744017D01*
X493750Y744600D01*
X493250Y745100D01*
X492667Y745267D01*
X490083D01*
G01X497600Y742600D02*
X497100Y742683D01*
X496600Y743017D01*
X496267Y743600D01*
X496100Y744267D01*
X496267Y744933D01*
X496600Y745517D01*
X497100Y745850D01*
X497600Y745933D01*
X498100Y745850D01*
X498600Y745517D01*
X498933Y744933D01*
X499017Y744267D01*
X498933Y743600D01*
X498600Y743017D01*
X498100Y742683D01*
X497600Y742600D01*
G01X504700D02*
Y745933D01*
G01Y745350D02*
X504367Y745683D01*
X503867Y745850D01*
X503283Y745933D01*
X502700Y745767D01*
X502200Y745433D01*
X501867Y744933D01*
X501700Y744267D01*
X501867Y743600D01*
X502200Y743100D01*
X502700Y742767D01*
X503283Y742600D01*
X503867Y742683D01*
X504367Y742933D01*
X504700Y743267D01*
G01X507633Y742600D02*
Y745933D01*
G01Y745267D02*
X508050Y745600D01*
X508467Y745850D01*
X509050Y745933D01*
X509467Y745850D01*
X509967Y745600D01*
G01X515900Y747600D02*
Y742600D01*
G01Y743350D02*
X515567Y742933D01*
X515067Y742683D01*
X514483Y742600D01*
X513817Y742767D01*
X513317Y743183D01*
X512983Y743683D01*
X512900Y744267D01*
X512983Y744850D01*
X513317Y745350D01*
X513817Y745767D01*
X514483Y745933D01*
X515067Y745850D01*
X515483Y745683D01*
X515900Y745350D01*
G01X518750Y743183D02*
X519167Y742850D01*
X519750Y742600D01*
X520250D01*
X520750Y742767D01*
X521083Y743017D01*
X521250Y743350D01*
X521167Y743850D01*
X520833Y744100D01*
X519333Y744600D01*
X519000Y745183D01*
X519167Y745600D01*
X519500Y745850D01*
X520000Y745933D01*
X520500Y745850D01*
X521000Y745600D01*
G01X71000Y756600D02*
X73000D01*
G01X72000D02*
Y751600D01*
G01X71000D02*
X73000D01*
G01X75933D02*
Y756600D01*
X77933D01*
X78600Y756350D01*
X79100Y755767D01*
X79267Y755100D01*
X79100Y754433D01*
X78683Y753933D01*
X77933Y753683D01*
X75933D01*
G01X85033Y756183D02*
X84533Y756433D01*
X83950Y756600D01*
X83283D01*
X82533Y756350D01*
X81950Y755933D01*
X81533Y755433D01*
X81200Y754600D01*
X81117Y753850D01*
X81283Y753100D01*
X81533Y752600D01*
X82033Y752100D01*
X82617Y751767D01*
X83200Y751600D01*
X83783D01*
X84367Y751767D01*
X84867Y752017D01*
X85283Y752350D01*
G01X87717Y753267D02*
X89883D01*
G01X94400Y756600D02*
Y751600D01*
G01X92483Y756600D02*
X96317D01*
G01X97833Y751600D02*
Y756600D01*
X100000Y752433D01*
X102167Y756600D01*
Y751600D01*
G01X104517Y753267D02*
X106683D01*
G01X109617Y753683D02*
X110200Y754267D01*
X110700Y754600D01*
X111367Y754767D01*
X111950Y754600D01*
X112367Y754267D01*
X112700Y753767D01*
X112783Y753183D01*
X112700Y752683D01*
X112367Y752183D01*
X111867Y751767D01*
X111283Y751600D01*
X110617Y751767D01*
X110033Y752267D01*
X109700Y753017D01*
X109617Y753850D01*
X109783Y754933D01*
X110033Y755517D01*
X110450Y756100D01*
X111033Y756517D01*
X111617Y756600D01*
X112200Y756433D01*
X112617Y756017D01*
G01X114967Y752350D02*
X115467Y751933D01*
X116050Y751683D01*
X116800Y751600D01*
X117550Y751767D01*
X118133Y752100D01*
X118550Y752683D01*
X118633Y753350D01*
X118467Y754017D01*
X118050Y754433D01*
X117467Y754767D01*
X116883Y754850D01*
X116300Y754767D01*
X115550Y754433D01*
X115800Y756600D01*
X118050D01*
G01X122400D02*
X121733Y756433D01*
X121233Y756017D01*
X120900Y755517D01*
X120650Y754850D01*
X120567Y754100D01*
X120650Y753350D01*
X120900Y752683D01*
X121233Y752183D01*
X121733Y751767D01*
X122400Y751600D01*
X123067Y751767D01*
X123567Y752183D01*
X123900Y752683D01*
X124150Y753350D01*
X124233Y754100D01*
X124150Y754850D01*
X123900Y755517D01*
X123567Y756017D01*
X123067Y756433D01*
X122400Y756600D01*
G01X133600D02*
Y751600D01*
G01X131683Y756600D02*
X135517D01*
G01X137950Y753850D02*
X140617D01*
X140367Y754433D01*
X139950Y754767D01*
X139367Y754933D01*
X138783Y754850D01*
X138283Y754600D01*
X137950Y754017D01*
X137783Y753517D01*
Y753017D01*
X137950Y752517D01*
X138367Y752017D01*
X138867Y751683D01*
X139450Y751600D01*
X140033Y751767D01*
X140617Y752267D01*
G01X143550Y752183D02*
X143967Y751850D01*
X144550Y751600D01*
X145050D01*
X145550Y751767D01*
X145883Y752017D01*
X146050Y752350D01*
X145967Y752850D01*
X145633Y753100D01*
X144133Y753600D01*
X143800Y754183D01*
X143967Y754600D01*
X144300Y754850D01*
X144800Y754933D01*
X145300Y754850D01*
X145800Y754600D01*
G01X150400Y756600D02*
Y751600D01*
G01X149233Y754933D02*
X151567D01*
G01X159433Y751600D02*
Y756600D01*
X161600Y752433D01*
X163767Y756600D01*
Y751600D01*
G01X165950Y753850D02*
X168617D01*
X168367Y754433D01*
X167950Y754767D01*
X167367Y754933D01*
X166783Y754850D01*
X166283Y754600D01*
X165950Y754017D01*
X165783Y753517D01*
Y753017D01*
X165950Y752517D01*
X166367Y752017D01*
X166867Y751683D01*
X167450Y751600D01*
X168033Y751767D01*
X168617Y752267D01*
G01X172800Y756600D02*
Y751600D01*
G01X171633Y754933D02*
X173967D01*
G01X176983Y751600D02*
Y756600D01*
G01Y754183D02*
X177400Y754600D01*
X177817Y754850D01*
X178483Y754933D01*
X178983Y754850D01*
X179567Y754517D01*
X179817Y754017D01*
Y751600D01*
G01X184000D02*
X183500Y751683D01*
X183000Y752017D01*
X182667Y752600D01*
X182500Y753267D01*
X182667Y753933D01*
X183000Y754517D01*
X183500Y754850D01*
X184000Y754933D01*
X184500Y754850D01*
X185000Y754517D01*
X185333Y753933D01*
X185417Y753267D01*
X185333Y752600D01*
X185000Y752017D01*
X184500Y751683D01*
X184000Y751600D01*
G01X191100Y756600D02*
Y751600D01*
G01Y752350D02*
X190767Y751933D01*
X190267Y751683D01*
X189683Y751600D01*
X189017Y751767D01*
X188517Y752183D01*
X188183Y752683D01*
X188100Y753267D01*
X188183Y753850D01*
X188517Y754350D01*
X189017Y754767D01*
X189683Y754933D01*
X190267Y754850D01*
X190683Y754683D01*
X191100Y754350D01*
G01X193950Y752183D02*
X194367Y751850D01*
X194950Y751600D01*
X195450D01*
X195950Y751767D01*
X196283Y752017D01*
X196450Y752350D01*
X196367Y752850D01*
X196033Y753100D01*
X194533Y753600D01*
X194200Y754183D01*
X194367Y754600D01*
X194700Y754850D01*
X195200Y754933D01*
X195700Y754850D01*
X196200Y754600D01*
G01X204233Y751600D02*
Y756600D01*
X206400Y752433D01*
X208567Y756600D01*
Y751600D01*
G01X213500D02*
Y754933D01*
G01Y754350D02*
X213167Y754683D01*
X212667Y754850D01*
X212083Y754933D01*
X211500Y754767D01*
X211000Y754433D01*
X210667Y753933D01*
X210500Y753267D01*
X210667Y752600D01*
X211000Y752100D01*
X211500Y751767D01*
X212083Y751600D01*
X212667Y751683D01*
X213167Y751933D01*
X213500Y752267D01*
G01X216183Y751600D02*
Y754933D01*
G01Y754100D02*
X216517Y754517D01*
X217017Y754850D01*
X217683Y754933D01*
X218267Y754850D01*
X218767Y754517D01*
X219017Y753933D01*
Y751600D01*
G01X221783Y754933D02*
Y752600D01*
X222117Y752017D01*
X222617Y751683D01*
X223200Y751600D01*
X223783Y751683D01*
X224283Y752017D01*
X224617Y752600D01*
G01Y751600D02*
Y754933D01*
G01X230300Y751600D02*
Y754933D01*
G01Y754350D02*
X229967Y754683D01*
X229467Y754850D01*
X228883Y754933D01*
X228300Y754767D01*
X227800Y754433D01*
X227467Y753933D01*
X227300Y753267D01*
X227467Y752600D01*
X227800Y752100D01*
X228300Y751767D01*
X228883Y751600D01*
X229467Y751683D01*
X229967Y751933D01*
X230300Y752267D01*
G01X234400Y751600D02*
Y756600D01*
G01X71000Y765600D02*
X73000D01*
G01X72000D02*
Y760600D01*
G01X71000D02*
X73000D01*
G01X75933D02*
Y765600D01*
X77933D01*
X78600Y765350D01*
X79100Y764767D01*
X79267Y764100D01*
X79100Y763433D01*
X78683Y762933D01*
X77933Y762683D01*
X75933D01*
G01X85033Y765183D02*
X84533Y765433D01*
X83950Y765600D01*
X83283D01*
X82533Y765350D01*
X81950Y764933D01*
X81533Y764433D01*
X81200Y763600D01*
X81117Y762850D01*
X81283Y762100D01*
X81533Y761600D01*
X82033Y761100D01*
X82617Y760767D01*
X83200Y760600D01*
X83783D01*
X84367Y760767D01*
X84867Y761017D01*
X85283Y761350D01*
G01X87717Y762267D02*
X89883D01*
G01X92817Y762683D02*
X93400Y763267D01*
X93900Y763600D01*
X94567Y763767D01*
X95150Y763600D01*
X95567Y763267D01*
X95900Y762767D01*
X95983Y762183D01*
X95900Y761683D01*
X95567Y761183D01*
X95067Y760767D01*
X94483Y760600D01*
X93817Y760767D01*
X93233Y761267D01*
X92900Y762017D01*
X92817Y762850D01*
X92983Y763933D01*
X93233Y764517D01*
X93650Y765100D01*
X94233Y765517D01*
X94817Y765600D01*
X95400Y765433D01*
X95817Y765017D01*
G01X100000Y765600D02*
X99333Y765433D01*
X98833Y765017D01*
X98500Y764517D01*
X98250Y763850D01*
X98167Y763100D01*
X98250Y762350D01*
X98500Y761683D01*
X98833Y761183D01*
X99333Y760767D01*
X100000Y760600D01*
X100667Y760767D01*
X101167Y761183D01*
X101500Y761683D01*
X101750Y762350D01*
X101833Y763100D01*
X101750Y763850D01*
X101500Y764517D01*
X101167Y765017D01*
X100667Y765433D01*
X100000Y765600D01*
G01X105600Y760600D02*
Y765600D01*
X104600Y764600D01*
G01Y760600D02*
X106600D01*
G01X109617Y762683D02*
X110200Y763267D01*
X110700Y763600D01*
X111367Y763767D01*
X111950Y763600D01*
X112367Y763267D01*
X112700Y762767D01*
X112783Y762183D01*
X112700Y761683D01*
X112367Y761183D01*
X111867Y760767D01*
X111283Y760600D01*
X110617Y760767D01*
X110033Y761267D01*
X109700Y762017D01*
X109617Y762850D01*
X109783Y763933D01*
X110033Y764517D01*
X110450Y765100D01*
X111033Y765517D01*
X111617Y765600D01*
X112200Y765433D01*
X112617Y765017D01*
G01X122400Y760600D02*
X121733Y760683D01*
X121150Y761017D01*
X120650Y761517D01*
X120317Y762100D01*
X120150Y762767D01*
Y763433D01*
X120317Y764100D01*
X120650Y764683D01*
X121150Y765183D01*
X121733Y765517D01*
X122400Y765600D01*
X123067Y765517D01*
X123650Y765183D01*
X124150Y764683D01*
X124483Y764100D01*
X124650Y763433D01*
Y762767D01*
X124483Y762100D01*
X124150Y761517D01*
X123650Y761017D01*
X123067Y760683D01*
X122400Y760600D01*
G01X123067Y761933D02*
X124067Y760600D01*
G01X126583Y763933D02*
Y761600D01*
X126917Y761017D01*
X127417Y760683D01*
X128000Y760600D01*
X128583Y760683D01*
X129083Y761017D01*
X129417Y761600D01*
G01Y760600D02*
Y763933D01*
G01X135100Y760600D02*
Y763933D01*
G01Y763350D02*
X134767Y763683D01*
X134267Y763850D01*
X133683Y763933D01*
X133100Y763767D01*
X132600Y763433D01*
X132267Y762933D01*
X132100Y762267D01*
X132267Y761600D01*
X132600Y761100D01*
X133100Y760767D01*
X133683Y760600D01*
X134267Y760683D01*
X134767Y760933D01*
X135100Y761267D01*
G01X139200Y760600D02*
Y765600D01*
G01X144800Y763933D02*
Y760600D01*
G01Y765267D02*
X144633Y765350D01*
Y765517D01*
X144800Y765600D01*
X144967Y765517D01*
Y765350D01*
X144800Y765267D01*
G01X149900Y760600D02*
Y764850D01*
X150067Y765267D01*
X150400Y765517D01*
X150900Y765600D01*
X151400Y765433D01*
X151650Y765017D01*
G01X150650Y763600D02*
X148983D01*
G01X156000Y763933D02*
Y760600D01*
G01Y765267D02*
X155833Y765350D01*
Y765517D01*
X156000Y765600D01*
X156167Y765517D01*
Y765350D01*
X156000Y765267D01*
G01X162933Y763517D02*
X162350Y763850D01*
X161850Y763933D01*
X161183Y763767D01*
X160683Y763433D01*
X160350Y762850D01*
X160267Y762267D01*
X160350Y761683D01*
X160683Y761183D01*
X161183Y760767D01*
X161850Y760600D01*
X162433Y760767D01*
X162933Y761100D01*
G01X168700Y760600D02*
Y763933D01*
G01Y763350D02*
X168367Y763683D01*
X167867Y763850D01*
X167283Y763933D01*
X166700Y763767D01*
X166200Y763433D01*
X165867Y762933D01*
X165700Y762267D01*
X165867Y761600D01*
X166200Y761100D01*
X166700Y760767D01*
X167283Y760600D01*
X167867Y760683D01*
X168367Y760933D01*
X168700Y761267D01*
G01X172800Y765600D02*
Y760600D01*
G01X171633Y763933D02*
X173967D01*
G01X178400D02*
Y760600D01*
G01Y765267D02*
X178233Y765350D01*
Y765517D01*
X178400Y765600D01*
X178567Y765517D01*
Y765350D01*
X178400Y765267D01*
G01X184000Y760600D02*
X183500Y760683D01*
X183000Y761017D01*
X182667Y761600D01*
X182500Y762267D01*
X182667Y762933D01*
X183000Y763517D01*
X183500Y763850D01*
X184000Y763933D01*
X184500Y763850D01*
X185000Y763517D01*
X185333Y762933D01*
X185417Y762267D01*
X185333Y761600D01*
X185000Y761017D01*
X184500Y760683D01*
X184000Y760600D01*
G01X188183D02*
Y763933D01*
G01Y763100D02*
X188517Y763517D01*
X189017Y763850D01*
X189683Y763933D01*
X190267Y763850D01*
X190767Y763517D01*
X191017Y762933D01*
Y760600D01*
G01X203300Y758933D02*
X199133Y763933D01*
Y764767D01*
X199967Y765600D01*
X200800D01*
X201633Y764767D01*
Y763933D01*
X200800Y763100D01*
X199133Y762267D01*
X198300Y761433D01*
Y759767D01*
X199133Y758933D01*
X201633D01*
X203300Y760600D01*
G01X210333D02*
Y765600D01*
X212333D01*
X213000Y765350D01*
X213500Y764767D01*
X213667Y764100D01*
X213500Y763433D01*
X213083Y762933D01*
X212333Y762683D01*
X210333D01*
G01X216350Y762850D02*
X219017D01*
X218767Y763433D01*
X218350Y763767D01*
X217767Y763933D01*
X217183Y763850D01*
X216683Y763600D01*
X216350Y763017D01*
X216183Y762517D01*
Y762017D01*
X216350Y761517D01*
X216767Y761017D01*
X217267Y760683D01*
X217850Y760600D01*
X218433Y760767D01*
X219017Y761267D01*
G01X222033Y760600D02*
Y763933D01*
G01Y763267D02*
X222450Y763600D01*
X222867Y763850D01*
X223450Y763933D01*
X223867Y763850D01*
X224367Y763600D01*
G01X228300Y760600D02*
Y764850D01*
X228467Y765267D01*
X228800Y765517D01*
X229300Y765600D01*
X229800Y765433D01*
X230050Y765017D01*
G01X229050Y763600D02*
X227383D01*
G01X234400Y760600D02*
X233900Y760683D01*
X233400Y761017D01*
X233067Y761600D01*
X232900Y762267D01*
X233067Y762933D01*
X233400Y763517D01*
X233900Y763850D01*
X234400Y763933D01*
X234900Y763850D01*
X235400Y763517D01*
X235733Y762933D01*
X235817Y762267D01*
X235733Y761600D01*
X235400Y761017D01*
X234900Y760683D01*
X234400Y760600D01*
G01X238833D02*
Y763933D01*
G01Y763267D02*
X239250Y763600D01*
X239667Y763850D01*
X240250Y763933D01*
X240667Y763850D01*
X241167Y763600D01*
G01X243100Y760600D02*
Y763933D01*
G01Y763017D02*
X243350Y763433D01*
X243767Y763767D01*
X244350Y763933D01*
X244933Y763767D01*
X245350Y763433D01*
X245600Y763017D01*
Y760600D01*
G01Y763017D02*
X245850Y763433D01*
X246267Y763767D01*
X246850Y763933D01*
X247433Y763767D01*
X247850Y763433D01*
X248100Y762933D01*
Y760600D01*
G01X252700D02*
Y763933D01*
G01Y763350D02*
X252367Y763683D01*
X251867Y763850D01*
X251283Y763933D01*
X250700Y763767D01*
X250200Y763433D01*
X249867Y762933D01*
X249700Y762267D01*
X249867Y761600D01*
X250200Y761100D01*
X250700Y760767D01*
X251283Y760600D01*
X251867Y760683D01*
X252367Y760933D01*
X252700Y761267D01*
G01X255383Y760600D02*
Y763933D01*
G01Y763100D02*
X255717Y763517D01*
X256217Y763850D01*
X256883Y763933D01*
X257467Y763850D01*
X257967Y763517D01*
X258217Y762933D01*
Y760600D01*
G01X263733Y763517D02*
X263150Y763850D01*
X262650Y763933D01*
X261983Y763767D01*
X261483Y763433D01*
X261150Y762850D01*
X261067Y762267D01*
X261150Y761683D01*
X261483Y761183D01*
X261983Y760767D01*
X262650Y760600D01*
X263233Y760767D01*
X263733Y761100D01*
G01X266750Y762850D02*
X269417D01*
X269167Y763433D01*
X268750Y763767D01*
X268167Y763933D01*
X267583Y763850D01*
X267083Y763600D01*
X266750Y763017D01*
X266583Y762517D01*
Y762017D01*
X266750Y761517D01*
X267167Y761017D01*
X267667Y760683D01*
X268250Y760600D01*
X268833Y760767D01*
X269417Y761267D01*
G01X277450D02*
X278117Y760850D01*
X278867Y760600D01*
X279533D01*
X280200Y760850D01*
X280700Y761267D01*
X280950Y761850D01*
X280783Y762433D01*
X280367Y762933D01*
X279617Y763267D01*
X278617Y763433D01*
X278033Y763767D01*
X277783Y764350D01*
X277950Y764933D01*
X278367Y765350D01*
X278950Y765600D01*
X279533D01*
X280117Y765433D01*
X280617Y765017D01*
G01X283300Y758933D02*
Y763933D01*
G01Y763183D02*
X283717Y763600D01*
X284133Y763850D01*
X284800Y763933D01*
X285383Y763850D01*
X285967Y763433D01*
X286217Y762850D01*
X286300Y762267D01*
X286217Y761683D01*
X285967Y761100D01*
X285467Y760767D01*
X284800Y760600D01*
X284217Y760683D01*
X283633Y760933D01*
X283300Y761267D01*
G01X289150Y762850D02*
X291817D01*
X291567Y763433D01*
X291150Y763767D01*
X290567Y763933D01*
X289983Y763850D01*
X289483Y763600D01*
X289150Y763017D01*
X288983Y762517D01*
Y762017D01*
X289150Y761517D01*
X289567Y761017D01*
X290067Y760683D01*
X290650Y760600D01*
X291233Y760767D01*
X291817Y761267D01*
G01X297333Y763517D02*
X296750Y763850D01*
X296250Y763933D01*
X295583Y763767D01*
X295083Y763433D01*
X294750Y762850D01*
X294667Y762267D01*
X294750Y761683D01*
X295083Y761183D01*
X295583Y760767D01*
X296250Y760600D01*
X296833Y760767D01*
X297333Y761100D01*
G01X301600Y763933D02*
Y760600D01*
G01Y765267D02*
X301433Y765350D01*
Y765517D01*
X301600Y765600D01*
X301767Y765517D01*
Y765350D01*
X301600Y765267D01*
G01X306700Y760600D02*
Y764850D01*
X306867Y765267D01*
X307200Y765517D01*
X307700Y765600D01*
X308200Y765433D01*
X308450Y765017D01*
G01X307450Y763600D02*
X305783D01*
G01X312800Y763933D02*
Y760600D01*
G01Y765267D02*
X312633Y765350D01*
Y765517D01*
X312800Y765600D01*
X312967Y765517D01*
Y765350D01*
X312800Y765267D01*
G01X319733Y763517D02*
X319150Y763850D01*
X318650Y763933D01*
X317983Y763767D01*
X317483Y763433D01*
X317150Y762850D01*
X317067Y762267D01*
X317150Y761683D01*
X317483Y761183D01*
X317983Y760767D01*
X318650Y760600D01*
X319233Y760767D01*
X319733Y761100D01*
G01X325500Y760600D02*
Y763933D01*
G01Y763350D02*
X325167Y763683D01*
X324667Y763850D01*
X324083Y763933D01*
X323500Y763767D01*
X323000Y763433D01*
X322667Y762933D01*
X322500Y762267D01*
X322667Y761600D01*
X323000Y761100D01*
X323500Y760767D01*
X324083Y760600D01*
X324667Y760683D01*
X325167Y760933D01*
X325500Y761267D01*
G01X329600Y765600D02*
Y760600D01*
G01X328433Y763933D02*
X330767D01*
G01X335200D02*
Y760600D01*
G01Y765267D02*
X335033Y765350D01*
Y765517D01*
X335200Y765600D01*
X335367Y765517D01*
Y765350D01*
X335200Y765267D01*
G01X340800Y760600D02*
X340300Y760683D01*
X339800Y761017D01*
X339467Y761600D01*
X339300Y762267D01*
X339467Y762933D01*
X339800Y763517D01*
X340300Y763850D01*
X340800Y763933D01*
X341300Y763850D01*
X341800Y763517D01*
X342133Y762933D01*
X342217Y762267D01*
X342133Y761600D01*
X341800Y761017D01*
X341300Y760683D01*
X340800Y760600D01*
G01X344983D02*
Y763933D01*
G01Y763100D02*
X345317Y763517D01*
X345817Y763850D01*
X346483Y763933D01*
X347067Y763850D01*
X347567Y763517D01*
X347817Y762933D01*
Y760600D01*
G01X357100D02*
Y764850D01*
X357267Y765267D01*
X357600Y765517D01*
X358100Y765600D01*
X358600Y765433D01*
X358850Y765017D01*
G01X357850Y763600D02*
X356183D01*
G01X363200Y760600D02*
X362700Y760683D01*
X362200Y761017D01*
X361867Y761600D01*
X361700Y762267D01*
X361867Y762933D01*
X362200Y763517D01*
X362700Y763850D01*
X363200Y763933D01*
X363700Y763850D01*
X364200Y763517D01*
X364533Y762933D01*
X364617Y762267D01*
X364533Y761600D01*
X364200Y761017D01*
X363700Y760683D01*
X363200Y760600D01*
G01X367633D02*
Y763933D01*
G01Y763267D02*
X368050Y763600D01*
X368467Y763850D01*
X369050Y763933D01*
X369467Y763850D01*
X369967Y763600D01*
G01X378250Y760600D02*
Y765600D01*
G01X381750D02*
Y760600D01*
G01Y763100D02*
X378250D01*
G01X385600Y763933D02*
Y760600D01*
G01Y765267D02*
X385433Y765350D01*
Y765517D01*
X385600Y765600D01*
X385767Y765517D01*
Y765350D01*
X385600Y765267D01*
G01X390033Y759350D02*
X390617Y759017D01*
X391283Y758933D01*
X391867Y759017D01*
X392367Y759433D01*
X392700Y760017D01*
Y763933D01*
G01Y763267D02*
X392367Y763600D01*
X391867Y763850D01*
X391283Y763933D01*
X390617Y763767D01*
X390200Y763433D01*
X389867Y762850D01*
X389700Y762267D01*
X389783Y761767D01*
X390117Y761183D01*
X390617Y760767D01*
X391283Y760600D01*
X391783Y760683D01*
X392367Y761017D01*
X392700Y761350D01*
G01X395383Y760600D02*
Y765600D01*
G01Y763183D02*
X395800Y763600D01*
X396217Y763850D01*
X396883Y763933D01*
X397383Y763850D01*
X397967Y763517D01*
X398217Y763017D01*
Y760600D01*
G01X406167D02*
Y765600D01*
X407833D01*
X408500Y765350D01*
X409000Y765017D01*
X409417Y764517D01*
X409750Y763933D01*
X409833Y763100D01*
X409750Y762267D01*
X409417Y761683D01*
X409000Y761183D01*
X408500Y760850D01*
X407833Y760600D01*
X406167D01*
G01X412350Y762850D02*
X415017D01*
X414767Y763433D01*
X414350Y763767D01*
X413767Y763933D01*
X413183Y763850D01*
X412683Y763600D01*
X412350Y763017D01*
X412183Y762517D01*
Y762017D01*
X412350Y761517D01*
X412767Y761017D01*
X413267Y760683D01*
X413850Y760600D01*
X414433Y760767D01*
X415017Y761267D01*
G01X417783Y760600D02*
Y763933D01*
G01Y763100D02*
X418117Y763517D01*
X418617Y763850D01*
X419283Y763933D01*
X419867Y763850D01*
X420367Y763517D01*
X420617Y762933D01*
Y760600D01*
G01X423550Y761183D02*
X423967Y760850D01*
X424550Y760600D01*
X425050D01*
X425550Y760767D01*
X425883Y761017D01*
X426050Y761350D01*
X425967Y761850D01*
X425633Y762100D01*
X424133Y762600D01*
X423800Y763183D01*
X423967Y763600D01*
X424300Y763850D01*
X424800Y763933D01*
X425300Y763850D01*
X425800Y763600D01*
G01X430400Y763933D02*
Y760600D01*
G01Y765267D02*
X430233Y765350D01*
Y765517D01*
X430400Y765600D01*
X430567Y765517D01*
Y765350D01*
X430400Y765267D01*
G01X436000Y765600D02*
Y760600D01*
G01X434833Y763933D02*
X437167D01*
G01X439850Y759100D02*
X440350Y758933D01*
X441017Y759100D01*
X441433Y759433D01*
X441767Y759850D01*
X442267Y761183D01*
X443350Y763933D01*
G01X440683D02*
X442267Y761183D01*
G01X451800Y765600D02*
X453800D01*
G01X452800D02*
Y760600D01*
G01X451800D02*
X453800D01*
G01X456983D02*
Y763933D01*
G01Y763100D02*
X457317Y763517D01*
X457817Y763850D01*
X458483Y763933D01*
X459067Y763850D01*
X459567Y763517D01*
X459817Y762933D01*
Y760600D01*
G01X464000Y765600D02*
Y760600D01*
G01X462833Y763933D02*
X465167D01*
G01X468350Y762850D02*
X471017D01*
X470767Y763433D01*
X470350Y763767D01*
X469767Y763933D01*
X469183Y763850D01*
X468683Y763600D01*
X468350Y763017D01*
X468183Y762517D01*
Y762017D01*
X468350Y761517D01*
X468767Y761017D01*
X469267Y760683D01*
X469850Y760600D01*
X470433Y760767D01*
X471017Y761267D01*
G01X474033Y760600D02*
Y763933D01*
G01Y763267D02*
X474450Y763600D01*
X474867Y763850D01*
X475450Y763933D01*
X475867Y763850D01*
X476367Y763600D01*
G01X482133Y763517D02*
X481550Y763850D01*
X481050Y763933D01*
X480383Y763767D01*
X479883Y763433D01*
X479550Y762850D01*
X479467Y762267D01*
X479550Y761683D01*
X479883Y761183D01*
X480383Y760767D01*
X481050Y760600D01*
X481633Y760767D01*
X482133Y761100D01*
G01X486400Y760600D02*
X485900Y760683D01*
X485400Y761017D01*
X485067Y761600D01*
X484900Y762267D01*
X485067Y762933D01*
X485400Y763517D01*
X485900Y763850D01*
X486400Y763933D01*
X486900Y763850D01*
X487400Y763517D01*
X487733Y762933D01*
X487817Y762267D01*
X487733Y761600D01*
X487400Y761017D01*
X486900Y760683D01*
X486400Y760600D01*
G01X490583D02*
Y763933D01*
G01Y763100D02*
X490917Y763517D01*
X491417Y763850D01*
X492083Y763933D01*
X492667Y763850D01*
X493167Y763517D01*
X493417Y762933D01*
Y760600D01*
G01X496183D02*
Y763933D01*
G01Y763100D02*
X496517Y763517D01*
X497017Y763850D01*
X497683Y763933D01*
X498267Y763850D01*
X498767Y763517D01*
X499017Y762933D01*
Y760600D01*
G01X501950Y762850D02*
X504617D01*
X504367Y763433D01*
X503950Y763767D01*
X503367Y763933D01*
X502783Y763850D01*
X502283Y763600D01*
X501950Y763017D01*
X501783Y762517D01*
Y762017D01*
X501950Y761517D01*
X502367Y761017D01*
X502867Y760683D01*
X503450Y760600D01*
X504033Y760767D01*
X504617Y761267D01*
G01X510133Y763517D02*
X509550Y763850D01*
X509050Y763933D01*
X508383Y763767D01*
X507883Y763433D01*
X507550Y762850D01*
X507467Y762267D01*
X507550Y761683D01*
X507883Y761183D01*
X508383Y760767D01*
X509050Y760600D01*
X509633Y760767D01*
X510133Y761100D01*
G01X514400Y765600D02*
Y760600D01*
G01X513233Y763933D02*
X515567D01*
G01X519583Y758933D02*
X518750Y759767D01*
X518333Y760600D01*
Y763933D01*
X518750Y764767D01*
X519583Y765600D01*
G01X523850Y760600D02*
Y765600D01*
G01X527350D02*
Y760600D01*
G01Y763100D02*
X523850D01*
G01X529367Y760600D02*
Y765600D01*
X531033D01*
X531700Y765350D01*
X532200Y765017D01*
X532617Y764517D01*
X532950Y763933D01*
X533033Y763100D01*
X532950Y762267D01*
X532617Y761683D01*
X532200Y761183D01*
X531700Y760850D01*
X531033Y760600D01*
X529367D01*
G01X535800Y765600D02*
X537800D01*
G01X536800D02*
Y760600D01*
G01X535800D02*
X537800D01*
G01X542817Y758933D02*
X543650Y759767D01*
X544067Y760600D01*
Y763933D01*
X543650Y764767D01*
X542817Y765600D01*
G01X551933D02*
Y760600D01*
X555267D01*
G01X560700D02*
Y763933D01*
G01Y763350D02*
X560367Y763683D01*
X559867Y763850D01*
X559283Y763933D01*
X558700Y763767D01*
X558200Y763433D01*
X557867Y762933D01*
X557700Y762267D01*
X557867Y761600D01*
X558200Y761100D01*
X558700Y760767D01*
X559283Y760600D01*
X559867Y760683D01*
X560367Y760933D01*
X560700Y761267D01*
G01X563050Y759100D02*
X563550Y758933D01*
X564217Y759100D01*
X564633Y759433D01*
X564967Y759850D01*
X565467Y761183D01*
X566550Y763933D01*
G01X563883D02*
X565467Y761183D01*
G01X569150Y762850D02*
X571817D01*
X571567Y763433D01*
X571150Y763767D01*
X570567Y763933D01*
X569983Y763850D01*
X569483Y763600D01*
X569150Y763017D01*
X568983Y762517D01*
Y762017D01*
X569150Y761517D01*
X569567Y761017D01*
X570067Y760683D01*
X570650Y760600D01*
X571233Y760767D01*
X571817Y761267D01*
G01X574833Y760600D02*
Y763933D01*
G01Y763267D02*
X575250Y763600D01*
X575667Y763850D01*
X576250Y763933D01*
X576667Y763850D01*
X577167Y763600D01*
G01X580350Y761183D02*
X580767Y760850D01*
X581350Y760600D01*
X581850D01*
X582350Y760767D01*
X582683Y761017D01*
X582850Y761350D01*
X582767Y761850D01*
X582433Y762100D01*
X580933Y762600D01*
X580600Y763183D01*
X580767Y763600D01*
X581100Y763850D01*
X581600Y763933D01*
X582100Y763850D01*
X582600Y763600D01*
G01X592800Y760600D02*
X592300Y760683D01*
X591800Y761017D01*
X591467Y761600D01*
X591300Y762267D01*
X591467Y762933D01*
X591800Y763517D01*
X592300Y763850D01*
X592800Y763933D01*
X593300Y763850D01*
X593800Y763517D01*
X594133Y762933D01*
X594217Y762267D01*
X594133Y761600D01*
X593800Y761017D01*
X593300Y760683D01*
X592800Y760600D01*
G01X597233D02*
Y763933D01*
G01Y763267D02*
X597650Y763600D01*
X598067Y763850D01*
X598650Y763933D01*
X599067Y763850D01*
X599567Y763600D01*
G01X610267Y763267D02*
X610600Y763517D01*
X610850Y763933D01*
X611017Y764517D01*
X610850Y765017D01*
X610517Y765350D01*
X609933Y765600D01*
X607683D01*
Y760600D01*
X610433D01*
X611017Y760933D01*
X611350Y761433D01*
X611517Y762017D01*
X611350Y762600D01*
X610850Y763100D01*
X610267Y763267D01*
X607683D01*
G01X615200Y760600D02*
X614700Y760683D01*
X614200Y761017D01*
X613867Y761600D01*
X613700Y762267D01*
X613867Y762933D01*
X614200Y763517D01*
X614700Y763850D01*
X615200Y763933D01*
X615700Y763850D01*
X616200Y763517D01*
X616533Y762933D01*
X616617Y762267D01*
X616533Y761600D01*
X616200Y761017D01*
X615700Y760683D01*
X615200Y760600D01*
G01X622300D02*
Y763933D01*
G01Y763350D02*
X621967Y763683D01*
X621467Y763850D01*
X620883Y763933D01*
X620300Y763767D01*
X619800Y763433D01*
X619467Y762933D01*
X619300Y762267D01*
X619467Y761600D01*
X619800Y761100D01*
X620300Y760767D01*
X620883Y760600D01*
X621467Y760683D01*
X621967Y760933D01*
X622300Y761267D01*
G01X625233Y760600D02*
Y763933D01*
G01Y763267D02*
X625650Y763600D01*
X626067Y763850D01*
X626650Y763933D01*
X627067Y763850D01*
X627567Y763600D01*
G01X633500Y765600D02*
Y760600D01*
G01Y761350D02*
X633167Y760933D01*
X632667Y760683D01*
X632083Y760600D01*
X631417Y760767D01*
X630917Y761183D01*
X630583Y761683D01*
X630500Y762267D01*
X630583Y762850D01*
X630917Y763350D01*
X631417Y763767D01*
X632083Y763933D01*
X632667Y763850D01*
X633083Y763683D01*
X633500Y763350D01*
G01X636350Y761183D02*
X636767Y760850D01*
X637350Y760600D01*
X637850D01*
X638350Y760767D01*
X638683Y761017D01*
X638850Y761350D01*
X638767Y761850D01*
X638433Y762100D01*
X636933Y762600D01*
X636600Y763183D01*
X636767Y763600D01*
X637100Y763850D01*
X637600Y763933D01*
X638100Y763850D01*
X638600Y763600D01*
G01X643617Y758933D02*
X644450Y759767D01*
X644867Y760600D01*
Y763933D01*
X644450Y764767D01*
X643617Y765600D01*
G01X7000Y832500D02*
Y837500D01*
X6000Y836500D01*
G01Y832500D02*
X8000D01*
G01X12600Y832333D02*
X12433Y832417D01*
Y832583D01*
X12600Y832667D01*
X12767Y832583D01*
Y832417D01*
X12600Y832333D01*
G01X16450Y833167D02*
X17117Y832750D01*
X17867Y832500D01*
X18533D01*
X19200Y832750D01*
X19700Y833167D01*
X19950Y833750D01*
X19783Y834333D01*
X19367Y834833D01*
X18617Y835167D01*
X17617Y835333D01*
X17033Y835667D01*
X16783Y836250D01*
X16950Y836833D01*
X17367Y837250D01*
X17950Y837500D01*
X18533D01*
X19117Y837333D01*
X19617Y836917D01*
G01X22300Y830833D02*
Y835833D01*
G01Y835083D02*
X22717Y835500D01*
X23133Y835750D01*
X23800Y835833D01*
X24383Y835750D01*
X24967Y835333D01*
X25217Y834750D01*
X25300Y834167D01*
X25217Y833583D01*
X24967Y833000D01*
X24467Y832667D01*
X23800Y832500D01*
X23217Y832583D01*
X22633Y832833D01*
X22300Y833167D01*
G01X28150Y834750D02*
X30817D01*
X30567Y835333D01*
X30150Y835667D01*
X29567Y835833D01*
X28983Y835750D01*
X28483Y835500D01*
X28150Y834917D01*
X27983Y834417D01*
Y833917D01*
X28150Y833417D01*
X28567Y832917D01*
X29067Y832583D01*
X29650Y832500D01*
X30233Y832667D01*
X30817Y833167D01*
G01X36333Y835417D02*
X35750Y835750D01*
X35250Y835833D01*
X34583Y835667D01*
X34083Y835333D01*
X33750Y834750D01*
X33667Y834167D01*
X33750Y833583D01*
X34083Y833083D01*
X34583Y832667D01*
X35250Y832500D01*
X35833Y832667D01*
X36333Y833000D01*
G01X40600Y835833D02*
Y832500D01*
G01Y837167D02*
X40433Y837250D01*
Y837417D01*
X40600Y837500D01*
X40767Y837417D01*
Y837250D01*
X40600Y837167D01*
G01X45700Y832500D02*
Y836750D01*
X45867Y837167D01*
X46200Y837417D01*
X46700Y837500D01*
X47200Y837333D01*
X47450Y836917D01*
G01X46450Y835500D02*
X44783D01*
G01X51800Y835833D02*
Y832500D01*
G01Y837167D02*
X51633Y837250D01*
Y837417D01*
X51800Y837500D01*
X51967Y837417D01*
Y837250D01*
X51800Y837167D01*
G01X58733Y835417D02*
X58150Y835750D01*
X57650Y835833D01*
X56983Y835667D01*
X56483Y835333D01*
X56150Y834750D01*
X56067Y834167D01*
X56150Y833583D01*
X56483Y833083D01*
X56983Y832667D01*
X57650Y832500D01*
X58233Y832667D01*
X58733Y833000D01*
G01X64500Y832500D02*
Y835833D01*
G01Y835250D02*
X64167Y835583D01*
X63667Y835750D01*
X63083Y835833D01*
X62500Y835667D01*
X62000Y835333D01*
X61667Y834833D01*
X61500Y834167D01*
X61667Y833500D01*
X62000Y833000D01*
X62500Y832667D01*
X63083Y832500D01*
X63667Y832583D01*
X64167Y832833D01*
X64500Y833167D01*
G01X68600Y837500D02*
Y832500D01*
G01X67433Y835833D02*
X69767D01*
G01X74200D02*
Y832500D01*
G01Y837167D02*
X74033Y837250D01*
Y837417D01*
X74200Y837500D01*
X74367Y837417D01*
Y837250D01*
X74200Y837167D01*
G01X79800Y832500D02*
X79300Y832583D01*
X78800Y832917D01*
X78467Y833500D01*
X78300Y834167D01*
X78467Y834833D01*
X78800Y835417D01*
X79300Y835750D01*
X79800Y835833D01*
X80300Y835750D01*
X80800Y835417D01*
X81133Y834833D01*
X81217Y834167D01*
X81133Y833500D01*
X80800Y832917D01*
X80300Y832583D01*
X79800Y832500D01*
G01X83983D02*
Y835833D01*
G01Y835000D02*
X84317Y835417D01*
X84817Y835750D01*
X85483Y835833D01*
X86067Y835750D01*
X86567Y835417D01*
X86817Y834833D01*
Y832500D01*
G01X98100Y837500D02*
Y832500D01*
G01Y833250D02*
X97767Y832833D01*
X97267Y832583D01*
X96683Y832500D01*
X96017Y832667D01*
X95517Y833083D01*
X95183Y833583D01*
X95100Y834167D01*
X95183Y834750D01*
X95517Y835250D01*
X96017Y835667D01*
X96683Y835833D01*
X97267Y835750D01*
X97683Y835583D01*
X98100Y835250D01*
G01X102200Y832500D02*
X101700Y832583D01*
X101200Y832917D01*
X100867Y833500D01*
X100700Y834167D01*
X100867Y834833D01*
X101200Y835417D01*
X101700Y835750D01*
X102200Y835833D01*
X102700Y835750D01*
X103200Y835417D01*
X103533Y834833D01*
X103617Y834167D01*
X103533Y833500D01*
X103200Y832917D01*
X102700Y832583D01*
X102200Y832500D01*
G01X109133Y835417D02*
X108550Y835750D01*
X108050Y835833D01*
X107383Y835667D01*
X106883Y835333D01*
X106550Y834750D01*
X106467Y834167D01*
X106550Y833583D01*
X106883Y833083D01*
X107383Y832667D01*
X108050Y832500D01*
X108633Y832667D01*
X109133Y833000D01*
G01X111983Y835833D02*
Y833500D01*
X112317Y832917D01*
X112817Y832583D01*
X113400Y832500D01*
X113983Y832583D01*
X114483Y832917D01*
X114817Y833500D01*
G01Y832500D02*
Y835833D01*
G01X116500Y832500D02*
Y835833D01*
G01Y834917D02*
X116750Y835333D01*
X117167Y835667D01*
X117750Y835833D01*
X118333Y835667D01*
X118750Y835333D01*
X119000Y834917D01*
Y832500D01*
G01Y834917D02*
X119250Y835333D01*
X119667Y835667D01*
X120250Y835833D01*
X120833Y835667D01*
X121250Y835333D01*
X121500Y834833D01*
Y832500D01*
G01X123350Y834750D02*
X126017D01*
X125767Y835333D01*
X125350Y835667D01*
X124767Y835833D01*
X124183Y835750D01*
X123683Y835500D01*
X123350Y834917D01*
X123183Y834417D01*
Y833917D01*
X123350Y833417D01*
X123767Y832917D01*
X124267Y832583D01*
X124850Y832500D01*
X125433Y832667D01*
X126017Y833167D01*
G01X128783Y832500D02*
Y835833D01*
G01Y835000D02*
X129117Y835417D01*
X129617Y835750D01*
X130283Y835833D01*
X130867Y835750D01*
X131367Y835417D01*
X131617Y834833D01*
Y832500D01*
G01X135800Y837500D02*
Y832500D01*
G01X134633Y835833D02*
X136967D01*
G01X141400Y832333D02*
X141233Y832417D01*
Y832583D01*
X141400Y832667D01*
X141567Y832583D01*
Y832417D01*
X141400Y832333D01*
G01Y834583D02*
X141233Y834667D01*
Y834833D01*
X141400Y834917D01*
X141567Y834833D01*
Y834667D01*
X141400Y834583D01*
G01X57000Y802500D02*
X59000D01*
G01X58000D02*
Y797500D01*
G01X57000D02*
X59000D01*
G01X63100D02*
Y801750D01*
X63267Y802167D01*
X63600Y802417D01*
X64100Y802500D01*
X64600Y802333D01*
X64850Y801917D01*
G01X63850Y800500D02*
X62183D01*
G01X74800Y802500D02*
Y797500D01*
G01X73633Y800833D02*
X75967D01*
G01X78983Y797500D02*
Y802500D01*
G01Y800083D02*
X79400Y800500D01*
X79817Y800750D01*
X80483Y800833D01*
X80983Y800750D01*
X81567Y800417D01*
X81817Y799917D01*
Y797500D01*
G01X84750Y799750D02*
X87417D01*
X87167Y800333D01*
X86750Y800667D01*
X86167Y800833D01*
X85583Y800750D01*
X85083Y800500D01*
X84750Y799917D01*
X84583Y799417D01*
Y798917D01*
X84750Y798417D01*
X85167Y797917D01*
X85667Y797583D01*
X86250Y797500D01*
X86833Y797667D01*
X87417Y798167D01*
G01X98533Y800417D02*
X97950Y800750D01*
X97450Y800833D01*
X96783Y800667D01*
X96283Y800333D01*
X95950Y799750D01*
X95867Y799167D01*
X95950Y798583D01*
X96283Y798083D01*
X96783Y797667D01*
X97450Y797500D01*
X98033Y797667D01*
X98533Y798000D01*
G01X101633Y797500D02*
Y800833D01*
G01Y800167D02*
X102050Y800500D01*
X102467Y800750D01*
X103050Y800833D01*
X103467Y800750D01*
X103967Y800500D01*
G01X108400Y800833D02*
Y797500D01*
G01Y802167D02*
X108233Y802250D01*
Y802417D01*
X108400Y802500D01*
X108567Y802417D01*
Y802250D01*
X108400Y802167D01*
G01X114000Y802500D02*
Y797500D01*
G01X112833Y800833D02*
X115167D01*
G01X118350Y799750D02*
X121017D01*
X120767Y800333D01*
X120350Y800667D01*
X119767Y800833D01*
X119183Y800750D01*
X118683Y800500D01*
X118350Y799917D01*
X118183Y799417D01*
Y798917D01*
X118350Y798417D01*
X118767Y797917D01*
X119267Y797583D01*
X119850Y797500D01*
X120433Y797667D01*
X121017Y798167D01*
G01X124033Y797500D02*
Y800833D01*
G01Y800167D02*
X124450Y800500D01*
X124867Y800750D01*
X125450Y800833D01*
X125867Y800750D01*
X126367Y800500D01*
G01X130800Y800833D02*
Y797500D01*
G01Y802167D02*
X130633Y802250D01*
Y802417D01*
X130800Y802500D01*
X130967Y802417D01*
Y802250D01*
X130800Y802167D01*
G01X137900Y797500D02*
Y800833D01*
G01Y800250D02*
X137567Y800583D01*
X137067Y800750D01*
X136483Y800833D01*
X135900Y800667D01*
X135400Y800333D01*
X135067Y799833D01*
X134900Y799167D01*
X135067Y798500D01*
X135400Y798000D01*
X135900Y797667D01*
X136483Y797500D01*
X137067Y797583D01*
X137567Y797833D01*
X137900Y798167D01*
G01X147600Y800833D02*
Y797500D01*
G01Y802167D02*
X147433Y802250D01*
Y802417D01*
X147600Y802500D01*
X147767Y802417D01*
Y802250D01*
X147600Y802167D01*
G01X151950Y798083D02*
X152367Y797750D01*
X152950Y797500D01*
X153450D01*
X153950Y797667D01*
X154283Y797917D01*
X154450Y798250D01*
X154367Y798750D01*
X154033Y799000D01*
X152533Y799500D01*
X152200Y800083D01*
X152367Y800500D01*
X152700Y800750D01*
X153200Y800833D01*
X153700Y800750D01*
X154200Y800500D01*
G01X162983Y797500D02*
Y800833D01*
G01Y800000D02*
X163317Y800417D01*
X163817Y800750D01*
X164483Y800833D01*
X165067Y800750D01*
X165567Y800417D01*
X165817Y799833D01*
Y797500D01*
G01X170000D02*
X169500Y797583D01*
X169000Y797917D01*
X168667Y798500D01*
X168500Y799167D01*
X168667Y799833D01*
X169000Y800417D01*
X169500Y800750D01*
X170000Y800833D01*
X170500Y800750D01*
X171000Y800417D01*
X171333Y799833D01*
X171417Y799167D01*
X171333Y798500D01*
X171000Y797917D01*
X170500Y797583D01*
X170000Y797500D01*
G01X175600Y802500D02*
Y797500D01*
G01X174433Y800833D02*
X176767D01*
G01X185550Y798083D02*
X185967Y797750D01*
X186550Y797500D01*
X187050D01*
X187550Y797667D01*
X187883Y797917D01*
X188050Y798250D01*
X187967Y798750D01*
X187633Y799000D01*
X186133Y799500D01*
X185800Y800083D01*
X185967Y800500D01*
X186300Y800750D01*
X186800Y800833D01*
X187300Y800750D01*
X187800Y800500D01*
G01X190900Y795833D02*
Y800833D01*
G01Y800083D02*
X191317Y800500D01*
X191733Y800750D01*
X192400Y800833D01*
X192983Y800750D01*
X193567Y800333D01*
X193817Y799750D01*
X193900Y799167D01*
X193817Y798583D01*
X193567Y798000D01*
X193067Y797667D01*
X192400Y797500D01*
X191817Y797583D01*
X191233Y797833D01*
X190900Y798167D01*
G01X196750Y799750D02*
X199417D01*
X199167Y800333D01*
X198750Y800667D01*
X198167Y800833D01*
X197583Y800750D01*
X197083Y800500D01*
X196750Y799917D01*
X196583Y799417D01*
Y798917D01*
X196750Y798417D01*
X197167Y797917D01*
X197667Y797583D01*
X198250Y797500D01*
X198833Y797667D01*
X199417Y798167D01*
G01X204933Y800417D02*
X204350Y800750D01*
X203850Y800833D01*
X203183Y800667D01*
X202683Y800333D01*
X202350Y799750D01*
X202267Y799167D01*
X202350Y798583D01*
X202683Y798083D01*
X203183Y797667D01*
X203850Y797500D01*
X204433Y797667D01*
X204933Y798000D01*
G01X209200Y800833D02*
Y797500D01*
G01Y802167D02*
X209033Y802250D01*
Y802417D01*
X209200Y802500D01*
X209367Y802417D01*
Y802250D01*
X209200Y802167D01*
G01X214300Y797500D02*
Y801750D01*
X214467Y802167D01*
X214800Y802417D01*
X215300Y802500D01*
X215800Y802333D01*
X216050Y801917D01*
G01X215050Y800500D02*
X213383D01*
G01X220400Y800833D02*
Y797500D01*
G01Y802167D02*
X220233Y802250D01*
Y802417D01*
X220400Y802500D01*
X220567Y802417D01*
Y802250D01*
X220400Y802167D01*
G01X224750Y799750D02*
X227417D01*
X227167Y800333D01*
X226750Y800667D01*
X226167Y800833D01*
X225583Y800750D01*
X225083Y800500D01*
X224750Y799917D01*
X224583Y799417D01*
Y798917D01*
X224750Y798417D01*
X225167Y797917D01*
X225667Y797583D01*
X226250Y797500D01*
X226833Y797667D01*
X227417Y798167D01*
G01X233100Y802500D02*
Y797500D01*
G01Y798250D02*
X232767Y797833D01*
X232267Y797583D01*
X231683Y797500D01*
X231017Y797667D01*
X230517Y798083D01*
X230183Y798583D01*
X230100Y799167D01*
X230183Y799750D01*
X230517Y800250D01*
X231017Y800667D01*
X231683Y800833D01*
X232267Y800750D01*
X232683Y800583D01*
X233100Y800250D01*
G01X242800Y800833D02*
Y797500D01*
G01Y802167D02*
X242633Y802250D01*
Y802417D01*
X242800Y802500D01*
X242967Y802417D01*
Y802250D01*
X242800Y802167D01*
G01X246983Y797500D02*
Y800833D01*
G01Y800000D02*
X247317Y800417D01*
X247817Y800750D01*
X248483Y800833D01*
X249067Y800750D01*
X249567Y800417D01*
X249817Y799833D01*
Y797500D01*
G01X259600Y802500D02*
Y797500D01*
G01X258433Y800833D02*
X260767D01*
G01X263783Y797500D02*
Y802500D01*
G01Y800083D02*
X264200Y800500D01*
X264617Y800750D01*
X265283Y800833D01*
X265783Y800750D01*
X266367Y800417D01*
X266617Y799917D01*
Y797500D01*
G01X269550Y799750D02*
X272217D01*
X271967Y800333D01*
X271550Y800667D01*
X270967Y800833D01*
X270383Y800750D01*
X269883Y800500D01*
X269550Y799917D01*
X269383Y799417D01*
Y798917D01*
X269550Y798417D01*
X269967Y797917D01*
X270467Y797583D01*
X271050Y797500D01*
X271633Y797667D01*
X272217Y798167D01*
G01X282000Y802500D02*
Y797500D01*
G01X280833Y800833D02*
X283167D01*
G01X289100Y797500D02*
Y800833D01*
G01Y800250D02*
X288767Y800583D01*
X288267Y800750D01*
X287683Y800833D01*
X287100Y800667D01*
X286600Y800333D01*
X286267Y799833D01*
X286100Y799167D01*
X286267Y798500D01*
X286600Y798000D01*
X287100Y797667D01*
X287683Y797500D01*
X288267Y797583D01*
X288767Y797833D01*
X289100Y798167D01*
G01X291700Y797500D02*
Y802500D01*
G01Y800000D02*
X292117Y800500D01*
X292617Y800750D01*
X293117Y800833D01*
X293867Y800667D01*
X294367Y800333D01*
X294700Y799750D01*
Y799083D01*
X294533Y798417D01*
X294200Y797917D01*
X293617Y797583D01*
X293117Y797500D01*
X292617Y797583D01*
X292117Y797833D01*
X291700Y798250D01*
G01X298800Y797500D02*
Y802500D01*
G01X303150Y799750D02*
X305817D01*
X305567Y800333D01*
X305150Y800667D01*
X304567Y800833D01*
X303983Y800750D01*
X303483Y800500D01*
X303150Y799917D01*
X302983Y799417D01*
Y798917D01*
X303150Y798417D01*
X303567Y797917D01*
X304067Y797583D01*
X304650Y797500D01*
X305233Y797667D01*
X305817Y798167D01*
G01X310000Y797333D02*
X309833Y797417D01*
Y797583D01*
X310000Y797667D01*
X310167Y797583D01*
Y797417D01*
X310000Y797333D01*
G01Y799583D02*
X309833Y799667D01*
Y799833D01*
X310000Y799917D01*
X310167Y799833D01*
Y799667D01*
X310000Y799583D01*
G01X67000Y770433D02*
X66833Y770517D01*
Y770683D01*
X67000Y770767D01*
X67167Y770683D01*
Y770517D01*
X67000Y770433D01*
G01X71000Y774600D02*
X73000D01*
G01X72000D02*
Y769600D01*
G01X71000D02*
X73000D01*
G01X75933D02*
Y774600D01*
X77933D01*
X78600Y774350D01*
X79100Y773767D01*
X79267Y773100D01*
X79100Y772433D01*
X78683Y771933D01*
X77933Y771683D01*
X75933D01*
G01X85033Y774183D02*
X84533Y774433D01*
X83950Y774600D01*
X83283D01*
X82533Y774350D01*
X81950Y773933D01*
X81533Y773433D01*
X81200Y772600D01*
X81117Y771850D01*
X81283Y771100D01*
X81533Y770600D01*
X82033Y770100D01*
X82617Y769767D01*
X83200Y769600D01*
X83783D01*
X84367Y769767D01*
X84867Y770017D01*
X85283Y770350D01*
G01X87717Y771267D02*
X89883D01*
G01X92817Y771683D02*
X93400Y772267D01*
X93900Y772600D01*
X94567Y772767D01*
X95150Y772600D01*
X95567Y772267D01*
X95900Y771767D01*
X95983Y771183D01*
X95900Y770683D01*
X95567Y770183D01*
X95067Y769767D01*
X94483Y769600D01*
X93817Y769767D01*
X93233Y770267D01*
X92900Y771017D01*
X92817Y771850D01*
X92983Y772933D01*
X93233Y773517D01*
X93650Y774100D01*
X94233Y774517D01*
X94817Y774600D01*
X95400Y774433D01*
X95817Y774017D01*
G01X100000Y774600D02*
X99333Y774433D01*
X98833Y774017D01*
X98500Y773517D01*
X98250Y772850D01*
X98167Y772100D01*
X98250Y771350D01*
X98500Y770683D01*
X98833Y770183D01*
X99333Y769767D01*
X100000Y769600D01*
X100667Y769767D01*
X101167Y770183D01*
X101500Y770683D01*
X101750Y771350D01*
X101833Y772100D01*
X101750Y772850D01*
X101500Y773517D01*
X101167Y774017D01*
X100667Y774433D01*
X100000Y774600D01*
G01X105600Y769600D02*
Y774600D01*
X104600Y773600D01*
G01Y769600D02*
X106600D01*
G01X109617Y773767D02*
X110117Y774267D01*
X110700Y774517D01*
X111367Y774600D01*
X112200Y774433D01*
X112783Y774017D01*
X112950Y773517D01*
X112867Y773017D01*
X112533Y772600D01*
X110867Y771767D01*
X110117Y771183D01*
X109617Y770350D01*
X109450Y769600D01*
X112950D01*
G01X122400D02*
X121733Y769683D01*
X121150Y770017D01*
X120650Y770517D01*
X120317Y771100D01*
X120150Y771767D01*
Y772433D01*
X120317Y773100D01*
X120650Y773683D01*
X121150Y774183D01*
X121733Y774517D01*
X122400Y774600D01*
X123067Y774517D01*
X123650Y774183D01*
X124150Y773683D01*
X124483Y773100D01*
X124650Y772433D01*
Y771767D01*
X124483Y771100D01*
X124150Y770517D01*
X123650Y770017D01*
X123067Y769683D01*
X122400Y769600D01*
G01X123067Y770933D02*
X124067Y769600D01*
G01X126583Y772933D02*
Y770600D01*
X126917Y770017D01*
X127417Y769683D01*
X128000Y769600D01*
X128583Y769683D01*
X129083Y770017D01*
X129417Y770600D01*
G01Y769600D02*
Y772933D01*
G01X135100Y769600D02*
Y772933D01*
G01Y772350D02*
X134767Y772683D01*
X134267Y772850D01*
X133683Y772933D01*
X133100Y772767D01*
X132600Y772433D01*
X132267Y771933D01*
X132100Y771267D01*
X132267Y770600D01*
X132600Y770100D01*
X133100Y769767D01*
X133683Y769600D01*
X134267Y769683D01*
X134767Y769933D01*
X135100Y770267D01*
G01X139200Y769600D02*
Y774600D01*
G01X144800Y772933D02*
Y769600D01*
G01Y774267D02*
X144633Y774350D01*
Y774517D01*
X144800Y774600D01*
X144967Y774517D01*
Y774350D01*
X144800Y774267D01*
G01X149900Y769600D02*
Y773850D01*
X150067Y774267D01*
X150400Y774517D01*
X150900Y774600D01*
X151400Y774433D01*
X151650Y774017D01*
G01X150650Y772600D02*
X148983D01*
G01X156000Y772933D02*
Y769600D01*
G01Y774267D02*
X155833Y774350D01*
Y774517D01*
X156000Y774600D01*
X156167Y774517D01*
Y774350D01*
X156000Y774267D01*
G01X162933Y772517D02*
X162350Y772850D01*
X161850Y772933D01*
X161183Y772767D01*
X160683Y772433D01*
X160350Y771850D01*
X160267Y771267D01*
X160350Y770683D01*
X160683Y770183D01*
X161183Y769767D01*
X161850Y769600D01*
X162433Y769767D01*
X162933Y770100D01*
G01X168700Y769600D02*
Y772933D01*
G01Y772350D02*
X168367Y772683D01*
X167867Y772850D01*
X167283Y772933D01*
X166700Y772767D01*
X166200Y772433D01*
X165867Y771933D01*
X165700Y771267D01*
X165867Y770600D01*
X166200Y770100D01*
X166700Y769767D01*
X167283Y769600D01*
X167867Y769683D01*
X168367Y769933D01*
X168700Y770267D01*
G01X172800Y774600D02*
Y769600D01*
G01X171633Y772933D02*
X173967D01*
G01X178400D02*
Y769600D01*
G01Y774267D02*
X178233Y774350D01*
Y774517D01*
X178400Y774600D01*
X178567Y774517D01*
Y774350D01*
X178400Y774267D01*
G01X184000Y769600D02*
X183500Y769683D01*
X183000Y770017D01*
X182667Y770600D01*
X182500Y771267D01*
X182667Y771933D01*
X183000Y772517D01*
X183500Y772850D01*
X184000Y772933D01*
X184500Y772850D01*
X185000Y772517D01*
X185333Y771933D01*
X185417Y771267D01*
X185333Y770600D01*
X185000Y770017D01*
X184500Y769683D01*
X184000Y769600D01*
G01X188183D02*
Y772933D01*
G01Y772100D02*
X188517Y772517D01*
X189017Y772850D01*
X189683Y772933D01*
X190267Y772850D01*
X190767Y772517D01*
X191017Y771933D01*
Y769600D01*
G01X202300D02*
Y772933D01*
G01Y772350D02*
X201967Y772683D01*
X201467Y772850D01*
X200883Y772933D01*
X200300Y772767D01*
X199800Y772433D01*
X199467Y771933D01*
X199300Y771267D01*
X199467Y770600D01*
X199800Y770100D01*
X200300Y769767D01*
X200883Y769600D01*
X201467Y769683D01*
X201967Y769933D01*
X202300Y770267D01*
G01X204983Y769600D02*
Y772933D01*
G01Y772100D02*
X205317Y772517D01*
X205817Y772850D01*
X206483Y772933D01*
X207067Y772850D01*
X207567Y772517D01*
X207817Y771933D01*
Y769600D01*
G01X213500Y774600D02*
Y769600D01*
G01Y770350D02*
X213167Y769933D01*
X212667Y769683D01*
X212083Y769600D01*
X211417Y769767D01*
X210917Y770183D01*
X210583Y770683D01*
X210500Y771267D01*
X210583Y771850D01*
X210917Y772350D01*
X211417Y772767D01*
X212083Y772933D01*
X212667Y772850D01*
X213083Y772683D01*
X213500Y772350D01*
G01X221533Y769600D02*
Y774600D01*
X223533D01*
X224200Y774350D01*
X224700Y773767D01*
X224867Y773100D01*
X224700Y772433D01*
X224283Y771933D01*
X223533Y771683D01*
X221533D01*
G01X227550Y771850D02*
X230217D01*
X229967Y772433D01*
X229550Y772767D01*
X228967Y772933D01*
X228383Y772850D01*
X227883Y772600D01*
X227550Y772017D01*
X227383Y771517D01*
Y771017D01*
X227550Y770517D01*
X227967Y770017D01*
X228467Y769683D01*
X229050Y769600D01*
X229633Y769767D01*
X230217Y770267D01*
G01X233233Y769600D02*
Y772933D01*
G01Y772267D02*
X233650Y772600D01*
X234067Y772850D01*
X234650Y772933D01*
X235067Y772850D01*
X235567Y772600D01*
G01X239500Y769600D02*
Y773850D01*
X239667Y774267D01*
X240000Y774517D01*
X240500Y774600D01*
X241000Y774433D01*
X241250Y774017D01*
G01X240250Y772600D02*
X238583D01*
G01X245600Y769600D02*
X245100Y769683D01*
X244600Y770017D01*
X244267Y770600D01*
X244100Y771267D01*
X244267Y771933D01*
X244600Y772517D01*
X245100Y772850D01*
X245600Y772933D01*
X246100Y772850D01*
X246600Y772517D01*
X246933Y771933D01*
X247017Y771267D01*
X246933Y770600D01*
X246600Y770017D01*
X246100Y769683D01*
X245600Y769600D01*
G01X250033D02*
Y772933D01*
G01Y772267D02*
X250450Y772600D01*
X250867Y772850D01*
X251450Y772933D01*
X251867Y772850D01*
X252367Y772600D01*
G01X254300Y769600D02*
Y772933D01*
G01Y772017D02*
X254550Y772433D01*
X254967Y772767D01*
X255550Y772933D01*
X256133Y772767D01*
X256550Y772433D01*
X256800Y772017D01*
Y769600D01*
G01Y772017D02*
X257050Y772433D01*
X257467Y772767D01*
X258050Y772933D01*
X258633Y772767D01*
X259050Y772433D01*
X259300Y771933D01*
Y769600D01*
G01X263900D02*
Y772933D01*
G01Y772350D02*
X263567Y772683D01*
X263067Y772850D01*
X262483Y772933D01*
X261900Y772767D01*
X261400Y772433D01*
X261067Y771933D01*
X260900Y771267D01*
X261067Y770600D01*
X261400Y770100D01*
X261900Y769767D01*
X262483Y769600D01*
X263067Y769683D01*
X263567Y769933D01*
X263900Y770267D01*
G01X266583Y769600D02*
Y772933D01*
G01Y772100D02*
X266917Y772517D01*
X267417Y772850D01*
X268083Y772933D01*
X268667Y772850D01*
X269167Y772517D01*
X269417Y771933D01*
Y769600D01*
G01X274933Y772517D02*
X274350Y772850D01*
X273850Y772933D01*
X273183Y772767D01*
X272683Y772433D01*
X272350Y771850D01*
X272267Y771267D01*
X272350Y770683D01*
X272683Y770183D01*
X273183Y769767D01*
X273850Y769600D01*
X274433Y769767D01*
X274933Y770100D01*
G01X277950Y771850D02*
X280617D01*
X280367Y772433D01*
X279950Y772767D01*
X279367Y772933D01*
X278783Y772850D01*
X278283Y772600D01*
X277950Y772017D01*
X277783Y771517D01*
Y771017D01*
X277950Y770517D01*
X278367Y770017D01*
X278867Y769683D01*
X279450Y769600D01*
X280033Y769767D01*
X280617Y770267D01*
G01X288650D02*
X289317Y769850D01*
X290067Y769600D01*
X290733D01*
X291400Y769850D01*
X291900Y770267D01*
X292150Y770850D01*
X291983Y771433D01*
X291567Y771933D01*
X290817Y772267D01*
X289817Y772433D01*
X289233Y772767D01*
X288983Y773350D01*
X289150Y773933D01*
X289567Y774350D01*
X290150Y774600D01*
X290733D01*
X291317Y774433D01*
X291817Y774017D01*
G01X294500Y767933D02*
Y772933D01*
G01Y772183D02*
X294917Y772600D01*
X295333Y772850D01*
X296000Y772933D01*
X296583Y772850D01*
X297167Y772433D01*
X297417Y771850D01*
X297500Y771267D01*
X297417Y770683D01*
X297167Y770100D01*
X296667Y769767D01*
X296000Y769600D01*
X295417Y769683D01*
X294833Y769933D01*
X294500Y770267D01*
G01X300350Y771850D02*
X303017D01*
X302767Y772433D01*
X302350Y772767D01*
X301767Y772933D01*
X301183Y772850D01*
X300683Y772600D01*
X300350Y772017D01*
X300183Y771517D01*
Y771017D01*
X300350Y770517D01*
X300767Y770017D01*
X301267Y769683D01*
X301850Y769600D01*
X302433Y769767D01*
X303017Y770267D01*
G01X308533Y772517D02*
X307950Y772850D01*
X307450Y772933D01*
X306783Y772767D01*
X306283Y772433D01*
X305950Y771850D01*
X305867Y771267D01*
X305950Y770683D01*
X306283Y770183D01*
X306783Y769767D01*
X307450Y769600D01*
X308033Y769767D01*
X308533Y770100D01*
G01X312800Y772933D02*
Y769600D01*
G01Y774267D02*
X312633Y774350D01*
Y774517D01*
X312800Y774600D01*
X312967Y774517D01*
Y774350D01*
X312800Y774267D01*
G01X317900Y769600D02*
Y773850D01*
X318067Y774267D01*
X318400Y774517D01*
X318900Y774600D01*
X319400Y774433D01*
X319650Y774017D01*
G01X318650Y772600D02*
X316983D01*
G01X324000Y772933D02*
Y769600D01*
G01Y774267D02*
X323833Y774350D01*
Y774517D01*
X324000Y774600D01*
X324167Y774517D01*
Y774350D01*
X324000Y774267D01*
G01X330933Y772517D02*
X330350Y772850D01*
X329850Y772933D01*
X329183Y772767D01*
X328683Y772433D01*
X328350Y771850D01*
X328267Y771267D01*
X328350Y770683D01*
X328683Y770183D01*
X329183Y769767D01*
X329850Y769600D01*
X330433Y769767D01*
X330933Y770100D01*
G01X336700Y769600D02*
Y772933D01*
G01Y772350D02*
X336367Y772683D01*
X335867Y772850D01*
X335283Y772933D01*
X334700Y772767D01*
X334200Y772433D01*
X333867Y771933D01*
X333700Y771267D01*
X333867Y770600D01*
X334200Y770100D01*
X334700Y769767D01*
X335283Y769600D01*
X335867Y769683D01*
X336367Y769933D01*
X336700Y770267D01*
G01X340800Y774600D02*
Y769600D01*
G01X339633Y772933D02*
X341967D01*
G01X346400D02*
Y769600D01*
G01Y774267D02*
X346233Y774350D01*
Y774517D01*
X346400Y774600D01*
X346567Y774517D01*
Y774350D01*
X346400Y774267D01*
G01X352000Y769600D02*
X351500Y769683D01*
X351000Y770017D01*
X350667Y770600D01*
X350500Y771267D01*
X350667Y771933D01*
X351000Y772517D01*
X351500Y772850D01*
X352000Y772933D01*
X352500Y772850D01*
X353000Y772517D01*
X353333Y771933D01*
X353417Y771267D01*
X353333Y770600D01*
X353000Y770017D01*
X352500Y769683D01*
X352000Y769600D01*
G01X356183D02*
Y772933D01*
G01Y772100D02*
X356517Y772517D01*
X357017Y772850D01*
X357683Y772933D01*
X358267Y772850D01*
X358767Y772517D01*
X359017Y771933D01*
Y769600D01*
G01X368300D02*
Y773850D01*
X368467Y774267D01*
X368800Y774517D01*
X369300Y774600D01*
X369800Y774433D01*
X370050Y774017D01*
G01X369050Y772600D02*
X367383D01*
G01X374400Y769600D02*
X373900Y769683D01*
X373400Y770017D01*
X373067Y770600D01*
X372900Y771267D01*
X373067Y771933D01*
X373400Y772517D01*
X373900Y772850D01*
X374400Y772933D01*
X374900Y772850D01*
X375400Y772517D01*
X375733Y771933D01*
X375817Y771267D01*
X375733Y770600D01*
X375400Y770017D01*
X374900Y769683D01*
X374400Y769600D01*
G01X378833D02*
Y772933D01*
G01Y772267D02*
X379250Y772600D01*
X379667Y772850D01*
X380250Y772933D01*
X380667Y772850D01*
X381167Y772600D01*
G01X389533Y769600D02*
Y774600D01*
X391617D01*
X392283Y774350D01*
X392700Y774017D01*
X392867Y773350D01*
X392700Y772683D01*
X392200Y772267D01*
X391617Y772017D01*
X389533D01*
G01X391617D02*
X392867Y769600D01*
G01X396800Y772933D02*
Y769600D01*
G01Y774267D02*
X396633Y774350D01*
Y774517D01*
X396800Y774600D01*
X396967Y774517D01*
Y774350D01*
X396800Y774267D01*
G01X401233Y768350D02*
X401817Y768017D01*
X402483Y767933D01*
X403067Y768017D01*
X403567Y768433D01*
X403900Y769017D01*
Y772933D01*
G01Y772267D02*
X403567Y772600D01*
X403067Y772850D01*
X402483Y772933D01*
X401817Y772767D01*
X401400Y772433D01*
X401067Y771850D01*
X400900Y771267D01*
X400983Y770767D01*
X401317Y770183D01*
X401817Y769767D01*
X402483Y769600D01*
X402983Y769683D01*
X403567Y770017D01*
X403900Y770350D01*
G01X408000Y772933D02*
Y769600D01*
G01Y774267D02*
X407833Y774350D01*
Y774517D01*
X408000Y774600D01*
X408167Y774517D01*
Y774350D01*
X408000Y774267D01*
G01X415100Y774600D02*
Y769600D01*
G01Y770350D02*
X414767Y769933D01*
X414267Y769683D01*
X413683Y769600D01*
X413017Y769767D01*
X412517Y770183D01*
X412183Y770683D01*
X412100Y771267D01*
X412183Y771850D01*
X412517Y772350D01*
X413017Y772767D01*
X413683Y772933D01*
X414267Y772850D01*
X414683Y772683D01*
X415100Y772350D01*
G01X423133Y769600D02*
Y774600D01*
X425133D01*
X425800Y774350D01*
X426300Y773767D01*
X426467Y773100D01*
X426300Y772433D01*
X425883Y771933D01*
X425133Y771683D01*
X423133D01*
G01X429233Y769600D02*
Y772933D01*
G01Y772267D02*
X429650Y772600D01*
X430067Y772850D01*
X430650Y772933D01*
X431067Y772850D01*
X431567Y772600D01*
G01X436000Y772933D02*
Y769600D01*
G01Y774267D02*
X435833Y774350D01*
Y774517D01*
X436000Y774600D01*
X436167Y774517D01*
Y774350D01*
X436000Y774267D01*
G01X440183Y769600D02*
Y772933D01*
G01Y772100D02*
X440517Y772517D01*
X441017Y772850D01*
X441683Y772933D01*
X442267Y772850D01*
X442767Y772517D01*
X443017Y771933D01*
Y769600D01*
G01X447200Y774600D02*
Y769600D01*
G01X446033Y772933D02*
X448367D01*
G01X451550Y771850D02*
X454217D01*
X453967Y772433D01*
X453550Y772767D01*
X452967Y772933D01*
X452383Y772850D01*
X451883Y772600D01*
X451550Y772017D01*
X451383Y771517D01*
Y771017D01*
X451550Y770517D01*
X451967Y770017D01*
X452467Y769683D01*
X453050Y769600D01*
X453633Y769767D01*
X454217Y770267D01*
G01X459900Y774600D02*
Y769600D01*
G01Y770350D02*
X459567Y769933D01*
X459067Y769683D01*
X458483Y769600D01*
X457817Y769767D01*
X457317Y770183D01*
X456983Y770683D01*
X456900Y771267D01*
X456983Y771850D01*
X457317Y772350D01*
X457817Y772767D01*
X458483Y772933D01*
X459067Y772850D01*
X459483Y772683D01*
X459900Y772350D01*
G01X470267Y772267D02*
X470600Y772517D01*
X470850Y772933D01*
X471017Y773517D01*
X470850Y774017D01*
X470517Y774350D01*
X469933Y774600D01*
X467683D01*
Y769600D01*
X470433D01*
X471017Y769933D01*
X471350Y770433D01*
X471517Y771017D01*
X471350Y771600D01*
X470850Y772100D01*
X470267Y772267D01*
X467683D01*
G01X475200Y769600D02*
X474700Y769683D01*
X474200Y770017D01*
X473867Y770600D01*
X473700Y771267D01*
X473867Y771933D01*
X474200Y772517D01*
X474700Y772850D01*
X475200Y772933D01*
X475700Y772850D01*
X476200Y772517D01*
X476533Y771933D01*
X476617Y771267D01*
X476533Y770600D01*
X476200Y770017D01*
X475700Y769683D01*
X475200Y769600D01*
G01X482300D02*
Y772933D01*
G01Y772350D02*
X481967Y772683D01*
X481467Y772850D01*
X480883Y772933D01*
X480300Y772767D01*
X479800Y772433D01*
X479467Y771933D01*
X479300Y771267D01*
X479467Y770600D01*
X479800Y770100D01*
X480300Y769767D01*
X480883Y769600D01*
X481467Y769683D01*
X481967Y769933D01*
X482300Y770267D01*
G01X485233Y769600D02*
Y772933D01*
G01Y772267D02*
X485650Y772600D01*
X486067Y772850D01*
X486650Y772933D01*
X487067Y772850D01*
X487567Y772600D01*
G01X493500Y774600D02*
Y769600D01*
G01Y770350D02*
X493167Y769933D01*
X492667Y769683D01*
X492083Y769600D01*
X491417Y769767D01*
X490917Y770183D01*
X490583Y770683D01*
X490500Y771267D01*
X490583Y771850D01*
X490917Y772350D01*
X491417Y772767D01*
X492083Y772933D01*
X492667Y772850D01*
X493083Y772683D01*
X493500Y772350D01*
G01X496350Y770183D02*
X496767Y769850D01*
X497350Y769600D01*
X497850D01*
X498350Y769767D01*
X498683Y770017D01*
X498850Y770350D01*
X498767Y770850D01*
X498433Y771100D01*
X496933Y771600D01*
X496600Y772183D01*
X496767Y772600D01*
X497100Y772850D01*
X497600Y772933D01*
X498100Y772850D01*
X498600Y772600D01*
G01X67000Y779433D02*
X66833Y779517D01*
Y779683D01*
X67000Y779767D01*
X67167Y779683D01*
Y779517D01*
X67000Y779433D01*
G01Y786333D02*
X66833Y786417D01*
Y786583D01*
X67000Y786667D01*
X67167Y786583D01*
Y786417D01*
X67000Y786333D01*
G01X71000Y783600D02*
X73000D01*
G01X72000D02*
Y778600D01*
G01X71000D02*
X73000D01*
G01X75933D02*
Y783600D01*
X77933D01*
X78600Y783350D01*
X79100Y782767D01*
X79267Y782100D01*
X79100Y781433D01*
X78683Y780933D01*
X77933Y780683D01*
X75933D01*
G01X85033Y783183D02*
X84533Y783433D01*
X83950Y783600D01*
X83283D01*
X82533Y783350D01*
X81950Y782933D01*
X81533Y782433D01*
X81200Y781600D01*
X81117Y780850D01*
X81283Y780100D01*
X81533Y779600D01*
X82033Y779100D01*
X82617Y778767D01*
X83200Y778600D01*
X83783D01*
X84367Y778767D01*
X84867Y779017D01*
X85283Y779350D01*
G01X87717Y780267D02*
X89883D01*
G01X92817Y780683D02*
X93400Y781267D01*
X93900Y781600D01*
X94567Y781767D01*
X95150Y781600D01*
X95567Y781267D01*
X95900Y780767D01*
X95983Y780183D01*
X95900Y779683D01*
X95567Y779183D01*
X95067Y778767D01*
X94483Y778600D01*
X93817Y778767D01*
X93233Y779267D01*
X92900Y780017D01*
X92817Y780850D01*
X92983Y781933D01*
X93233Y782517D01*
X93650Y783100D01*
X94233Y783517D01*
X94817Y783600D01*
X95400Y783433D01*
X95817Y783017D01*
G01X100000Y783600D02*
X99333Y783433D01*
X98833Y783017D01*
X98500Y782517D01*
X98250Y781850D01*
X98167Y781100D01*
X98250Y780350D01*
X98500Y779683D01*
X98833Y779183D01*
X99333Y778767D01*
X100000Y778600D01*
X100667Y778767D01*
X101167Y779183D01*
X101500Y779683D01*
X101750Y780350D01*
X101833Y781100D01*
X101750Y781850D01*
X101500Y782517D01*
X101167Y783017D01*
X100667Y783433D01*
X100000Y783600D01*
G01X105600Y778600D02*
Y783600D01*
X104600Y782600D01*
G01Y778600D02*
X106600D01*
G01X111200D02*
Y783600D01*
X110200Y782600D01*
G01Y778600D02*
X112200D01*
G01X122900Y781100D02*
X124567D01*
Y779600D01*
X124067Y779100D01*
X123483Y778767D01*
X122650Y778600D01*
X121817Y778767D01*
X121233Y779100D01*
X120733Y779600D01*
X120400Y780183D01*
X120233Y780850D01*
Y781433D01*
X120400Y781933D01*
X120733Y782517D01*
X121233Y783017D01*
X121733Y783350D01*
X122400Y783600D01*
X122983D01*
X123650Y783433D01*
X124150Y783100D01*
G01X126750Y780850D02*
X129417D01*
X129167Y781433D01*
X128750Y781767D01*
X128167Y781933D01*
X127583Y781850D01*
X127083Y781600D01*
X126750Y781017D01*
X126583Y780517D01*
Y780017D01*
X126750Y779517D01*
X127167Y779017D01*
X127667Y778683D01*
X128250Y778600D01*
X128833Y778767D01*
X129417Y779267D01*
G01X132183Y778600D02*
Y781933D01*
G01Y781100D02*
X132517Y781517D01*
X133017Y781850D01*
X133683Y781933D01*
X134267Y781850D01*
X134767Y781517D01*
X135017Y780933D01*
Y778600D01*
G01X137950Y780850D02*
X140617D01*
X140367Y781433D01*
X139950Y781767D01*
X139367Y781933D01*
X138783Y781850D01*
X138283Y781600D01*
X137950Y781017D01*
X137783Y780517D01*
Y780017D01*
X137950Y779517D01*
X138367Y779017D01*
X138867Y778683D01*
X139450Y778600D01*
X140033Y778767D01*
X140617Y779267D01*
G01X143633Y778600D02*
Y781933D01*
G01Y781267D02*
X144050Y781600D01*
X144467Y781850D01*
X145050Y781933D01*
X145467Y781850D01*
X145967Y781600D01*
G01X150400Y781933D02*
Y778600D01*
G01Y783267D02*
X150233Y783350D01*
Y783517D01*
X150400Y783600D01*
X150567Y783517D01*
Y783350D01*
X150400Y783267D01*
G01X157333Y781517D02*
X156750Y781850D01*
X156250Y781933D01*
X155583Y781767D01*
X155083Y781433D01*
X154750Y780850D01*
X154667Y780267D01*
X154750Y779683D01*
X155083Y779183D01*
X155583Y778767D01*
X156250Y778600D01*
X156833Y778767D01*
X157333Y779100D01*
G01X165533Y778600D02*
Y783600D01*
X167533D01*
X168200Y783350D01*
X168700Y782767D01*
X168867Y782100D01*
X168700Y781433D01*
X168283Y780933D01*
X167533Y780683D01*
X165533D01*
G01X171550Y780850D02*
X174217D01*
X173967Y781433D01*
X173550Y781767D01*
X172967Y781933D01*
X172383Y781850D01*
X171883Y781600D01*
X171550Y781017D01*
X171383Y780517D01*
Y780017D01*
X171550Y779517D01*
X171967Y779017D01*
X172467Y778683D01*
X173050Y778600D01*
X173633Y778767D01*
X174217Y779267D01*
G01X177233Y778600D02*
Y781933D01*
G01Y781267D02*
X177650Y781600D01*
X178067Y781850D01*
X178650Y781933D01*
X179067Y781850D01*
X179567Y781600D01*
G01X183500Y778600D02*
Y782850D01*
X183667Y783267D01*
X184000Y783517D01*
X184500Y783600D01*
X185000Y783433D01*
X185250Y783017D01*
G01X184250Y781600D02*
X182583D01*
G01X189600Y778600D02*
X189100Y778683D01*
X188600Y779017D01*
X188267Y779600D01*
X188100Y780267D01*
X188267Y780933D01*
X188600Y781517D01*
X189100Y781850D01*
X189600Y781933D01*
X190100Y781850D01*
X190600Y781517D01*
X190933Y780933D01*
X191017Y780267D01*
X190933Y779600D01*
X190600Y779017D01*
X190100Y778683D01*
X189600Y778600D01*
G01X194033D02*
Y781933D01*
G01Y781267D02*
X194450Y781600D01*
X194867Y781850D01*
X195450Y781933D01*
X195867Y781850D01*
X196367Y781600D01*
G01X198300Y778600D02*
Y781933D01*
G01Y781017D02*
X198550Y781433D01*
X198967Y781767D01*
X199550Y781933D01*
X200133Y781767D01*
X200550Y781433D01*
X200800Y781017D01*
Y778600D01*
G01Y781017D02*
X201050Y781433D01*
X201467Y781767D01*
X202050Y781933D01*
X202633Y781767D01*
X203050Y781433D01*
X203300Y780933D01*
Y778600D01*
G01X207900D02*
Y781933D01*
G01Y781350D02*
X207567Y781683D01*
X207067Y781850D01*
X206483Y781933D01*
X205900Y781767D01*
X205400Y781433D01*
X205067Y780933D01*
X204900Y780267D01*
X205067Y779600D01*
X205400Y779100D01*
X205900Y778767D01*
X206483Y778600D01*
X207067Y778683D01*
X207567Y778933D01*
X207900Y779267D01*
G01X210583Y778600D02*
Y781933D01*
G01Y781100D02*
X210917Y781517D01*
X211417Y781850D01*
X212083Y781933D01*
X212667Y781850D01*
X213167Y781517D01*
X213417Y780933D01*
Y778600D01*
G01X218933Y781517D02*
X218350Y781850D01*
X217850Y781933D01*
X217183Y781767D01*
X216683Y781433D01*
X216350Y780850D01*
X216267Y780267D01*
X216350Y779683D01*
X216683Y779183D01*
X217183Y778767D01*
X217850Y778600D01*
X218433Y778767D01*
X218933Y779100D01*
G01X221950Y780850D02*
X224617D01*
X224367Y781433D01*
X223950Y781767D01*
X223367Y781933D01*
X222783Y781850D01*
X222283Y781600D01*
X221950Y781017D01*
X221783Y780517D01*
Y780017D01*
X221950Y779517D01*
X222367Y779017D01*
X222867Y778683D01*
X223450Y778600D01*
X224033Y778767D01*
X224617Y779267D01*
G01X232650D02*
X233317Y778850D01*
X234067Y778600D01*
X234733D01*
X235400Y778850D01*
X235900Y779267D01*
X236150Y779850D01*
X235983Y780433D01*
X235567Y780933D01*
X234817Y781267D01*
X233817Y781433D01*
X233233Y781767D01*
X232983Y782350D01*
X233150Y782933D01*
X233567Y783350D01*
X234150Y783600D01*
X234733D01*
X235317Y783433D01*
X235817Y783017D01*
G01X238500Y776933D02*
Y781933D01*
G01Y781183D02*
X238917Y781600D01*
X239333Y781850D01*
X240000Y781933D01*
X240583Y781850D01*
X241167Y781433D01*
X241417Y780850D01*
X241500Y780267D01*
X241417Y779683D01*
X241167Y779100D01*
X240667Y778767D01*
X240000Y778600D01*
X239417Y778683D01*
X238833Y778933D01*
X238500Y779267D01*
G01X244350Y780850D02*
X247017D01*
X246767Y781433D01*
X246350Y781767D01*
X245767Y781933D01*
X245183Y781850D01*
X244683Y781600D01*
X244350Y781017D01*
X244183Y780517D01*
Y780017D01*
X244350Y779517D01*
X244767Y779017D01*
X245267Y778683D01*
X245850Y778600D01*
X246433Y778767D01*
X247017Y779267D01*
G01X252533Y781517D02*
X251950Y781850D01*
X251450Y781933D01*
X250783Y781767D01*
X250283Y781433D01*
X249950Y780850D01*
X249867Y780267D01*
X249950Y779683D01*
X250283Y779183D01*
X250783Y778767D01*
X251450Y778600D01*
X252033Y778767D01*
X252533Y779100D01*
G01X256800Y781933D02*
Y778600D01*
G01Y783267D02*
X256633Y783350D01*
Y783517D01*
X256800Y783600D01*
X256967Y783517D01*
Y783350D01*
X256800Y783267D01*
G01X261900Y778600D02*
Y782850D01*
X262067Y783267D01*
X262400Y783517D01*
X262900Y783600D01*
X263400Y783433D01*
X263650Y783017D01*
G01X262650Y781600D02*
X260983D01*
G01X268000Y781933D02*
Y778600D01*
G01Y783267D02*
X267833Y783350D01*
Y783517D01*
X268000Y783600D01*
X268167Y783517D01*
Y783350D01*
X268000Y783267D01*
G01X274933Y781517D02*
X274350Y781850D01*
X273850Y781933D01*
X273183Y781767D01*
X272683Y781433D01*
X272350Y780850D01*
X272267Y780267D01*
X272350Y779683D01*
X272683Y779183D01*
X273183Y778767D01*
X273850Y778600D01*
X274433Y778767D01*
X274933Y779100D01*
G01X280700Y778600D02*
Y781933D01*
G01Y781350D02*
X280367Y781683D01*
X279867Y781850D01*
X279283Y781933D01*
X278700Y781767D01*
X278200Y781433D01*
X277867Y780933D01*
X277700Y780267D01*
X277867Y779600D01*
X278200Y779100D01*
X278700Y778767D01*
X279283Y778600D01*
X279867Y778683D01*
X280367Y778933D01*
X280700Y779267D01*
G01X284800Y783600D02*
Y778600D01*
G01X283633Y781933D02*
X285967D01*
G01X290400D02*
Y778600D01*
G01Y783267D02*
X290233Y783350D01*
Y783517D01*
X290400Y783600D01*
X290567Y783517D01*
Y783350D01*
X290400Y783267D01*
G01X296000Y778600D02*
X295500Y778683D01*
X295000Y779017D01*
X294667Y779600D01*
X294500Y780267D01*
X294667Y780933D01*
X295000Y781517D01*
X295500Y781850D01*
X296000Y781933D01*
X296500Y781850D01*
X297000Y781517D01*
X297333Y780933D01*
X297417Y780267D01*
X297333Y779600D01*
X297000Y779017D01*
X296500Y778683D01*
X296000Y778600D01*
G01X300183D02*
Y781933D01*
G01Y781100D02*
X300517Y781517D01*
X301017Y781850D01*
X301683Y781933D01*
X302267Y781850D01*
X302767Y781517D01*
X303017Y780933D01*
Y778600D01*
G01X312300D02*
Y782850D01*
X312467Y783267D01*
X312800Y783517D01*
X313300Y783600D01*
X313800Y783433D01*
X314050Y783017D01*
G01X313050Y781600D02*
X311383D01*
G01X318400Y778600D02*
X317900Y778683D01*
X317400Y779017D01*
X317067Y779600D01*
X316900Y780267D01*
X317067Y780933D01*
X317400Y781517D01*
X317900Y781850D01*
X318400Y781933D01*
X318900Y781850D01*
X319400Y781517D01*
X319733Y780933D01*
X319817Y780267D01*
X319733Y779600D01*
X319400Y779017D01*
X318900Y778683D01*
X318400Y778600D01*
G01X322833D02*
Y781933D01*
G01Y781267D02*
X323250Y781600D01*
X323667Y781850D01*
X324250Y781933D01*
X324667Y781850D01*
X325167Y781600D01*
G01X333533Y778600D02*
Y783600D01*
X335533D01*
X336200Y783350D01*
X336700Y782767D01*
X336867Y782100D01*
X336700Y781433D01*
X336283Y780933D01*
X335533Y780683D01*
X333533D01*
G01X339633Y778600D02*
Y781933D01*
G01Y781267D02*
X340050Y781600D01*
X340467Y781850D01*
X341050Y781933D01*
X341467Y781850D01*
X341967Y781600D01*
G01X346400Y781933D02*
Y778600D01*
G01Y783267D02*
X346233Y783350D01*
Y783517D01*
X346400Y783600D01*
X346567Y783517D01*
Y783350D01*
X346400Y783267D01*
G01X350583Y778600D02*
Y781933D01*
G01Y781100D02*
X350917Y781517D01*
X351417Y781850D01*
X352083Y781933D01*
X352667Y781850D01*
X353167Y781517D01*
X353417Y780933D01*
Y778600D01*
G01X357600Y783600D02*
Y778600D01*
G01X356433Y781933D02*
X358767D01*
G01X361950Y780850D02*
X364617D01*
X364367Y781433D01*
X363950Y781767D01*
X363367Y781933D01*
X362783Y781850D01*
X362283Y781600D01*
X361950Y781017D01*
X361783Y780517D01*
Y780017D01*
X361950Y779517D01*
X362367Y779017D01*
X362867Y778683D01*
X363450Y778600D01*
X364033Y778767D01*
X364617Y779267D01*
G01X370300Y783600D02*
Y778600D01*
G01Y779350D02*
X369967Y778933D01*
X369467Y778683D01*
X368883Y778600D01*
X368217Y778767D01*
X367717Y779183D01*
X367383Y779683D01*
X367300Y780267D01*
X367383Y780850D01*
X367717Y781350D01*
X368217Y781767D01*
X368883Y781933D01*
X369467Y781850D01*
X369883Y781683D01*
X370300Y781350D01*
G01X380667Y781267D02*
X381000Y781517D01*
X381250Y781933D01*
X381417Y782517D01*
X381250Y783017D01*
X380917Y783350D01*
X380333Y783600D01*
X378083D01*
Y778600D01*
X380833D01*
X381417Y778933D01*
X381750Y779433D01*
X381917Y780017D01*
X381750Y780600D01*
X381250Y781100D01*
X380667Y781267D01*
X378083D01*
G01X385600Y778600D02*
X385100Y778683D01*
X384600Y779017D01*
X384267Y779600D01*
X384100Y780267D01*
X384267Y780933D01*
X384600Y781517D01*
X385100Y781850D01*
X385600Y781933D01*
X386100Y781850D01*
X386600Y781517D01*
X386933Y780933D01*
X387017Y780267D01*
X386933Y779600D01*
X386600Y779017D01*
X386100Y778683D01*
X385600Y778600D01*
G01X392700D02*
Y781933D01*
G01Y781350D02*
X392367Y781683D01*
X391867Y781850D01*
X391283Y781933D01*
X390700Y781767D01*
X390200Y781433D01*
X389867Y780933D01*
X389700Y780267D01*
X389867Y779600D01*
X390200Y779100D01*
X390700Y778767D01*
X391283Y778600D01*
X391867Y778683D01*
X392367Y778933D01*
X392700Y779267D01*
G01X395633Y778600D02*
Y781933D01*
G01Y781267D02*
X396050Y781600D01*
X396467Y781850D01*
X397050Y781933D01*
X397467Y781850D01*
X397967Y781600D01*
G01X403900Y783600D02*
Y778600D01*
G01Y779350D02*
X403567Y778933D01*
X403067Y778683D01*
X402483Y778600D01*
X401817Y778767D01*
X401317Y779183D01*
X400983Y779683D01*
X400900Y780267D01*
X400983Y780850D01*
X401317Y781350D01*
X401817Y781767D01*
X402483Y781933D01*
X403067Y781850D01*
X403483Y781683D01*
X403900Y781350D01*
G01X406750Y779183D02*
X407167Y778850D01*
X407750Y778600D01*
X408250D01*
X408750Y778767D01*
X409083Y779017D01*
X409250Y779350D01*
X409167Y779850D01*
X408833Y780100D01*
X407333Y780600D01*
X407000Y781183D01*
X407167Y781600D01*
X407500Y781850D01*
X408000Y781933D01*
X408500Y781850D01*
X409000Y781600D01*
G01X71000Y791500D02*
X73000D01*
G01X72000D02*
Y786500D01*
G01X71000D02*
X73000D01*
G01X75933D02*
Y791500D01*
X77933D01*
X78600Y791250D01*
X79100Y790667D01*
X79267Y790000D01*
X79100Y789333D01*
X78683Y788833D01*
X77933Y788583D01*
X75933D01*
G01X85033Y791083D02*
X84533Y791333D01*
X83950Y791500D01*
X83283D01*
X82533Y791250D01*
X81950Y790833D01*
X81533Y790333D01*
X81200Y789500D01*
X81117Y788750D01*
X81283Y788000D01*
X81533Y787500D01*
X82033Y787000D01*
X82617Y786667D01*
X83200Y786500D01*
X83783D01*
X84367Y786667D01*
X84867Y786917D01*
X85283Y787250D01*
G01X87717Y788167D02*
X89883D01*
G01X92317Y786500D02*
X94400Y791500D01*
X96483Y786500D01*
G01X95733Y788250D02*
X93067D01*
G01X98917Y788167D02*
X101083D01*
G01X104017Y788583D02*
X104600Y789167D01*
X105100Y789500D01*
X105767Y789667D01*
X106350Y789500D01*
X106767Y789167D01*
X107100Y788667D01*
X107183Y788083D01*
X107100Y787583D01*
X106767Y787083D01*
X106267Y786667D01*
X105683Y786500D01*
X105017Y786667D01*
X104433Y787167D01*
X104100Y787917D01*
X104017Y788750D01*
X104183Y789833D01*
X104433Y790417D01*
X104850Y791000D01*
X105433Y791417D01*
X106017Y791500D01*
X106600Y791333D01*
X107017Y790917D01*
G01X111200Y791500D02*
X110533Y791333D01*
X110033Y790917D01*
X109700Y790417D01*
X109450Y789750D01*
X109367Y789000D01*
X109450Y788250D01*
X109700Y787583D01*
X110033Y787083D01*
X110533Y786667D01*
X111200Y786500D01*
X111867Y786667D01*
X112367Y787083D01*
X112700Y787583D01*
X112950Y788250D01*
X113033Y789000D01*
X112950Y789750D01*
X112700Y790417D01*
X112367Y790917D01*
X111867Y791333D01*
X111200Y791500D01*
G01X116800D02*
X116133Y791333D01*
X115633Y790917D01*
X115300Y790417D01*
X115050Y789750D01*
X114967Y789000D01*
X115050Y788250D01*
X115300Y787583D01*
X115633Y787083D01*
X116133Y786667D01*
X116800Y786500D01*
X117467Y786667D01*
X117967Y787083D01*
X118300Y787583D01*
X118550Y788250D01*
X118633Y789000D01*
X118550Y789750D01*
X118300Y790417D01*
X117967Y790917D01*
X117467Y791333D01*
X116800Y791500D01*
G01X125917Y786500D02*
X128000Y791500D01*
X130083Y786500D01*
G01X129333Y788250D02*
X126667D01*
G01X134933Y789417D02*
X134350Y789750D01*
X133850Y789833D01*
X133183Y789667D01*
X132683Y789333D01*
X132350Y788750D01*
X132267Y788167D01*
X132350Y787583D01*
X132683Y787083D01*
X133183Y786667D01*
X133850Y786500D01*
X134433Y786667D01*
X134933Y787000D01*
G01X140533Y789417D02*
X139950Y789750D01*
X139450Y789833D01*
X138783Y789667D01*
X138283Y789333D01*
X137950Y788750D01*
X137867Y788167D01*
X137950Y787583D01*
X138283Y787083D01*
X138783Y786667D01*
X139450Y786500D01*
X140033Y786667D01*
X140533Y787000D01*
G01X143550Y788750D02*
X146217D01*
X145967Y789333D01*
X145550Y789667D01*
X144967Y789833D01*
X144383Y789750D01*
X143883Y789500D01*
X143550Y788917D01*
X143383Y788417D01*
Y787917D01*
X143550Y787417D01*
X143967Y786917D01*
X144467Y786583D01*
X145050Y786500D01*
X145633Y786667D01*
X146217Y787167D01*
G01X148900Y784833D02*
Y789833D01*
G01Y789083D02*
X149317Y789500D01*
X149733Y789750D01*
X150400Y789833D01*
X150983Y789750D01*
X151567Y789333D01*
X151817Y788750D01*
X151900Y788167D01*
X151817Y787583D01*
X151567Y787000D01*
X151067Y786667D01*
X150400Y786500D01*
X149817Y786583D01*
X149233Y786833D01*
X148900Y787167D01*
G01X156000Y791500D02*
Y786500D01*
G01X154833Y789833D02*
X157167D01*
G01X163100Y786500D02*
Y789833D01*
G01Y789250D02*
X162767Y789583D01*
X162267Y789750D01*
X161683Y789833D01*
X161100Y789667D01*
X160600Y789333D01*
X160267Y788833D01*
X160100Y788167D01*
X160267Y787500D01*
X160600Y787000D01*
X161100Y786667D01*
X161683Y786500D01*
X162267Y786583D01*
X162767Y786833D01*
X163100Y787167D01*
G01X165700Y786500D02*
Y791500D01*
G01Y789000D02*
X166117Y789500D01*
X166617Y789750D01*
X167117Y789833D01*
X167867Y789667D01*
X168367Y789333D01*
X168700Y788750D01*
Y788083D01*
X168533Y787417D01*
X168200Y786917D01*
X167617Y786583D01*
X167117Y786500D01*
X166617Y786583D01*
X166117Y786833D01*
X165700Y787250D01*
G01X172800Y789833D02*
Y786500D01*
G01Y791167D02*
X172633Y791250D01*
Y791417D01*
X172800Y791500D01*
X172967Y791417D01*
Y791250D01*
X172800Y791167D01*
G01X178400Y786500D02*
Y791500D01*
G01X184000Y789833D02*
Y786500D01*
G01Y791167D02*
X183833Y791250D01*
Y791417D01*
X184000Y791500D01*
X184167Y791417D01*
Y791250D01*
X184000Y791167D01*
G01X189600Y791500D02*
Y786500D01*
G01X188433Y789833D02*
X190767D01*
G01X193450Y785000D02*
X193950Y784833D01*
X194617Y785000D01*
X195033Y785333D01*
X195367Y785750D01*
X195867Y787083D01*
X196950Y789833D01*
G01X194283D02*
X195867Y787083D01*
G01X206400Y786500D02*
X205900Y786583D01*
X205400Y786917D01*
X205067Y787500D01*
X204900Y788167D01*
X205067Y788833D01*
X205400Y789417D01*
X205900Y789750D01*
X206400Y789833D01*
X206900Y789750D01*
X207400Y789417D01*
X207733Y788833D01*
X207817Y788167D01*
X207733Y787500D01*
X207400Y786917D01*
X206900Y786583D01*
X206400Y786500D01*
G01X211500D02*
Y790750D01*
X211667Y791167D01*
X212000Y791417D01*
X212500Y791500D01*
X213000Y791333D01*
X213250Y790917D01*
G01X212250Y789500D02*
X210583D01*
G01X221533Y786500D02*
Y791500D01*
X223533D01*
X224200Y791250D01*
X224700Y790667D01*
X224867Y790000D01*
X224700Y789333D01*
X224283Y788833D01*
X223533Y788583D01*
X221533D01*
G01X227633Y786500D02*
Y789833D01*
G01Y789167D02*
X228050Y789500D01*
X228467Y789750D01*
X229050Y789833D01*
X229467Y789750D01*
X229967Y789500D01*
G01X234400Y789833D02*
Y786500D01*
G01Y791167D02*
X234233Y791250D01*
Y791417D01*
X234400Y791500D01*
X234567Y791417D01*
Y791250D01*
X234400Y791167D01*
G01X238583Y786500D02*
Y789833D01*
G01Y789000D02*
X238917Y789417D01*
X239417Y789750D01*
X240083Y789833D01*
X240667Y789750D01*
X241167Y789417D01*
X241417Y788833D01*
Y786500D01*
G01X245600Y791500D02*
Y786500D01*
G01X244433Y789833D02*
X246767D01*
G01X249950Y788750D02*
X252617D01*
X252367Y789333D01*
X251950Y789667D01*
X251367Y789833D01*
X250783Y789750D01*
X250283Y789500D01*
X249950Y788917D01*
X249783Y788417D01*
Y787917D01*
X249950Y787417D01*
X250367Y786917D01*
X250867Y786583D01*
X251450Y786500D01*
X252033Y786667D01*
X252617Y787167D01*
G01X258300Y791500D02*
Y786500D01*
G01Y787250D02*
X257967Y786833D01*
X257467Y786583D01*
X256883Y786500D01*
X256217Y786667D01*
X255717Y787083D01*
X255383Y787583D01*
X255300Y788167D01*
X255383Y788750D01*
X255717Y789250D01*
X256217Y789667D01*
X256883Y789833D01*
X257467Y789750D01*
X257883Y789583D01*
X258300Y789250D01*
G01X268667Y789167D02*
X269000Y789417D01*
X269250Y789833D01*
X269417Y790417D01*
X269250Y790917D01*
X268917Y791250D01*
X268333Y791500D01*
X266083D01*
Y786500D01*
X268833D01*
X269417Y786833D01*
X269750Y787333D01*
X269917Y787917D01*
X269750Y788500D01*
X269250Y789000D01*
X268667Y789167D01*
X266083D01*
G01X273600Y786500D02*
X273100Y786583D01*
X272600Y786917D01*
X272267Y787500D01*
X272100Y788167D01*
X272267Y788833D01*
X272600Y789417D01*
X273100Y789750D01*
X273600Y789833D01*
X274100Y789750D01*
X274600Y789417D01*
X274933Y788833D01*
X275017Y788167D01*
X274933Y787500D01*
X274600Y786917D01*
X274100Y786583D01*
X273600Y786500D01*
G01X280700D02*
Y789833D01*
G01Y789250D02*
X280367Y789583D01*
X279867Y789750D01*
X279283Y789833D01*
X278700Y789667D01*
X278200Y789333D01*
X277867Y788833D01*
X277700Y788167D01*
X277867Y787500D01*
X278200Y787000D01*
X278700Y786667D01*
X279283Y786500D01*
X279867Y786583D01*
X280367Y786833D01*
X280700Y787167D01*
G01X283633Y786500D02*
Y789833D01*
G01Y789167D02*
X284050Y789500D01*
X284467Y789750D01*
X285050Y789833D01*
X285467Y789750D01*
X285967Y789500D01*
G01X291900Y791500D02*
Y786500D01*
G01Y787250D02*
X291567Y786833D01*
X291067Y786583D01*
X290483Y786500D01*
X289817Y786667D01*
X289317Y787083D01*
X288983Y787583D01*
X288900Y788167D01*
X288983Y788750D01*
X289317Y789250D01*
X289817Y789667D01*
X290483Y789833D01*
X291067Y789750D01*
X291483Y789583D01*
X291900Y789250D01*
G01X294750Y787083D02*
X295167Y786750D01*
X295750Y786500D01*
X296250D01*
X296750Y786667D01*
X297083Y786917D01*
X297250Y787250D01*
X297167Y787750D01*
X296833Y788000D01*
X295333Y788500D01*
X295000Y789083D01*
X295167Y789500D01*
X295500Y789750D01*
X296000Y789833D01*
X296500Y789750D01*
X297000Y789500D01*
G01X57833Y806500D02*
Y811500D01*
X59833D01*
X60500Y811250D01*
X61000Y810667D01*
X61167Y810000D01*
X61000Y809333D01*
X60583Y808833D01*
X59833Y808583D01*
X57833D01*
G01X65100Y806500D02*
Y811500D01*
G01X69450Y808750D02*
X72117D01*
X71867Y809333D01*
X71450Y809667D01*
X70867Y809833D01*
X70283Y809750D01*
X69783Y809500D01*
X69450Y808917D01*
X69283Y808417D01*
Y807917D01*
X69450Y807417D01*
X69867Y806917D01*
X70367Y806583D01*
X70950Y806500D01*
X71533Y806667D01*
X72117Y807167D01*
G01X77800Y806500D02*
Y809833D01*
G01Y809250D02*
X77467Y809583D01*
X76967Y809750D01*
X76383Y809833D01*
X75800Y809667D01*
X75300Y809333D01*
X74967Y808833D01*
X74800Y808167D01*
X74967Y807500D01*
X75300Y807000D01*
X75800Y806667D01*
X76383Y806500D01*
X76967Y806583D01*
X77467Y806833D01*
X77800Y807167D01*
G01X80650Y807083D02*
X81067Y806750D01*
X81650Y806500D01*
X82150D01*
X82650Y806667D01*
X82983Y806917D01*
X83150Y807250D01*
X83067Y807750D01*
X82733Y808000D01*
X81233Y808500D01*
X80900Y809083D01*
X81067Y809500D01*
X81400Y809750D01*
X81900Y809833D01*
X82400Y809750D01*
X82900Y809500D01*
G01X86250Y808750D02*
X88917D01*
X88667Y809333D01*
X88250Y809667D01*
X87667Y809833D01*
X87083Y809750D01*
X86583Y809500D01*
X86250Y808917D01*
X86083Y808417D01*
Y807917D01*
X86250Y807417D01*
X86667Y806917D01*
X87167Y806583D01*
X87750Y806500D01*
X88333Y806667D01*
X88917Y807167D01*
G01X98200Y806500D02*
Y810750D01*
X98367Y811167D01*
X98700Y811417D01*
X99200Y811500D01*
X99700Y811333D01*
X99950Y810917D01*
G01X98950Y809500D02*
X97283D01*
G01X104300Y806500D02*
X103800Y806583D01*
X103300Y806917D01*
X102967Y807500D01*
X102800Y808167D01*
X102967Y808833D01*
X103300Y809417D01*
X103800Y809750D01*
X104300Y809833D01*
X104800Y809750D01*
X105300Y809417D01*
X105633Y808833D01*
X105717Y808167D01*
X105633Y807500D01*
X105300Y806917D01*
X104800Y806583D01*
X104300Y806500D01*
G01X109900D02*
Y811500D01*
G01X115500Y806500D02*
Y811500D01*
G01X121100Y806500D02*
X120600Y806583D01*
X120100Y806917D01*
X119767Y807500D01*
X119600Y808167D01*
X119767Y808833D01*
X120100Y809417D01*
X120600Y809750D01*
X121100Y809833D01*
X121600Y809750D01*
X122100Y809417D01*
X122433Y808833D01*
X122517Y808167D01*
X122433Y807500D01*
X122100Y806917D01*
X121600Y806583D01*
X121100Y806500D01*
G01X124617Y809833D02*
X125617Y806500D01*
X126700Y809833D01*
X127783Y806500D01*
X128783Y809833D01*
G01X137900Y811500D02*
Y806500D01*
G01X136733Y809833D02*
X139067D01*
G01X142083Y806500D02*
Y811500D01*
G01Y809083D02*
X142500Y809500D01*
X142917Y809750D01*
X143583Y809833D01*
X144083Y809750D01*
X144667Y809417D01*
X144917Y808917D01*
Y806500D01*
G01X147850Y808750D02*
X150517D01*
X150267Y809333D01*
X149850Y809667D01*
X149267Y809833D01*
X148683Y809750D01*
X148183Y809500D01*
X147850Y808917D01*
X147683Y808417D01*
Y807917D01*
X147850Y807417D01*
X148267Y806917D01*
X148767Y806583D01*
X149350Y806500D01*
X149933Y806667D01*
X150517Y807167D01*
G01X159050Y807083D02*
X159467Y806750D01*
X160050Y806500D01*
X160550D01*
X161050Y806667D01*
X161383Y806917D01*
X161550Y807250D01*
X161467Y807750D01*
X161133Y808000D01*
X159633Y808500D01*
X159300Y809083D01*
X159467Y809500D01*
X159800Y809750D01*
X160300Y809833D01*
X160800Y809750D01*
X161300Y809500D01*
G01X164400Y804833D02*
Y809833D01*
G01Y809083D02*
X164817Y809500D01*
X165233Y809750D01*
X165900Y809833D01*
X166483Y809750D01*
X167067Y809333D01*
X167317Y808750D01*
X167400Y808167D01*
X167317Y807583D01*
X167067Y807000D01*
X166567Y806667D01*
X165900Y806500D01*
X165317Y806583D01*
X164733Y806833D01*
X164400Y807167D01*
G01X170250Y808750D02*
X172917D01*
X172667Y809333D01*
X172250Y809667D01*
X171667Y809833D01*
X171083Y809750D01*
X170583Y809500D01*
X170250Y808917D01*
X170083Y808417D01*
Y807917D01*
X170250Y807417D01*
X170667Y806917D01*
X171167Y806583D01*
X171750Y806500D01*
X172333Y806667D01*
X172917Y807167D01*
G01X178433Y809417D02*
X177850Y809750D01*
X177350Y809833D01*
X176683Y809667D01*
X176183Y809333D01*
X175850Y808750D01*
X175767Y808167D01*
X175850Y807583D01*
X176183Y807083D01*
X176683Y806667D01*
X177350Y806500D01*
X177933Y806667D01*
X178433Y807000D01*
G01X182700Y809833D02*
Y806500D01*
G01Y811167D02*
X182533Y811250D01*
Y811417D01*
X182700Y811500D01*
X182867Y811417D01*
Y811250D01*
X182700Y811167D01*
G01X187800Y806500D02*
Y810750D01*
X187967Y811167D01*
X188300Y811417D01*
X188800Y811500D01*
X189300Y811333D01*
X189550Y810917D01*
G01X188550Y809500D02*
X186883D01*
G01X193900Y809833D02*
Y806500D01*
G01Y811167D02*
X193733Y811250D01*
Y811417D01*
X193900Y811500D01*
X194067Y811417D01*
Y811250D01*
X193900Y811167D01*
G01X200833Y809417D02*
X200250Y809750D01*
X199750Y809833D01*
X199083Y809667D01*
X198583Y809333D01*
X198250Y808750D01*
X198167Y808167D01*
X198250Y807583D01*
X198583Y807083D01*
X199083Y806667D01*
X199750Y806500D01*
X200333Y806667D01*
X200833Y807000D01*
G01X206600Y806500D02*
Y809833D01*
G01Y809250D02*
X206267Y809583D01*
X205767Y809750D01*
X205183Y809833D01*
X204600Y809667D01*
X204100Y809333D01*
X203767Y808833D01*
X203600Y808167D01*
X203767Y807500D01*
X204100Y807000D01*
X204600Y806667D01*
X205183Y806500D01*
X205767Y806583D01*
X206267Y806833D01*
X206600Y807167D01*
G01X210700Y811500D02*
Y806500D01*
G01X209533Y809833D02*
X211867D01*
G01X216300D02*
Y806500D01*
G01Y811167D02*
X216133Y811250D01*
Y811417D01*
X216300Y811500D01*
X216467Y811417D01*
Y811250D01*
X216300Y811167D01*
G01X221900Y806500D02*
X221400Y806583D01*
X220900Y806917D01*
X220567Y807500D01*
X220400Y808167D01*
X220567Y808833D01*
X220900Y809417D01*
X221400Y809750D01*
X221900Y809833D01*
X222400Y809750D01*
X222900Y809417D01*
X223233Y808833D01*
X223317Y808167D01*
X223233Y807500D01*
X222900Y806917D01*
X222400Y806583D01*
X221900Y806500D01*
G01X226083D02*
Y809833D01*
G01Y809000D02*
X226417Y809417D01*
X226917Y809750D01*
X227583Y809833D01*
X228167Y809750D01*
X228667Y809417D01*
X228917Y808833D01*
Y806500D01*
G01X240200Y811500D02*
Y806500D01*
G01Y807250D02*
X239867Y806833D01*
X239367Y806583D01*
X238783Y806500D01*
X238117Y806667D01*
X237617Y807083D01*
X237283Y807583D01*
X237200Y808167D01*
X237283Y808750D01*
X237617Y809250D01*
X238117Y809667D01*
X238783Y809833D01*
X239367Y809750D01*
X239783Y809583D01*
X240200Y809250D01*
G01X244300Y806500D02*
X243800Y806583D01*
X243300Y806917D01*
X242967Y807500D01*
X242800Y808167D01*
X242967Y808833D01*
X243300Y809417D01*
X243800Y809750D01*
X244300Y809833D01*
X244800Y809750D01*
X245300Y809417D01*
X245633Y808833D01*
X245717Y808167D01*
X245633Y807500D01*
X245300Y806917D01*
X244800Y806583D01*
X244300Y806500D01*
G01X251233Y809417D02*
X250650Y809750D01*
X250150Y809833D01*
X249483Y809667D01*
X248983Y809333D01*
X248650Y808750D01*
X248567Y808167D01*
X248650Y807583D01*
X248983Y807083D01*
X249483Y806667D01*
X250150Y806500D01*
X250733Y806667D01*
X251233Y807000D01*
G01X254083Y809833D02*
Y807500D01*
X254417Y806917D01*
X254917Y806583D01*
X255500Y806500D01*
X256083Y806583D01*
X256583Y806917D01*
X256917Y807500D01*
G01Y806500D02*
Y809833D01*
G01X258600Y806500D02*
Y809833D01*
G01Y808917D02*
X258850Y809333D01*
X259267Y809667D01*
X259850Y809833D01*
X260433Y809667D01*
X260850Y809333D01*
X261100Y808917D01*
Y806500D01*
G01Y808917D02*
X261350Y809333D01*
X261767Y809667D01*
X262350Y809833D01*
X262933Y809667D01*
X263350Y809333D01*
X263600Y808833D01*
Y806500D01*
G01X265450Y808750D02*
X268117D01*
X267867Y809333D01*
X267450Y809667D01*
X266867Y809833D01*
X266283Y809750D01*
X265783Y809500D01*
X265450Y808917D01*
X265283Y808417D01*
Y807917D01*
X265450Y807417D01*
X265867Y806917D01*
X266367Y806583D01*
X266950Y806500D01*
X267533Y806667D01*
X268117Y807167D01*
G01X270883Y806500D02*
Y809833D01*
G01Y809000D02*
X271217Y809417D01*
X271717Y809750D01*
X272383Y809833D01*
X272967Y809750D01*
X273467Y809417D01*
X273717Y808833D01*
Y806500D01*
G01X277900Y811500D02*
Y806500D01*
G01X276733Y809833D02*
X279067D01*
G01X282250Y807083D02*
X282667Y806750D01*
X283250Y806500D01*
X283750D01*
X284250Y806667D01*
X284583Y806917D01*
X284750Y807250D01*
X284667Y807750D01*
X284333Y808000D01*
X282833Y808500D01*
X282500Y809083D01*
X282667Y809500D01*
X283000Y809750D01*
X283500Y809833D01*
X284000Y809750D01*
X284500Y809500D01*
G01X294700Y809833D02*
Y806500D01*
G01Y811167D02*
X294533Y811250D01*
Y811417D01*
X294700Y811500D01*
X294867Y811417D01*
Y811250D01*
X294700Y811167D01*
G01X298883Y806500D02*
Y809833D01*
G01Y809000D02*
X299217Y809417D01*
X299717Y809750D01*
X300383Y809833D01*
X300967Y809750D01*
X301467Y809417D01*
X301717Y808833D01*
Y806500D01*
G01X312833Y809417D02*
X312250Y809750D01*
X311750Y809833D01*
X311083Y809667D01*
X310583Y809333D01*
X310250Y808750D01*
X310167Y808167D01*
X310250Y807583D01*
X310583Y807083D01*
X311083Y806667D01*
X311750Y806500D01*
X312333Y806667D01*
X312833Y807000D01*
G01X317100Y806500D02*
Y811500D01*
G01X324200Y806500D02*
Y809833D01*
G01Y809250D02*
X323867Y809583D01*
X323367Y809750D01*
X322783Y809833D01*
X322200Y809667D01*
X321700Y809333D01*
X321367Y808833D01*
X321200Y808167D01*
X321367Y807500D01*
X321700Y807000D01*
X322200Y806667D01*
X322783Y806500D01*
X323367Y806583D01*
X323867Y806833D01*
X324200Y807167D01*
G01X327050Y807083D02*
X327467Y806750D01*
X328050Y806500D01*
X328550D01*
X329050Y806667D01*
X329383Y806917D01*
X329550Y807250D01*
X329467Y807750D01*
X329133Y808000D01*
X327633Y808500D01*
X327300Y809083D01*
X327467Y809500D01*
X327800Y809750D01*
X328300Y809833D01*
X328800Y809750D01*
X329300Y809500D01*
G01X332650Y807083D02*
X333067Y806750D01*
X333650Y806500D01*
X334150D01*
X334650Y806667D01*
X334983Y806917D01*
X335150Y807250D01*
X335067Y807750D01*
X334733Y808000D01*
X333233Y808500D01*
X332900Y809083D01*
X333067Y809500D01*
X333400Y809750D01*
X333900Y809833D01*
X334400Y809750D01*
X334900Y809500D01*
G01X343517Y810667D02*
X344017Y811167D01*
X344600Y811417D01*
X345267Y811500D01*
X346100Y811333D01*
X346683Y810917D01*
X346850Y810417D01*
X346767Y809917D01*
X346433Y809500D01*
X344767Y808667D01*
X344017Y808083D01*
X343517Y807250D01*
X343350Y806500D01*
X346850D01*
G01X357800D02*
Y809833D01*
G01Y809250D02*
X357467Y809583D01*
X356967Y809750D01*
X356383Y809833D01*
X355800Y809667D01*
X355300Y809333D01*
X354967Y808833D01*
X354800Y808167D01*
X354967Y807500D01*
X355300Y807000D01*
X355800Y806667D01*
X356383Y806500D01*
X356967Y806583D01*
X357467Y806833D01*
X357800Y807167D01*
G01X360483Y806500D02*
Y809833D01*
G01Y809000D02*
X360817Y809417D01*
X361317Y809750D01*
X361983Y809833D01*
X362567Y809750D01*
X363067Y809417D01*
X363317Y808833D01*
Y806500D01*
G01X369000Y811500D02*
Y806500D01*
G01Y807250D02*
X368667Y806833D01*
X368167Y806583D01*
X367583Y806500D01*
X366917Y806667D01*
X366417Y807083D01*
X366083Y807583D01*
X366000Y808167D01*
X366083Y808750D01*
X366417Y809250D01*
X366917Y809667D01*
X367583Y809833D01*
X368167Y809750D01*
X368583Y809583D01*
X369000Y809250D01*
G01X378700Y811500D02*
Y806500D01*
G01X377533Y809833D02*
X379867D01*
G01X382883Y806500D02*
Y811500D01*
G01Y809083D02*
X383300Y809500D01*
X383717Y809750D01*
X384383Y809833D01*
X384883Y809750D01*
X385467Y809417D01*
X385717Y808917D01*
Y806500D01*
G01X388650Y808750D02*
X391317D01*
X391067Y809333D01*
X390650Y809667D01*
X390067Y809833D01*
X389483Y809750D01*
X388983Y809500D01*
X388650Y808917D01*
X388483Y808417D01*
Y807917D01*
X388650Y807417D01*
X389067Y806917D01*
X389567Y806583D01*
X390150Y806500D01*
X390733Y806667D01*
X391317Y807167D01*
G01X401100Y806500D02*
Y811500D01*
G01X408200Y806500D02*
Y809833D01*
G01Y809250D02*
X407867Y809583D01*
X407367Y809750D01*
X406783Y809833D01*
X406200Y809667D01*
X405700Y809333D01*
X405367Y808833D01*
X405200Y808167D01*
X405367Y807500D01*
X405700Y807000D01*
X406200Y806667D01*
X406783Y806500D01*
X407367Y806583D01*
X407867Y806833D01*
X408200Y807167D01*
G01X412300Y811500D02*
Y806500D01*
G01X411133Y809833D02*
X413467D01*
G01X416650Y808750D02*
X419317D01*
X419067Y809333D01*
X418650Y809667D01*
X418067Y809833D01*
X417483Y809750D01*
X416983Y809500D01*
X416650Y808917D01*
X416483Y808417D01*
Y807917D01*
X416650Y807417D01*
X417067Y806917D01*
X417567Y806583D01*
X418150Y806500D01*
X418733Y806667D01*
X419317Y807167D01*
G01X422250Y807083D02*
X422667Y806750D01*
X423250Y806500D01*
X423750D01*
X424250Y806667D01*
X424583Y806917D01*
X424750Y807250D01*
X424667Y807750D01*
X424333Y808000D01*
X422833Y808500D01*
X422500Y809083D01*
X422667Y809500D01*
X423000Y809750D01*
X423500Y809833D01*
X424000Y809750D01*
X424500Y809500D01*
G01X429100Y811500D02*
Y806500D01*
G01X427933Y809833D02*
X430267D01*
G01X438800D02*
X440300Y806500D01*
X441800Y809833D01*
G01X444650Y808750D02*
X447317D01*
X447067Y809333D01*
X446650Y809667D01*
X446067Y809833D01*
X445483Y809750D01*
X444983Y809500D01*
X444650Y808917D01*
X444483Y808417D01*
Y807917D01*
X444650Y807417D01*
X445067Y806917D01*
X445567Y806583D01*
X446150Y806500D01*
X446733Y806667D01*
X447317Y807167D01*
G01X450333Y806500D02*
Y809833D01*
G01Y809167D02*
X450750Y809500D01*
X451167Y809750D01*
X451750Y809833D01*
X452167Y809750D01*
X452667Y809500D01*
G01X455850Y807083D02*
X456267Y806750D01*
X456850Y806500D01*
X457350D01*
X457850Y806667D01*
X458183Y806917D01*
X458350Y807250D01*
X458267Y807750D01*
X457933Y808000D01*
X456433Y808500D01*
X456100Y809083D01*
X456267Y809500D01*
X456600Y809750D01*
X457100Y809833D01*
X457600Y809750D01*
X458100Y809500D01*
G01X462700Y809833D02*
Y806500D01*
G01Y811167D02*
X462533Y811250D01*
Y811417D01*
X462700Y811500D01*
X462867Y811417D01*
Y811250D01*
X462700Y811167D01*
G01X468300Y806500D02*
X467800Y806583D01*
X467300Y806917D01*
X466967Y807500D01*
X466800Y808167D01*
X466967Y808833D01*
X467300Y809417D01*
X467800Y809750D01*
X468300Y809833D01*
X468800Y809750D01*
X469300Y809417D01*
X469633Y808833D01*
X469717Y808167D01*
X469633Y807500D01*
X469300Y806917D01*
X468800Y806583D01*
X468300Y806500D01*
G01X472483D02*
Y809833D01*
G01Y809000D02*
X472817Y809417D01*
X473317Y809750D01*
X473983Y809833D01*
X474567Y809750D01*
X475067Y809417D01*
X475317Y808833D01*
Y806500D01*
G01X485100Y809833D02*
Y806500D01*
G01Y811167D02*
X484933Y811250D01*
Y811417D01*
X485100Y811500D01*
X485267Y811417D01*
Y811250D01*
X485100Y811167D01*
G01X489450Y807083D02*
X489867Y806750D01*
X490450Y806500D01*
X490950D01*
X491450Y806667D01*
X491783Y806917D01*
X491950Y807250D01*
X491867Y807750D01*
X491533Y808000D01*
X490033Y808500D01*
X489700Y809083D01*
X489867Y809500D01*
X490200Y809750D01*
X490700Y809833D01*
X491200Y809750D01*
X491700Y809500D01*
G01X500733Y806500D02*
Y809833D01*
G01Y809167D02*
X501150Y809500D01*
X501567Y809750D01*
X502150Y809833D01*
X502567Y809750D01*
X503067Y809500D01*
G01X506250Y808750D02*
X508917D01*
X508667Y809333D01*
X508250Y809667D01*
X507667Y809833D01*
X507083Y809750D01*
X506583Y809500D01*
X506250Y808917D01*
X506083Y808417D01*
Y807917D01*
X506250Y807417D01*
X506667Y806917D01*
X507167Y806583D01*
X507750Y806500D01*
X508333Y806667D01*
X508917Y807167D01*
G01X514600Y804833D02*
Y809833D01*
G01Y809083D02*
X514183Y809500D01*
X513683Y809750D01*
X513100Y809833D01*
X512600Y809750D01*
X512017Y809333D01*
X511683Y808750D01*
X511600Y808167D01*
X511683Y807583D01*
X512017Y807000D01*
X512600Y806583D01*
X513100Y806500D01*
X513683Y806583D01*
X514183Y806833D01*
X514600Y807250D01*
G01X517283Y809833D02*
Y807500D01*
X517617Y806917D01*
X518117Y806583D01*
X518700Y806500D01*
X519283Y806583D01*
X519783Y806917D01*
X520117Y807500D01*
G01Y806500D02*
Y809833D01*
G01X524300D02*
Y806500D01*
G01Y811167D02*
X524133Y811250D01*
Y811417D01*
X524300Y811500D01*
X524467Y811417D01*
Y811250D01*
X524300Y811167D01*
G01X528733Y806500D02*
Y809833D01*
G01Y809167D02*
X529150Y809500D01*
X529567Y809750D01*
X530150Y809833D01*
X530567Y809750D01*
X531067Y809500D01*
G01X534250Y808750D02*
X536917D01*
X536667Y809333D01*
X536250Y809667D01*
X535667Y809833D01*
X535083Y809750D01*
X534583Y809500D01*
X534250Y808917D01*
X534083Y808417D01*
Y807917D01*
X534250Y807417D01*
X534667Y806917D01*
X535167Y806583D01*
X535750Y806500D01*
X536333Y806667D01*
X536917Y807167D01*
G01X542600Y811500D02*
Y806500D01*
G01Y807250D02*
X542267Y806833D01*
X541767Y806583D01*
X541183Y806500D01*
X540517Y806667D01*
X540017Y807083D01*
X539683Y807583D01*
X539600Y808167D01*
X539683Y808750D01*
X540017Y809250D01*
X540517Y809667D01*
X541183Y809833D01*
X541767Y809750D01*
X542183Y809583D01*
X542600Y809250D01*
G01X546533Y805583D02*
X546867Y806667D01*
G01X112333Y-60000D02*
Y-65000D01*
X115667D01*
G01X119600D02*
X119100Y-64917D01*
X118600Y-64583D01*
X118267Y-64000D01*
X118100Y-63333D01*
X118267Y-62667D01*
X118600Y-62083D01*
X119100Y-61750D01*
X119600Y-61667D01*
X120100Y-61750D01*
X120600Y-62083D01*
X120933Y-62667D01*
X121017Y-63333D01*
X120933Y-64000D01*
X120600Y-64583D01*
X120100Y-64917D01*
X119600Y-65000D01*
G01X124033Y-66250D02*
X124617Y-66583D01*
X125283Y-66667D01*
X125867Y-66583D01*
X126367Y-66167D01*
X126700Y-65583D01*
Y-61667D01*
G01Y-62333D02*
X126367Y-62000D01*
X125867Y-61750D01*
X125283Y-61667D01*
X124617Y-61833D01*
X124200Y-62167D01*
X123867Y-62750D01*
X123700Y-63333D01*
X123783Y-63833D01*
X124117Y-64417D01*
X124617Y-64833D01*
X125283Y-65000D01*
X125783Y-64917D01*
X126367Y-64583D01*
X126700Y-64250D01*
G01X130800Y-65000D02*
X130300Y-64917D01*
X129800Y-64583D01*
X129467Y-64000D01*
X129300Y-63333D01*
X129467Y-62667D01*
X129800Y-62083D01*
X130300Y-61750D01*
X130800Y-61667D01*
X131300Y-61750D01*
X131800Y-62083D01*
X132133Y-62667D01*
X132217Y-63333D01*
X132133Y-64000D01*
X131800Y-64583D01*
X131300Y-64917D01*
X130800Y-65000D01*
G01X114000Y-36000D02*
Y-41000D01*
G01X112833Y-37667D02*
X115167D01*
G01X118183Y-41000D02*
Y-36000D01*
G01Y-38417D02*
X118600Y-38000D01*
X119017Y-37750D01*
X119683Y-37667D01*
X120183Y-37750D01*
X120767Y-38083D01*
X121017Y-38583D01*
Y-41000D01*
G01X125200Y-37667D02*
Y-41000D01*
G01Y-36333D02*
X125033Y-36250D01*
Y-36083D01*
X125200Y-36000D01*
X125367Y-36083D01*
Y-36250D01*
X125200Y-36333D01*
G01X132133Y-38083D02*
X131550Y-37750D01*
X131050Y-37667D01*
X130383Y-37833D01*
X129883Y-38167D01*
X129550Y-38750D01*
X129467Y-39333D01*
X129550Y-39917D01*
X129883Y-40417D01*
X130383Y-40833D01*
X131050Y-41000D01*
X131633Y-40833D01*
X132133Y-40500D01*
G01X134983Y-41000D02*
Y-36000D01*
G01X137650Y-37667D02*
X134983Y-39583D01*
G01X136067Y-38833D02*
X137817Y-41000D01*
G01X140583D02*
Y-37667D01*
G01Y-38500D02*
X140917Y-38083D01*
X141417Y-37750D01*
X142083Y-37667D01*
X142667Y-37750D01*
X143167Y-38083D01*
X143417Y-38667D01*
Y-41000D01*
G01X146350Y-38750D02*
X149017D01*
X148767Y-38167D01*
X148350Y-37833D01*
X147767Y-37667D01*
X147183Y-37750D01*
X146683Y-38000D01*
X146350Y-38583D01*
X146183Y-39083D01*
Y-39583D01*
X146350Y-40083D01*
X146767Y-40583D01*
X147267Y-40917D01*
X147850Y-41000D01*
X148433Y-40833D01*
X149017Y-40333D01*
G01X151950Y-40417D02*
X152367Y-40750D01*
X152950Y-41000D01*
X153450D01*
X153950Y-40833D01*
X154283Y-40583D01*
X154450Y-40250D01*
X154367Y-39750D01*
X154033Y-39500D01*
X152533Y-39000D01*
X152200Y-38417D01*
X152367Y-38000D01*
X152700Y-37750D01*
X153200Y-37667D01*
X153700Y-37750D01*
X154200Y-38000D01*
G01X157550Y-40417D02*
X157967Y-40750D01*
X158550Y-41000D01*
X159050D01*
X159550Y-40833D01*
X159883Y-40583D01*
X160050Y-40250D01*
X159967Y-39750D01*
X159633Y-39500D01*
X158133Y-39000D01*
X157800Y-38417D01*
X157967Y-38000D01*
X158300Y-37750D01*
X158800Y-37667D01*
X159300Y-37750D01*
X159800Y-38000D01*
G01X114000Y-15000D02*
Y-20000D01*
G01X112833Y-16667D02*
X115167D01*
G01X118183Y-20000D02*
Y-15000D01*
G01Y-17417D02*
X118600Y-17000D01*
X119017Y-16750D01*
X119683Y-16667D01*
X120183Y-16750D01*
X120767Y-17083D01*
X121017Y-17583D01*
Y-20000D01*
G01X125200Y-16667D02*
Y-20000D01*
G01Y-15333D02*
X125033Y-15250D01*
Y-15083D01*
X125200Y-15000D01*
X125367Y-15083D01*
Y-15250D01*
X125200Y-15333D01*
G01X132133Y-17083D02*
X131550Y-16750D01*
X131050Y-16667D01*
X130383Y-16833D01*
X129883Y-17167D01*
X129550Y-17750D01*
X129467Y-18333D01*
X129550Y-18917D01*
X129883Y-19417D01*
X130383Y-19833D01*
X131050Y-20000D01*
X131633Y-19833D01*
X132133Y-19500D01*
G01X134983Y-20000D02*
Y-15000D01*
G01X137650Y-16667D02*
X134983Y-18583D01*
G01X136067Y-17833D02*
X137817Y-20000D01*
G01X140583D02*
Y-16667D01*
G01Y-17500D02*
X140917Y-17083D01*
X141417Y-16750D01*
X142083Y-16667D01*
X142667Y-16750D01*
X143167Y-17083D01*
X143417Y-17667D01*
Y-20000D01*
G01X146350Y-17750D02*
X149017D01*
X148767Y-17167D01*
X148350Y-16833D01*
X147767Y-16667D01*
X147183Y-16750D01*
X146683Y-17000D01*
X146350Y-17583D01*
X146183Y-18083D01*
Y-18583D01*
X146350Y-19083D01*
X146767Y-19583D01*
X147267Y-19917D01*
X147850Y-20000D01*
X148433Y-19833D01*
X149017Y-19333D01*
G01X151950Y-19417D02*
X152367Y-19750D01*
X152950Y-20000D01*
X153450D01*
X153950Y-19833D01*
X154283Y-19583D01*
X154450Y-19250D01*
X154367Y-18750D01*
X154033Y-18500D01*
X152533Y-18000D01*
X152200Y-17417D01*
X152367Y-17000D01*
X152700Y-16750D01*
X153200Y-16667D01*
X153700Y-16750D01*
X154200Y-17000D01*
G01X157550Y-19417D02*
X157967Y-19750D01*
X158550Y-20000D01*
X159050D01*
X159550Y-19833D01*
X159883Y-19583D01*
X160050Y-19250D01*
X159967Y-18750D01*
X159633Y-18500D01*
X158133Y-18000D01*
X157800Y-17417D01*
X157967Y-17000D01*
X158300Y-16750D01*
X158800Y-16667D01*
X159300Y-16750D01*
X159800Y-17000D01*
G01X119183Y-2167D02*
X118350Y-1333D01*
X117933Y-500D01*
Y2833D01*
X118350Y3667D01*
X119183Y4500D01*
G01X123450Y167D02*
X124117Y-250D01*
X124867Y-500D01*
X125533D01*
X126200Y-250D01*
X126700Y167D01*
X126950Y750D01*
X126783Y1333D01*
X126367Y1833D01*
X125617Y2167D01*
X124617Y2333D01*
X124033Y2667D01*
X123783Y3250D01*
X123950Y3833D01*
X124367Y4250D01*
X124950Y4500D01*
X125533D01*
X126117Y4333D01*
X126617Y3917D01*
G01X128633Y-500D02*
Y4500D01*
X130800Y333D01*
X132967Y4500D01*
Y-500D01*
G01X134567D02*
Y4500D01*
X136233D01*
X136900Y4250D01*
X137400Y3917D01*
X137817Y3417D01*
X138150Y2833D01*
X138233Y2000D01*
X138150Y1167D01*
X137817Y583D01*
X137400Y83D01*
X136900Y-250D01*
X136233Y-500D01*
X134567D01*
G01X142417Y-2167D02*
X143250Y-1333D01*
X143667Y-500D01*
Y2833D01*
X143250Y3667D01*
X142417Y4500D01*
G01X103500Y679000D02*
Y-69500D01*
G01Y-9500D02*
X694500D01*
G01X103500Y-54500D02*
X694500D01*
G01X112483Y24700D02*
Y29700D01*
X114650Y25533D01*
X116817Y29700D01*
Y24700D01*
G01X121750D02*
Y28033D01*
G01Y27450D02*
X121417Y27783D01*
X120917Y27950D01*
X120333Y28033D01*
X119750Y27867D01*
X119250Y27533D01*
X118917Y27033D01*
X118750Y26367D01*
X118917Y25700D01*
X119250Y25200D01*
X119750Y24867D01*
X120333Y24700D01*
X120917Y24783D01*
X121417Y25033D01*
X121750Y25367D01*
G01X124683Y24700D02*
Y28033D01*
G01Y27367D02*
X125100Y27700D01*
X125517Y27950D01*
X126100Y28033D01*
X126517Y27950D01*
X127017Y27700D01*
G01X130033Y24700D02*
Y29700D01*
G01X132700Y28033D02*
X130033Y26117D01*
G01X131117Y26867D02*
X132867Y24700D01*
G01X137467Y23033D02*
X138300Y23867D01*
X138717Y24700D01*
Y28033D01*
X138300Y28867D01*
X137467Y29700D01*
G01X113070Y36130D02*
X114737D01*
Y34630D01*
X114237Y34130D01*
X113653Y33797D01*
X112820Y33630D01*
X111987Y33797D01*
X111403Y34130D01*
X110903Y34630D01*
X110570Y35213D01*
X110403Y35880D01*
Y36463D01*
X110570Y36963D01*
X110903Y37547D01*
X111403Y38047D01*
X111903Y38380D01*
X112570Y38630D01*
X113153D01*
X113820Y38463D01*
X114320Y38130D01*
G01X118170Y33630D02*
X117670Y33713D01*
X117170Y34047D01*
X116837Y34630D01*
X116670Y35297D01*
X116837Y35963D01*
X117170Y36547D01*
X117670Y36880D01*
X118170Y36963D01*
X118670Y36880D01*
X119170Y36547D01*
X119503Y35963D01*
X119587Y35297D01*
X119503Y34630D01*
X119170Y34047D01*
X118670Y33713D01*
X118170Y33630D01*
G01X123770D02*
Y38630D01*
G01X130870D02*
Y33630D01*
G01Y34380D02*
X130537Y33963D01*
X130037Y33713D01*
X129453Y33630D01*
X128787Y33797D01*
X128287Y34213D01*
X127953Y34713D01*
X127870Y35297D01*
X127953Y35880D01*
X128287Y36380D01*
X128787Y36797D01*
X129453Y36963D01*
X130037Y36880D01*
X130453Y36713D01*
X130870Y36380D01*
G01X133720Y35880D02*
X136387D01*
X136137Y36463D01*
X135720Y36797D01*
X135137Y36963D01*
X134553Y36880D01*
X134053Y36630D01*
X133720Y36047D01*
X133553Y35547D01*
Y35047D01*
X133720Y34547D01*
X134137Y34047D01*
X134637Y33713D01*
X135220Y33630D01*
X135803Y33797D01*
X136387Y34297D01*
G01X139153Y33630D02*
Y36963D01*
G01Y36130D02*
X139487Y36547D01*
X139987Y36880D01*
X140653Y36963D01*
X141237Y36880D01*
X141737Y36547D01*
X141987Y35963D01*
Y33630D01*
G01X151270D02*
Y37880D01*
X151437Y38297D01*
X151770Y38547D01*
X152270Y38630D01*
X152770Y38463D01*
X153020Y38047D01*
G01X152020Y36630D02*
X150353D01*
G01X157370Y36963D02*
Y33630D01*
G01Y38297D02*
X157203Y38380D01*
Y38547D01*
X157370Y38630D01*
X157537Y38547D01*
Y38380D01*
X157370Y38297D01*
G01X161553Y33630D02*
Y36963D01*
G01Y36130D02*
X161887Y36547D01*
X162387Y36880D01*
X163053Y36963D01*
X163637Y36880D01*
X164137Y36547D01*
X164387Y35963D01*
Y33630D01*
G01X167403Y32380D02*
X167987Y32047D01*
X168653Y31963D01*
X169237Y32047D01*
X169737Y32463D01*
X170070Y33047D01*
Y36963D01*
G01Y36297D02*
X169737Y36630D01*
X169237Y36880D01*
X168653Y36963D01*
X167987Y36797D01*
X167570Y36463D01*
X167237Y35880D01*
X167070Y35297D01*
X167153Y34797D01*
X167487Y34213D01*
X167987Y33797D01*
X168653Y33630D01*
X169153Y33713D01*
X169737Y34047D01*
X170070Y34380D01*
G01X172920Y35880D02*
X175587D01*
X175337Y36463D01*
X174920Y36797D01*
X174337Y36963D01*
X173753Y36880D01*
X173253Y36630D01*
X172920Y36047D01*
X172753Y35547D01*
Y35047D01*
X172920Y34547D01*
X173337Y34047D01*
X173837Y33713D01*
X174420Y33630D01*
X175003Y33797D01*
X175587Y34297D01*
G01X178603Y33630D02*
Y36963D01*
G01Y36297D02*
X179020Y36630D01*
X179437Y36880D01*
X180020Y36963D01*
X180437Y36880D01*
X180937Y36630D01*
G01X189303Y33630D02*
Y38630D01*
X191303D01*
X191970Y38380D01*
X192470Y37797D01*
X192637Y37130D01*
X192470Y36463D01*
X192053Y35963D01*
X191303Y35713D01*
X189303D01*
G01X194487Y33630D02*
X196570Y38630D01*
X198653Y33630D01*
G01X197903Y35380D02*
X195237D01*
G01X200337Y33630D02*
Y38630D01*
X202003D01*
X202670Y38380D01*
X203170Y38047D01*
X203587Y37547D01*
X203920Y36963D01*
X204003Y36130D01*
X203920Y35297D01*
X203587Y34713D01*
X203170Y34213D01*
X202670Y33880D01*
X202003Y33630D01*
X200337D01*
G01X211870Y33463D02*
X214870Y38630D01*
G01X217387Y33630D02*
Y38630D01*
X220553D01*
G01X219387Y36213D02*
X217387D01*
G01X224570Y36963D02*
Y33630D01*
G01Y38297D02*
X224403Y38380D01*
Y38547D01*
X224570Y38630D01*
X224737Y38547D01*
Y38380D01*
X224570Y38297D01*
G01X231670Y38630D02*
Y33630D01*
G01Y34380D02*
X231337Y33963D01*
X230837Y33713D01*
X230253Y33630D01*
X229587Y33797D01*
X229087Y34213D01*
X228753Y34713D01*
X228670Y35297D01*
X228753Y35880D01*
X229087Y36380D01*
X229587Y36797D01*
X230253Y36963D01*
X230837Y36880D01*
X231253Y36713D01*
X231670Y36380D01*
G01X234353Y36963D02*
Y34630D01*
X234687Y34047D01*
X235187Y33713D01*
X235770Y33630D01*
X236353Y33713D01*
X236853Y34047D01*
X237187Y34630D01*
G01Y33630D02*
Y36963D01*
G01X242703Y36547D02*
X242120Y36880D01*
X241620Y36963D01*
X240953Y36797D01*
X240453Y36463D01*
X240120Y35880D01*
X240037Y35297D01*
X240120Y34713D01*
X240453Y34213D01*
X240953Y33797D01*
X241620Y33630D01*
X242203Y33797D01*
X242703Y34130D01*
G01X246970Y36963D02*
Y33630D01*
G01Y38297D02*
X246803Y38380D01*
Y38547D01*
X246970Y38630D01*
X247137Y38547D01*
Y38380D01*
X246970Y38297D01*
G01X254070Y33630D02*
Y36963D01*
G01Y36380D02*
X253737Y36713D01*
X253237Y36880D01*
X252653Y36963D01*
X252070Y36797D01*
X251570Y36463D01*
X251237Y35963D01*
X251070Y35297D01*
X251237Y34630D01*
X251570Y34130D01*
X252070Y33797D01*
X252653Y33630D01*
X253237Y33713D01*
X253737Y33963D01*
X254070Y34297D01*
G01X258170Y33630D02*
Y38630D01*
G01X112743Y42673D02*
X111910Y43507D01*
X111493Y44340D01*
Y47673D01*
X111910Y48507D01*
X112743Y49340D01*
G01X116260Y44340D02*
Y47673D01*
G01Y46757D02*
X116510Y47173D01*
X116927Y47507D01*
X117510Y47673D01*
X118093Y47507D01*
X118510Y47173D01*
X118760Y46757D01*
Y44340D01*
G01Y46757D02*
X119010Y47173D01*
X119427Y47507D01*
X120010Y47673D01*
X120593Y47507D01*
X121010Y47173D01*
X121260Y46673D01*
Y44340D01*
G01X123110Y46590D02*
X125777D01*
X125527Y47173D01*
X125110Y47507D01*
X124527Y47673D01*
X123943Y47590D01*
X123443Y47340D01*
X123110Y46757D01*
X122943Y46257D01*
Y45757D01*
X123110Y45257D01*
X123527Y44757D01*
X124027Y44423D01*
X124610Y44340D01*
X125193Y44507D01*
X125777Y45007D01*
G01X131460Y44340D02*
Y47673D01*
G01Y47090D02*
X131127Y47423D01*
X130627Y47590D01*
X130043Y47673D01*
X129460Y47507D01*
X128960Y47173D01*
X128627Y46673D01*
X128460Y46007D01*
X128627Y45340D01*
X128960Y44840D01*
X129460Y44507D01*
X130043Y44340D01*
X130627Y44423D01*
X131127Y44673D01*
X131460Y45007D01*
G01X134310Y44923D02*
X134727Y44590D01*
X135310Y44340D01*
X135810D01*
X136310Y44507D01*
X136643Y44757D01*
X136810Y45090D01*
X136727Y45590D01*
X136393Y45840D01*
X134893Y46340D01*
X134560Y46923D01*
X134727Y47340D01*
X135060Y47590D01*
X135560Y47673D01*
X136060Y47590D01*
X136560Y47340D01*
G01X139743Y47673D02*
Y45340D01*
X140077Y44757D01*
X140577Y44423D01*
X141160Y44340D01*
X141743Y44423D01*
X142243Y44757D01*
X142577Y45340D01*
G01Y44340D02*
Y47673D01*
G01X145593Y44340D02*
Y47673D01*
G01Y47007D02*
X146010Y47340D01*
X146427Y47590D01*
X147010Y47673D01*
X147427Y47590D01*
X147927Y47340D01*
G01X151110Y46590D02*
X153777D01*
X153527Y47173D01*
X153110Y47507D01*
X152527Y47673D01*
X151943Y47590D01*
X151443Y47340D01*
X151110Y46757D01*
X150943Y46257D01*
Y45757D01*
X151110Y45257D01*
X151527Y44757D01*
X152027Y44423D01*
X152610Y44340D01*
X153193Y44507D01*
X153777Y45007D01*
G01X163560Y49340D02*
Y44340D01*
G01X162393Y47673D02*
X164727D01*
G01X169160Y44340D02*
X168660Y44423D01*
X168160Y44757D01*
X167827Y45340D01*
X167660Y46007D01*
X167827Y46673D01*
X168160Y47257D01*
X168660Y47590D01*
X169160Y47673D01*
X169660Y47590D01*
X170160Y47257D01*
X170493Y46673D01*
X170577Y46007D01*
X170493Y45340D01*
X170160Y44757D01*
X169660Y44423D01*
X169160Y44340D01*
G01X173260Y42673D02*
Y47673D01*
G01Y46923D02*
X173677Y47340D01*
X174093Y47590D01*
X174760Y47673D01*
X175343Y47590D01*
X175927Y47173D01*
X176177Y46590D01*
X176260Y46007D01*
X176177Y45423D01*
X175927Y44840D01*
X175427Y44507D01*
X174760Y44340D01*
X174177Y44423D01*
X173593Y44673D01*
X173260Y45007D01*
G01X184710Y44923D02*
X185127Y44590D01*
X185710Y44340D01*
X186210D01*
X186710Y44507D01*
X187043Y44757D01*
X187210Y45090D01*
X187127Y45590D01*
X186793Y45840D01*
X185293Y46340D01*
X184960Y46923D01*
X185127Y47340D01*
X185460Y47590D01*
X185960Y47673D01*
X186460Y47590D01*
X186960Y47340D01*
G01X191560Y47673D02*
Y44340D01*
G01Y49007D02*
X191393Y49090D01*
Y49257D01*
X191560Y49340D01*
X191727Y49257D01*
Y49090D01*
X191560Y49007D01*
G01X195910Y47673D02*
X198410D01*
X195910Y44340D01*
X198410D01*
G01X201510Y46590D02*
X204177D01*
X203927Y47173D01*
X203510Y47507D01*
X202927Y47673D01*
X202343Y47590D01*
X201843Y47340D01*
X201510Y46757D01*
X201343Y46257D01*
Y45757D01*
X201510Y45257D01*
X201927Y44757D01*
X202427Y44423D01*
X203010Y44340D01*
X203593Y44507D01*
X204177Y45007D01*
G01X213960Y44340D02*
X213460Y44423D01*
X212960Y44757D01*
X212627Y45340D01*
X212460Y46007D01*
X212627Y46673D01*
X212960Y47257D01*
X213460Y47590D01*
X213960Y47673D01*
X214460Y47590D01*
X214960Y47257D01*
X215293Y46673D01*
X215377Y46007D01*
X215293Y45340D01*
X214960Y44757D01*
X214460Y44423D01*
X213960Y44340D01*
G01X219060D02*
Y48590D01*
X219227Y49007D01*
X219560Y49257D01*
X220060Y49340D01*
X220560Y49173D01*
X220810Y48757D01*
G01X219810Y47340D02*
X218143D01*
G01X229093Y44340D02*
Y49340D01*
X231093D01*
X231760Y49090D01*
X232260Y48507D01*
X232427Y47840D01*
X232260Y47173D01*
X231843Y46673D01*
X231093Y46423D01*
X229093D01*
G01X234277Y44340D02*
X236360Y49340D01*
X238443Y44340D01*
G01X237693Y46090D02*
X235027D01*
G01X240127Y44340D02*
Y49340D01*
X241793D01*
X242460Y49090D01*
X242960Y48757D01*
X243377Y48257D01*
X243710Y47673D01*
X243793Y46840D01*
X243710Y46007D01*
X243377Y45423D01*
X242960Y44923D01*
X242460Y44590D01*
X241793Y44340D01*
X240127D01*
G01X251660Y44173D02*
X254660Y49340D01*
G01X112250Y12167D02*
X112917Y11750D01*
X113667Y11500D01*
X114333D01*
X115000Y11750D01*
X115500Y12167D01*
X115750Y12750D01*
X115583Y13333D01*
X115167Y13833D01*
X114417Y14167D01*
X113417Y14333D01*
X112833Y14667D01*
X112583Y15250D01*
X112750Y15833D01*
X113167Y16250D01*
X113750Y16500D01*
X114333D01*
X114917Y16333D01*
X115417Y15917D01*
G01X119600Y11500D02*
X119100Y11583D01*
X118600Y11917D01*
X118267Y12500D01*
X118100Y13167D01*
X118267Y13833D01*
X118600Y14417D01*
X119100Y14750D01*
X119600Y14833D01*
X120100Y14750D01*
X120600Y14417D01*
X120933Y13833D01*
X121017Y13167D01*
X120933Y12500D01*
X120600Y11917D01*
X120100Y11583D01*
X119600Y11500D01*
G01X125200D02*
Y16500D01*
G01X132300D02*
Y11500D01*
G01Y12250D02*
X131967Y11833D01*
X131467Y11583D01*
X130883Y11500D01*
X130217Y11667D01*
X129717Y12083D01*
X129383Y12583D01*
X129300Y13167D01*
X129383Y13750D01*
X129717Y14250D01*
X130217Y14667D01*
X130883Y14833D01*
X131467Y14750D01*
X131883Y14583D01*
X132300Y14250D01*
G01X135150Y13750D02*
X137817D01*
X137567Y14333D01*
X137150Y14667D01*
X136567Y14833D01*
X135983Y14750D01*
X135483Y14500D01*
X135150Y13917D01*
X134983Y13417D01*
Y12917D01*
X135150Y12417D01*
X135567Y11917D01*
X136067Y11583D01*
X136650Y11500D01*
X137233Y11667D01*
X137817Y12167D01*
G01X140833Y11500D02*
Y14833D01*
G01Y14167D02*
X141250Y14500D01*
X141667Y14750D01*
X142250Y14833D01*
X142667Y14750D01*
X143167Y14500D01*
G01X150700Y11500D02*
Y14833D01*
G01Y13917D02*
X150950Y14333D01*
X151367Y14667D01*
X151950Y14833D01*
X152533Y14667D01*
X152950Y14333D01*
X153200Y13917D01*
Y11500D01*
G01Y13917D02*
X153450Y14333D01*
X153867Y14667D01*
X154450Y14833D01*
X155033Y14667D01*
X155450Y14333D01*
X155700Y13833D01*
Y11500D01*
G01X160300D02*
Y14833D01*
G01Y14250D02*
X159967Y14583D01*
X159467Y14750D01*
X158883Y14833D01*
X158300Y14667D01*
X157800Y14333D01*
X157467Y13833D01*
X157300Y13167D01*
X157467Y12500D01*
X157800Y12000D01*
X158300Y11667D01*
X158883Y11500D01*
X159467Y11583D01*
X159967Y11833D01*
X160300Y12167D01*
G01X163150Y12083D02*
X163567Y11750D01*
X164150Y11500D01*
X164650D01*
X165150Y11667D01*
X165483Y11917D01*
X165650Y12250D01*
X165567Y12750D01*
X165233Y13000D01*
X163733Y13500D01*
X163400Y14083D01*
X163567Y14500D01*
X163900Y14750D01*
X164400Y14833D01*
X164900Y14750D01*
X165400Y14500D01*
G01X168583Y11500D02*
Y16500D01*
G01X171250Y14833D02*
X168583Y12917D01*
G01X169667Y13667D02*
X171417Y11500D01*
G01X182700Y16500D02*
Y11500D01*
G01Y12250D02*
X182367Y11833D01*
X181867Y11583D01*
X181283Y11500D01*
X180617Y11667D01*
X180117Y12083D01*
X179783Y12583D01*
X179700Y13167D01*
X179783Y13750D01*
X180117Y14250D01*
X180617Y14667D01*
X181283Y14833D01*
X181867Y14750D01*
X182283Y14583D01*
X182700Y14250D01*
G01X185550Y13750D02*
X188217D01*
X187967Y14333D01*
X187550Y14667D01*
X186967Y14833D01*
X186383Y14750D01*
X185883Y14500D01*
X185550Y13917D01*
X185383Y13417D01*
Y12917D01*
X185550Y12417D01*
X185967Y11917D01*
X186467Y11583D01*
X187050Y11500D01*
X187633Y11667D01*
X188217Y12167D01*
G01X191900Y11500D02*
Y15750D01*
X192067Y16167D01*
X192400Y16417D01*
X192900Y16500D01*
X193400Y16333D01*
X193650Y15917D01*
G01X192650Y14500D02*
X190983D01*
G01X198000Y14833D02*
Y11500D01*
G01Y16167D02*
X197833Y16250D01*
Y16417D01*
X198000Y16500D01*
X198167Y16417D01*
Y16250D01*
X198000Y16167D01*
G01X202183Y11500D02*
Y14833D01*
G01Y14000D02*
X202517Y14417D01*
X203017Y14750D01*
X203683Y14833D01*
X204267Y14750D01*
X204767Y14417D01*
X205017Y13833D01*
Y11500D01*
G01X207950Y13750D02*
X210617D01*
X210367Y14333D01*
X209950Y14667D01*
X209367Y14833D01*
X208783Y14750D01*
X208283Y14500D01*
X207950Y13917D01*
X207783Y13417D01*
Y12917D01*
X207950Y12417D01*
X208367Y11917D01*
X208867Y11583D01*
X209450Y11500D01*
X210033Y11667D01*
X210617Y12167D01*
G01X218900Y9833D02*
Y14833D01*
G01Y14083D02*
X219317Y14500D01*
X219733Y14750D01*
X220400Y14833D01*
X220983Y14750D01*
X221567Y14333D01*
X221817Y13750D01*
X221900Y13167D01*
X221817Y12583D01*
X221567Y12000D01*
X221067Y11667D01*
X220400Y11500D01*
X219817Y11583D01*
X219233Y11833D01*
X218900Y12167D01*
G01X227500Y11500D02*
Y14833D01*
G01Y14250D02*
X227167Y14583D01*
X226667Y14750D01*
X226083Y14833D01*
X225500Y14667D01*
X225000Y14333D01*
X224667Y13833D01*
X224500Y13167D01*
X224667Y12500D01*
X225000Y12000D01*
X225500Y11667D01*
X226083Y11500D01*
X226667Y11583D01*
X227167Y11833D01*
X227500Y12167D01*
G01X233100Y16500D02*
Y11500D01*
G01Y12250D02*
X232767Y11833D01*
X232267Y11583D01*
X231683Y11500D01*
X231017Y11667D01*
X230517Y12083D01*
X230183Y12583D01*
X230100Y13167D01*
X230183Y13750D01*
X230517Y14250D01*
X231017Y14667D01*
X231683Y14833D01*
X232267Y14750D01*
X232683Y14583D01*
X233100Y14250D01*
G01X112333Y51500D02*
Y56500D01*
X114333D01*
X115000Y56250D01*
X115500Y55667D01*
X115667Y55000D01*
X115500Y54333D01*
X115083Y53833D01*
X114333Y53583D01*
X112333D01*
G01X117517Y51500D02*
X119600Y56500D01*
X121683Y51500D01*
G01X120933Y53250D02*
X118267D01*
G01X123367Y51500D02*
Y56500D01*
X125033D01*
X125700Y56250D01*
X126200Y55917D01*
X126617Y55417D01*
X126950Y54833D01*
X127033Y54000D01*
X126950Y53167D01*
X126617Y52583D01*
X126200Y52083D01*
X125700Y51750D01*
X125033Y51500D01*
X123367D01*
G01X135150Y52083D02*
X135567Y51750D01*
X136150Y51500D01*
X136650D01*
X137150Y51667D01*
X137483Y51917D01*
X137650Y52250D01*
X137567Y52750D01*
X137233Y53000D01*
X135733Y53500D01*
X135400Y54083D01*
X135567Y54500D01*
X135900Y54750D01*
X136400Y54833D01*
X136900Y54750D01*
X137400Y54500D01*
G01X142000Y54833D02*
Y51500D01*
G01Y56167D02*
X141833Y56250D01*
Y56417D01*
X142000Y56500D01*
X142167Y56417D01*
Y56250D01*
X142000Y56167D01*
G01X146350Y54833D02*
X148850D01*
X146350Y51500D01*
X148850D01*
G01X151950Y53750D02*
X154617D01*
X154367Y54333D01*
X153950Y54667D01*
X153367Y54833D01*
X152783Y54750D01*
X152283Y54500D01*
X151950Y53917D01*
X151783Y53417D01*
Y52917D01*
X151950Y52417D01*
X152367Y51917D01*
X152867Y51583D01*
X153450Y51500D01*
X154033Y51667D01*
X154617Y52167D01*
G01X114000Y85000D02*
Y80000D01*
G01X112083Y85000D02*
X115917D01*
G01X118433Y80000D02*
Y83333D01*
G01Y82667D02*
X118850Y83000D01*
X119267Y83250D01*
X119850Y83333D01*
X120267Y83250D01*
X120767Y83000D01*
G01X126700Y80000D02*
Y83333D01*
G01Y82750D02*
X126367Y83083D01*
X125867Y83250D01*
X125283Y83333D01*
X124700Y83167D01*
X124200Y82833D01*
X123867Y82333D01*
X123700Y81667D01*
X123867Y81000D01*
X124200Y80500D01*
X124700Y80167D01*
X125283Y80000D01*
X125867Y80083D01*
X126367Y80333D01*
X126700Y80667D01*
G01X132133Y82917D02*
X131550Y83250D01*
X131050Y83333D01*
X130383Y83167D01*
X129883Y82833D01*
X129550Y82250D01*
X129467Y81667D01*
X129550Y81083D01*
X129883Y80583D01*
X130383Y80167D01*
X131050Y80000D01*
X131633Y80167D01*
X132133Y80500D01*
G01X135150Y82250D02*
X137817D01*
X137567Y82833D01*
X137150Y83167D01*
X136567Y83333D01*
X135983Y83250D01*
X135483Y83000D01*
X135150Y82417D01*
X134983Y81917D01*
Y81417D01*
X135150Y80917D01*
X135567Y80417D01*
X136067Y80083D01*
X136650Y80000D01*
X137233Y80167D01*
X137817Y80667D01*
G01X145517Y83333D02*
X146517Y80000D01*
X147600Y83333D01*
X148683Y80000D01*
X149683Y83333D01*
G01X153200D02*
Y80000D01*
G01Y84667D02*
X153033Y84750D01*
Y84917D01*
X153200Y85000D01*
X153367Y84917D01*
Y84750D01*
X153200Y84667D01*
G01X160300Y85000D02*
Y80000D01*
G01Y80750D02*
X159967Y80333D01*
X159467Y80083D01*
X158883Y80000D01*
X158217Y80167D01*
X157717Y80583D01*
X157383Y81083D01*
X157300Y81667D01*
X157383Y82250D01*
X157717Y82750D01*
X158217Y83167D01*
X158883Y83333D01*
X159467Y83250D01*
X159883Y83083D01*
X160300Y82750D01*
G01X164400Y85000D02*
Y80000D01*
G01X163233Y83333D02*
X165567D01*
G01X168583Y80000D02*
Y85000D01*
G01Y82583D02*
X169000Y83000D01*
X169417Y83250D01*
X170083Y83333D01*
X170583Y83250D01*
X171167Y82917D01*
X171417Y82417D01*
Y80000D01*
G01X103500Y60500D02*
X694500D01*
G01X112333Y111500D02*
Y116500D01*
X114417D01*
X115083Y116250D01*
X115500Y115917D01*
X115667Y115250D01*
X115500Y114583D01*
X115000Y114167D01*
X114417Y113917D01*
X112333D01*
G01X114417D02*
X115667Y111500D01*
G01X118350Y113750D02*
X121017D01*
X120767Y114333D01*
X120350Y114667D01*
X119767Y114833D01*
X119183Y114750D01*
X118683Y114500D01*
X118350Y113917D01*
X118183Y113417D01*
Y112917D01*
X118350Y112417D01*
X118767Y111917D01*
X119267Y111583D01*
X119850Y111500D01*
X120433Y111667D01*
X121017Y112167D01*
G01X125200Y111500D02*
Y116500D01*
G01X132300Y111500D02*
Y114833D01*
G01Y114250D02*
X131967Y114583D01*
X131467Y114750D01*
X130883Y114833D01*
X130300Y114667D01*
X129800Y114333D01*
X129467Y113833D01*
X129300Y113167D01*
X129467Y112500D01*
X129800Y112000D01*
X130300Y111667D01*
X130883Y111500D01*
X131467Y111583D01*
X131967Y111833D01*
X132300Y112167D01*
G01X136400Y116500D02*
Y111500D01*
G01X135233Y114833D02*
X137567D01*
G01X142000D02*
Y111500D01*
G01Y116167D02*
X141833Y116250D01*
Y116417D01*
X142000Y116500D01*
X142167Y116417D01*
Y116250D01*
X142000Y116167D01*
G01X146100Y114833D02*
X147600Y111500D01*
X149100Y114833D01*
G01X151950Y113750D02*
X154617D01*
X154367Y114333D01*
X153950Y114667D01*
X153367Y114833D01*
X152783Y114750D01*
X152283Y114500D01*
X151950Y113917D01*
X151783Y113417D01*
Y112917D01*
X151950Y112417D01*
X152367Y111917D01*
X152867Y111583D01*
X153450Y111500D01*
X154033Y111667D01*
X154617Y112167D01*
G01X162900Y109833D02*
Y114833D01*
G01Y114083D02*
X163317Y114500D01*
X163733Y114750D01*
X164400Y114833D01*
X164983Y114750D01*
X165567Y114333D01*
X165817Y113750D01*
X165900Y113167D01*
X165817Y112583D01*
X165567Y112000D01*
X165067Y111667D01*
X164400Y111500D01*
X163817Y111583D01*
X163233Y111833D01*
X162900Y112167D01*
G01X170000Y111500D02*
X169500Y111583D01*
X169000Y111917D01*
X168667Y112500D01*
X168500Y113167D01*
X168667Y113833D01*
X169000Y114417D01*
X169500Y114750D01*
X170000Y114833D01*
X170500Y114750D01*
X171000Y114417D01*
X171333Y113833D01*
X171417Y113167D01*
X171333Y112500D01*
X171000Y111917D01*
X170500Y111583D01*
X170000Y111500D01*
G01X174350Y112083D02*
X174767Y111750D01*
X175350Y111500D01*
X175850D01*
X176350Y111667D01*
X176683Y111917D01*
X176850Y112250D01*
X176767Y112750D01*
X176433Y113000D01*
X174933Y113500D01*
X174600Y114083D01*
X174767Y114500D01*
X175100Y114750D01*
X175600Y114833D01*
X176100Y114750D01*
X176600Y114500D01*
G01X181200Y114833D02*
Y111500D01*
G01Y116167D02*
X181033Y116250D01*
Y116417D01*
X181200Y116500D01*
X181367Y116417D01*
Y116250D01*
X181200Y116167D01*
G01X186800Y116500D02*
Y111500D01*
G01X185633Y114833D02*
X187967D01*
G01X192400D02*
Y111500D01*
G01Y116167D02*
X192233Y116250D01*
Y116417D01*
X192400Y116500D01*
X192567Y116417D01*
Y116250D01*
X192400Y116167D01*
G01X198000Y111500D02*
X197500Y111583D01*
X197000Y111917D01*
X196667Y112500D01*
X196500Y113167D01*
X196667Y113833D01*
X197000Y114417D01*
X197500Y114750D01*
X198000Y114833D01*
X198500Y114750D01*
X199000Y114417D01*
X199333Y113833D01*
X199417Y113167D01*
X199333Y112500D01*
X199000Y111917D01*
X198500Y111583D01*
X198000Y111500D01*
G01X202183D02*
Y114833D01*
G01Y114000D02*
X202517Y114417D01*
X203017Y114750D01*
X203683Y114833D01*
X204267Y114750D01*
X204767Y114417D01*
X205017Y113833D01*
Y111500D01*
G01X114000Y143500D02*
Y138500D01*
G01X112833Y141833D02*
X115167D01*
G01X118183Y138500D02*
Y143500D01*
G01Y141083D02*
X118600Y141500D01*
X119017Y141750D01*
X119683Y141833D01*
X120183Y141750D01*
X120767Y141417D01*
X121017Y140917D01*
Y138500D01*
G01X125200Y141833D02*
Y138500D01*
G01Y143167D02*
X125033Y143250D01*
Y143417D01*
X125200Y143500D01*
X125367Y143417D01*
Y143250D01*
X125200Y143167D01*
G01X132133Y141417D02*
X131550Y141750D01*
X131050Y141833D01*
X130383Y141667D01*
X129883Y141333D01*
X129550Y140750D01*
X129467Y140167D01*
X129550Y139583D01*
X129883Y139083D01*
X130383Y138667D01*
X131050Y138500D01*
X131633Y138667D01*
X132133Y139000D01*
G01X134983Y138500D02*
Y143500D01*
G01X137650Y141833D02*
X134983Y139917D01*
G01X136067Y140667D02*
X137817Y138500D01*
G01X140583D02*
Y141833D01*
G01Y141000D02*
X140917Y141417D01*
X141417Y141750D01*
X142083Y141833D01*
X142667Y141750D01*
X143167Y141417D01*
X143417Y140833D01*
Y138500D01*
G01X146350Y140750D02*
X149017D01*
X148767Y141333D01*
X148350Y141667D01*
X147767Y141833D01*
X147183Y141750D01*
X146683Y141500D01*
X146350Y140917D01*
X146183Y140417D01*
Y139917D01*
X146350Y139417D01*
X146767Y138917D01*
X147267Y138583D01*
X147850Y138500D01*
X148433Y138667D01*
X149017Y139167D01*
G01X151950Y139083D02*
X152367Y138750D01*
X152950Y138500D01*
X153450D01*
X153950Y138667D01*
X154283Y138917D01*
X154450Y139250D01*
X154367Y139750D01*
X154033Y140000D01*
X152533Y140500D01*
X152200Y141083D01*
X152367Y141500D01*
X152700Y141750D01*
X153200Y141833D01*
X153700Y141750D01*
X154200Y141500D01*
G01X157550Y139083D02*
X157967Y138750D01*
X158550Y138500D01*
X159050D01*
X159550Y138667D01*
X159883Y138917D01*
X160050Y139250D01*
X159967Y139750D01*
X159633Y140000D01*
X158133Y140500D01*
X157800Y141083D01*
X157967Y141500D01*
X158300Y141750D01*
X158800Y141833D01*
X159300Y141750D01*
X159800Y141500D01*
G01X171500Y138500D02*
Y141833D01*
G01Y141250D02*
X171167Y141583D01*
X170667Y141750D01*
X170083Y141833D01*
X169500Y141667D01*
X169000Y141333D01*
X168667Y140833D01*
X168500Y140167D01*
X168667Y139500D01*
X169000Y139000D01*
X169500Y138667D01*
X170083Y138500D01*
X170667Y138583D01*
X171167Y138833D01*
X171500Y139167D01*
G01X175100Y138500D02*
Y142750D01*
X175267Y143167D01*
X175600Y143417D01*
X176100Y143500D01*
X176600Y143333D01*
X176850Y142917D01*
G01X175850Y141500D02*
X174183D01*
G01X181200Y143500D02*
Y138500D01*
G01X180033Y141833D02*
X182367D01*
G01X185550Y140750D02*
X188217D01*
X187967Y141333D01*
X187550Y141667D01*
X186967Y141833D01*
X186383Y141750D01*
X185883Y141500D01*
X185550Y140917D01*
X185383Y140417D01*
Y139917D01*
X185550Y139417D01*
X185967Y138917D01*
X186467Y138583D01*
X187050Y138500D01*
X187633Y138667D01*
X188217Y139167D01*
G01X191233Y138500D02*
Y141833D01*
G01Y141167D02*
X191650Y141500D01*
X192067Y141750D01*
X192650Y141833D01*
X193067Y141750D01*
X193567Y141500D01*
G01X202100Y136833D02*
Y141833D01*
G01Y141083D02*
X202517Y141500D01*
X202933Y141750D01*
X203600Y141833D01*
X204183Y141750D01*
X204767Y141333D01*
X205017Y140750D01*
X205100Y140167D01*
X205017Y139583D01*
X204767Y139000D01*
X204267Y138667D01*
X203600Y138500D01*
X203017Y138583D01*
X202433Y138833D01*
X202100Y139167D01*
G01X209200Y138500D02*
Y143500D01*
G01X216300Y138500D02*
Y141833D01*
G01Y141250D02*
X215967Y141583D01*
X215467Y141750D01*
X214883Y141833D01*
X214300Y141667D01*
X213800Y141333D01*
X213467Y140833D01*
X213300Y140167D01*
X213467Y139500D01*
X213800Y139000D01*
X214300Y138667D01*
X214883Y138500D01*
X215467Y138583D01*
X215967Y138833D01*
X216300Y139167D01*
G01X220400Y143500D02*
Y138500D01*
G01X219233Y141833D02*
X221567D01*
G01X226000D02*
Y138500D01*
G01Y143167D02*
X225833Y143250D01*
Y143417D01*
X226000Y143500D01*
X226167Y143417D01*
Y143250D01*
X226000Y143167D01*
G01X230183Y138500D02*
Y141833D01*
G01Y141000D02*
X230517Y141417D01*
X231017Y141750D01*
X231683Y141833D01*
X232267Y141750D01*
X232767Y141417D01*
X233017Y140833D01*
Y138500D01*
G01X236033Y137250D02*
X236617Y136917D01*
X237283Y136833D01*
X237867Y136917D01*
X238367Y137333D01*
X238700Y137917D01*
Y141833D01*
G01Y141167D02*
X238367Y141500D01*
X237867Y141750D01*
X237283Y141833D01*
X236617Y141667D01*
X236200Y141333D01*
X235867Y140750D01*
X235700Y140167D01*
X235783Y139667D01*
X236117Y139083D01*
X236617Y138667D01*
X237283Y138500D01*
X237783Y138583D01*
X238367Y138917D01*
X238700Y139250D01*
G01X115667Y148500D02*
X112333D01*
Y153500D01*
X115667D01*
G01X114333Y151083D02*
X112333D01*
G01X118350Y151833D02*
X120850Y148500D01*
G01Y151833D02*
X118350Y148500D01*
G01X125200Y153500D02*
Y148500D01*
G01X124033Y151833D02*
X126367D01*
G01X129550Y150750D02*
X132217D01*
X131967Y151333D01*
X131550Y151667D01*
X130967Y151833D01*
X130383Y151750D01*
X129883Y151500D01*
X129550Y150917D01*
X129383Y150417D01*
Y149917D01*
X129550Y149417D01*
X129967Y148917D01*
X130467Y148583D01*
X131050Y148500D01*
X131633Y148667D01*
X132217Y149167D01*
G01X135233Y148500D02*
Y151833D01*
G01Y151167D02*
X135650Y151500D01*
X136067Y151750D01*
X136650Y151833D01*
X137067Y151750D01*
X137567Y151500D01*
G01X140583Y148500D02*
Y151833D01*
G01Y151000D02*
X140917Y151417D01*
X141417Y151750D01*
X142083Y151833D01*
X142667Y151750D01*
X143167Y151417D01*
X143417Y150833D01*
Y148500D01*
G01X149100D02*
Y151833D01*
G01Y151250D02*
X148767Y151583D01*
X148267Y151750D01*
X147683Y151833D01*
X147100Y151667D01*
X146600Y151333D01*
X146267Y150833D01*
X146100Y150167D01*
X146267Y149500D01*
X146600Y149000D01*
X147100Y148667D01*
X147683Y148500D01*
X148267Y148583D01*
X148767Y148833D01*
X149100Y149167D01*
G01X153200Y148500D02*
Y153500D01*
G01X165733Y151417D02*
X165150Y151750D01*
X164650Y151833D01*
X163983Y151667D01*
X163483Y151333D01*
X163150Y150750D01*
X163067Y150167D01*
X163150Y149583D01*
X163483Y149083D01*
X163983Y148667D01*
X164650Y148500D01*
X165233Y148667D01*
X165733Y149000D01*
G01X170000Y148500D02*
X169500Y148583D01*
X169000Y148917D01*
X168667Y149500D01*
X168500Y150167D01*
X168667Y150833D01*
X169000Y151417D01*
X169500Y151750D01*
X170000Y151833D01*
X170500Y151750D01*
X171000Y151417D01*
X171333Y150833D01*
X171417Y150167D01*
X171333Y149500D01*
X171000Y148917D01*
X170500Y148583D01*
X170000Y148500D01*
G01X174183D02*
Y151833D01*
G01Y151000D02*
X174517Y151417D01*
X175017Y151750D01*
X175683Y151833D01*
X176267Y151750D01*
X176767Y151417D01*
X177017Y150833D01*
Y148500D01*
G01X182700Y153500D02*
Y148500D01*
G01Y149250D02*
X182367Y148833D01*
X181867Y148583D01*
X181283Y148500D01*
X180617Y148667D01*
X180117Y149083D01*
X179783Y149583D01*
X179700Y150167D01*
X179783Y150750D01*
X180117Y151250D01*
X180617Y151667D01*
X181283Y151833D01*
X181867Y151750D01*
X182283Y151583D01*
X182700Y151250D01*
G01X185383Y151833D02*
Y149500D01*
X185717Y148917D01*
X186217Y148583D01*
X186800Y148500D01*
X187383Y148583D01*
X187883Y148917D01*
X188217Y149500D01*
G01Y148500D02*
Y151833D01*
G01X193733Y151417D02*
X193150Y151750D01*
X192650Y151833D01*
X191983Y151667D01*
X191483Y151333D01*
X191150Y150750D01*
X191067Y150167D01*
X191150Y149583D01*
X191483Y149083D01*
X191983Y148667D01*
X192650Y148500D01*
X193233Y148667D01*
X193733Y149000D01*
G01X198000Y153500D02*
Y148500D01*
G01X196833Y151833D02*
X199167D01*
G01X203600Y148500D02*
X203100Y148583D01*
X202600Y148917D01*
X202267Y149500D01*
X202100Y150167D01*
X202267Y150833D01*
X202600Y151417D01*
X203100Y151750D01*
X203600Y151833D01*
X204100Y151750D01*
X204600Y151417D01*
X204933Y150833D01*
X205017Y150167D01*
X204933Y149500D01*
X204600Y148917D01*
X204100Y148583D01*
X203600Y148500D01*
G01X208033D02*
Y151833D01*
G01Y151167D02*
X208450Y151500D01*
X208867Y151750D01*
X209450Y151833D01*
X209867Y151750D01*
X210367Y151500D01*
G01X112333Y356500D02*
Y351500D01*
X115667D01*
G01X121100D02*
Y354833D01*
G01Y354250D02*
X120767Y354583D01*
X120267Y354750D01*
X119683Y354833D01*
X119100Y354667D01*
X118600Y354333D01*
X118267Y353833D01*
X118100Y353167D01*
X118267Y352500D01*
X118600Y352000D01*
X119100Y351667D01*
X119683Y351500D01*
X120267Y351583D01*
X120767Y351833D01*
X121100Y352167D01*
G01X123950Y352083D02*
X124367Y351750D01*
X124950Y351500D01*
X125450D01*
X125950Y351667D01*
X126283Y351917D01*
X126450Y352250D01*
X126367Y352750D01*
X126033Y353000D01*
X124533Y353500D01*
X124200Y354083D01*
X124367Y354500D01*
X124700Y354750D01*
X125200Y354833D01*
X125700Y354750D01*
X126200Y354500D01*
G01X129550Y353750D02*
X132217D01*
X131967Y354333D01*
X131550Y354667D01*
X130967Y354833D01*
X130383Y354750D01*
X129883Y354500D01*
X129550Y353917D01*
X129383Y353417D01*
Y352917D01*
X129550Y352417D01*
X129967Y351917D01*
X130467Y351583D01*
X131050Y351500D01*
X131633Y351667D01*
X132217Y352167D01*
G01X135233Y351500D02*
Y354833D01*
G01Y354167D02*
X135650Y354500D01*
X136067Y354750D01*
X136650Y354833D01*
X137067Y354750D01*
X137567Y354500D01*
G01X146100Y354833D02*
X147600Y351500D01*
X149100Y354833D01*
G01X153200D02*
Y351500D01*
G01Y356167D02*
X153033Y356250D01*
Y356417D01*
X153200Y356500D01*
X153367Y356417D01*
Y356250D01*
X153200Y356167D01*
G01X160300Y351500D02*
Y354833D01*
G01Y354250D02*
X159967Y354583D01*
X159467Y354750D01*
X158883Y354833D01*
X158300Y354667D01*
X157800Y354333D01*
X157467Y353833D01*
X157300Y353167D01*
X157467Y352500D01*
X157800Y352000D01*
X158300Y351667D01*
X158883Y351500D01*
X159467Y351583D01*
X159967Y351833D01*
X160300Y352167D01*
G01X168167Y351333D02*
X171833Y355000D01*
G01X170000Y355667D02*
Y350667D01*
G01X171833Y351333D02*
X168167Y355000D01*
G01X167500Y353167D02*
X172500D01*
G01X175183Y349833D02*
X174350Y350667D01*
X173933Y351500D01*
Y354833D01*
X174350Y355667D01*
X175183Y356500D01*
G01X179367Y352250D02*
X179867Y351833D01*
X180450Y351583D01*
X181200Y351500D01*
X181950Y351667D01*
X182533Y352000D01*
X182950Y352583D01*
X183033Y353250D01*
X182867Y353917D01*
X182450Y354333D01*
X181867Y354667D01*
X181283Y354750D01*
X180700Y354667D01*
X179950Y354333D01*
X180200Y356500D01*
X182450D01*
G01X186800Y351333D02*
X186633Y351417D01*
Y351583D01*
X186800Y351667D01*
X186967Y351583D01*
Y351417D01*
X186800Y351333D01*
G01X192400Y351500D02*
Y356500D01*
X191400Y355500D01*
G01Y351500D02*
X193400D01*
G01X198417Y349833D02*
X199250Y350667D01*
X199667Y351500D01*
Y354833D01*
X199250Y355667D01*
X198417Y356500D01*
G01X105000Y364500D02*
X694500D01*
G01X112333Y406500D02*
Y411500D01*
X114333D01*
X115000Y411250D01*
X115500Y410667D01*
X115667Y410000D01*
X115500Y409333D01*
X115083Y408833D01*
X114333Y408583D01*
X112333D01*
G01X119600Y411500D02*
Y406500D01*
G01X117683Y411500D02*
X121517D01*
G01X123450Y406500D02*
Y411500D01*
G01X126950D02*
Y406500D01*
G01Y409000D02*
X123450D01*
G01X135233Y406500D02*
Y409833D01*
G01Y409167D02*
X135650Y409500D01*
X136067Y409750D01*
X136650Y409833D01*
X137067Y409750D01*
X137567Y409500D01*
G01X140750Y408750D02*
X143417D01*
X143167Y409333D01*
X142750Y409667D01*
X142167Y409833D01*
X141583Y409750D01*
X141083Y409500D01*
X140750Y408917D01*
X140583Y408417D01*
Y407917D01*
X140750Y407417D01*
X141167Y406917D01*
X141667Y406583D01*
X142250Y406500D01*
X142833Y406667D01*
X143417Y407167D01*
G01X146433Y405250D02*
X147017Y404917D01*
X147683Y404833D01*
X148267Y404917D01*
X148767Y405333D01*
X149100Y405917D01*
Y409833D01*
G01Y409167D02*
X148767Y409500D01*
X148267Y409750D01*
X147683Y409833D01*
X147017Y409667D01*
X146600Y409333D01*
X146267Y408750D01*
X146100Y408167D01*
X146183Y407667D01*
X146517Y407083D01*
X147017Y406667D01*
X147683Y406500D01*
X148183Y406583D01*
X148767Y406917D01*
X149100Y407250D01*
G01X153200Y409833D02*
Y406500D01*
G01Y411167D02*
X153033Y411250D01*
Y411417D01*
X153200Y411500D01*
X153367Y411417D01*
Y411250D01*
X153200Y411167D01*
G01X157550Y407083D02*
X157967Y406750D01*
X158550Y406500D01*
X159050D01*
X159550Y406667D01*
X159883Y406917D01*
X160050Y407250D01*
X159967Y407750D01*
X159633Y408000D01*
X158133Y408500D01*
X157800Y409083D01*
X157967Y409500D01*
X158300Y409750D01*
X158800Y409833D01*
X159300Y409750D01*
X159800Y409500D01*
G01X164400Y411500D02*
Y406500D01*
G01X163233Y409833D02*
X165567D01*
G01X168833Y406500D02*
Y409833D01*
G01Y409167D02*
X169250Y409500D01*
X169667Y409750D01*
X170250Y409833D01*
X170667Y409750D01*
X171167Y409500D01*
G01X177100Y406500D02*
Y409833D01*
G01Y409250D02*
X176767Y409583D01*
X176267Y409750D01*
X175683Y409833D01*
X175100Y409667D01*
X174600Y409333D01*
X174267Y408833D01*
X174100Y408167D01*
X174267Y407500D01*
X174600Y407000D01*
X175100Y406667D01*
X175683Y406500D01*
X176267Y406583D01*
X176767Y406833D01*
X177100Y407167D01*
G01X181200Y411500D02*
Y406500D01*
G01X180033Y409833D02*
X182367D01*
G01X186800D02*
Y406500D01*
G01Y411167D02*
X186633Y411250D01*
Y411417D01*
X186800Y411500D01*
X186967Y411417D01*
Y411250D01*
X186800Y411167D01*
G01X192400Y406500D02*
X191900Y406583D01*
X191400Y406917D01*
X191067Y407500D01*
X190900Y408167D01*
X191067Y408833D01*
X191400Y409417D01*
X191900Y409750D01*
X192400Y409833D01*
X192900Y409750D01*
X193400Y409417D01*
X193733Y408833D01*
X193817Y408167D01*
X193733Y407500D01*
X193400Y406917D01*
X192900Y406583D01*
X192400Y406500D01*
G01X196583D02*
Y409833D01*
G01Y409000D02*
X196917Y409417D01*
X197417Y409750D01*
X198083Y409833D01*
X198667Y409750D01*
X199167Y409417D01*
X199417Y408833D01*
Y406500D01*
G01X112167Y433000D02*
Y438000D01*
X113833D01*
X114500Y437750D01*
X115000Y437417D01*
X115417Y436917D01*
X115750Y436333D01*
X115833Y435500D01*
X115750Y434667D01*
X115417Y434083D01*
X115000Y433583D01*
X114500Y433250D01*
X113833Y433000D01*
X112167D01*
G01X118350Y435250D02*
X121017D01*
X120767Y435833D01*
X120350Y436167D01*
X119767Y436333D01*
X119183Y436250D01*
X118683Y436000D01*
X118350Y435417D01*
X118183Y434917D01*
Y434417D01*
X118350Y433917D01*
X118767Y433417D01*
X119267Y433083D01*
X119850Y433000D01*
X120433Y433167D01*
X121017Y433667D01*
G01X123700Y431333D02*
Y436333D01*
G01Y435583D02*
X124117Y436000D01*
X124533Y436250D01*
X125200Y436333D01*
X125783Y436250D01*
X126367Y435833D01*
X126617Y435250D01*
X126700Y434667D01*
X126617Y434083D01*
X126367Y433500D01*
X125867Y433167D01*
X125200Y433000D01*
X124617Y433083D01*
X124033Y433333D01*
X123700Y433667D01*
G01X130800Y438000D02*
Y433000D01*
G01X129633Y436333D02*
X131967D01*
G01X134983Y433000D02*
Y438000D01*
G01Y435583D02*
X135400Y436000D01*
X135817Y436250D01*
X136483Y436333D01*
X136983Y436250D01*
X137567Y435917D01*
X137817Y435417D01*
Y433000D01*
G01X148933Y435917D02*
X148350Y436250D01*
X147850Y436333D01*
X147183Y436167D01*
X146683Y435833D01*
X146350Y435250D01*
X146267Y434667D01*
X146350Y434083D01*
X146683Y433583D01*
X147183Y433167D01*
X147850Y433000D01*
X148433Y433167D01*
X148933Y433500D01*
G01X153200Y433000D02*
X152700Y433083D01*
X152200Y433417D01*
X151867Y434000D01*
X151700Y434667D01*
X151867Y435333D01*
X152200Y435917D01*
X152700Y436250D01*
X153200Y436333D01*
X153700Y436250D01*
X154200Y435917D01*
X154533Y435333D01*
X154617Y434667D01*
X154533Y434000D01*
X154200Y433417D01*
X153700Y433083D01*
X153200Y433000D01*
G01X157383D02*
Y436333D01*
G01Y435500D02*
X157717Y435917D01*
X158217Y436250D01*
X158883Y436333D01*
X159467Y436250D01*
X159967Y435917D01*
X160217Y435333D01*
Y433000D01*
G01X164400Y438000D02*
Y433000D01*
G01X163233Y436333D02*
X165567D01*
G01X168833Y433000D02*
Y436333D01*
G01Y435667D02*
X169250Y436000D01*
X169667Y436250D01*
X170250Y436333D01*
X170667Y436250D01*
X171167Y436000D01*
G01X175600Y433000D02*
X175100Y433083D01*
X174600Y433417D01*
X174267Y434000D01*
X174100Y434667D01*
X174267Y435333D01*
X174600Y435917D01*
X175100Y436250D01*
X175600Y436333D01*
X176100Y436250D01*
X176600Y435917D01*
X176933Y435333D01*
X177017Y434667D01*
X176933Y434000D01*
X176600Y433417D01*
X176100Y433083D01*
X175600Y433000D01*
G01X181200D02*
Y438000D01*
G01X190983Y433000D02*
Y438000D01*
G01Y435583D02*
X191400Y436000D01*
X191817Y436250D01*
X192483Y436333D01*
X192983Y436250D01*
X193567Y435917D01*
X193817Y435417D01*
Y433000D01*
G01X198000D02*
X197500Y433083D01*
X197000Y433417D01*
X196667Y434000D01*
X196500Y434667D01*
X196667Y435333D01*
X197000Y435917D01*
X197500Y436250D01*
X198000Y436333D01*
X198500Y436250D01*
X199000Y435917D01*
X199333Y435333D01*
X199417Y434667D01*
X199333Y434000D01*
X199000Y433417D01*
X198500Y433083D01*
X198000Y433000D01*
G01X203600D02*
Y438000D01*
G01X207950Y435250D02*
X210617D01*
X210367Y435833D01*
X209950Y436167D01*
X209367Y436333D01*
X208783Y436250D01*
X208283Y436000D01*
X207950Y435417D01*
X207783Y434917D01*
Y434417D01*
X207950Y433917D01*
X208367Y433417D01*
X208867Y433083D01*
X209450Y433000D01*
X210033Y433167D01*
X210617Y433667D01*
G01X112333Y455000D02*
Y460000D01*
X114417D01*
X115083Y459750D01*
X115500Y459417D01*
X115667Y458750D01*
X115500Y458083D01*
X115000Y457667D01*
X114417Y457417D01*
X112333D01*
G01X114417D02*
X115667Y455000D01*
G01X119600D02*
X119100Y455083D01*
X118600Y455417D01*
X118267Y456000D01*
X118100Y456667D01*
X118267Y457333D01*
X118600Y457917D01*
X119100Y458250D01*
X119600Y458333D01*
X120100Y458250D01*
X120600Y457917D01*
X120933Y457333D01*
X121017Y456667D01*
X120933Y456000D01*
X120600Y455417D01*
X120100Y455083D01*
X119600Y455000D01*
G01X123783Y458333D02*
Y456000D01*
X124117Y455417D01*
X124617Y455083D01*
X125200Y455000D01*
X125783Y455083D01*
X126283Y455417D01*
X126617Y456000D01*
G01Y455000D02*
Y458333D01*
G01X129633Y453750D02*
X130217Y453417D01*
X130883Y453333D01*
X131467Y453417D01*
X131967Y453833D01*
X132300Y454417D01*
Y458333D01*
G01Y457667D02*
X131967Y458000D01*
X131467Y458250D01*
X130883Y458333D01*
X130217Y458167D01*
X129800Y457833D01*
X129467Y457250D01*
X129300Y456667D01*
X129383Y456167D01*
X129717Y455583D01*
X130217Y455167D01*
X130883Y455000D01*
X131383Y455083D01*
X131967Y455417D01*
X132300Y455750D01*
G01X134983Y455000D02*
Y460000D01*
G01Y457583D02*
X135400Y458000D01*
X135817Y458250D01*
X136483Y458333D01*
X136983Y458250D01*
X137567Y457917D01*
X137817Y457417D01*
Y455000D01*
G01X140583D02*
Y458333D01*
G01Y457500D02*
X140917Y457917D01*
X141417Y458250D01*
X142083Y458333D01*
X142667Y458250D01*
X143167Y457917D01*
X143417Y457333D01*
Y455000D01*
G01X146350Y457250D02*
X149017D01*
X148767Y457833D01*
X148350Y458167D01*
X147767Y458333D01*
X147183Y458250D01*
X146683Y458000D01*
X146350Y457417D01*
X146183Y456917D01*
Y456417D01*
X146350Y455917D01*
X146767Y455417D01*
X147267Y455083D01*
X147850Y455000D01*
X148433Y455167D01*
X149017Y455667D01*
G01X151950Y455583D02*
X152367Y455250D01*
X152950Y455000D01*
X153450D01*
X153950Y455167D01*
X154283Y455417D01*
X154450Y455750D01*
X154367Y456250D01*
X154033Y456500D01*
X152533Y457000D01*
X152200Y457583D01*
X152367Y458000D01*
X152700Y458250D01*
X153200Y458333D01*
X153700Y458250D01*
X154200Y458000D01*
G01X157550Y455583D02*
X157967Y455250D01*
X158550Y455000D01*
X159050D01*
X159550Y455167D01*
X159883Y455417D01*
X160050Y455750D01*
X159967Y456250D01*
X159633Y456500D01*
X158133Y457000D01*
X157800Y457583D01*
X157967Y458000D01*
X158300Y458250D01*
X158800Y458333D01*
X159300Y458250D01*
X159800Y458000D01*
G01X103500Y449000D02*
X694500D01*
G01X104000Y464000D02*
X694500D01*
G01X103500Y424000D02*
X694500D01*
G01X112250Y513500D02*
Y518500D01*
G01X115750D02*
Y513500D01*
G01Y516000D02*
X112250D01*
G01X119600Y513500D02*
X119100Y513583D01*
X118600Y513917D01*
X118267Y514500D01*
X118100Y515167D01*
X118267Y515833D01*
X118600Y516417D01*
X119100Y516750D01*
X119600Y516833D01*
X120100Y516750D01*
X120600Y516417D01*
X120933Y515833D01*
X121017Y515167D01*
X120933Y514500D01*
X120600Y513917D01*
X120100Y513583D01*
X119600Y513500D01*
G01X125200D02*
Y518500D01*
G01X129550Y515750D02*
X132217D01*
X131967Y516333D01*
X131550Y516667D01*
X130967Y516833D01*
X130383Y516750D01*
X129883Y516500D01*
X129550Y515917D01*
X129383Y515417D01*
Y514917D01*
X129550Y514417D01*
X129967Y513917D01*
X130467Y513583D01*
X131050Y513500D01*
X131633Y513667D01*
X132217Y514167D01*
G01X140750Y514083D02*
X141167Y513750D01*
X141750Y513500D01*
X142250D01*
X142750Y513667D01*
X143083Y513917D01*
X143250Y514250D01*
X143167Y514750D01*
X142833Y515000D01*
X141333Y515500D01*
X141000Y516083D01*
X141167Y516500D01*
X141500Y516750D01*
X142000Y516833D01*
X142500Y516750D01*
X143000Y516500D01*
G01X147600Y516833D02*
Y513500D01*
G01Y518167D02*
X147433Y518250D01*
Y518417D01*
X147600Y518500D01*
X147767Y518417D01*
Y518250D01*
X147600Y518167D01*
G01X151950Y516833D02*
X154450D01*
X151950Y513500D01*
X154450D01*
G01X157550Y515750D02*
X160217D01*
X159967Y516333D01*
X159550Y516667D01*
X158967Y516833D01*
X158383Y516750D01*
X157883Y516500D01*
X157550Y515917D01*
X157383Y515417D01*
Y514917D01*
X157550Y514417D01*
X157967Y513917D01*
X158467Y513583D01*
X159050Y513500D01*
X159633Y513667D01*
X160217Y514167D01*
G01X111917Y610000D02*
X114000Y605000D01*
X116083Y610000D01*
G01X119600Y608333D02*
Y605000D01*
G01Y609667D02*
X119433Y609750D01*
Y609917D01*
X119600Y610000D01*
X119767Y609917D01*
Y609750D01*
X119600Y609667D01*
G01X126700Y605000D02*
Y608333D01*
G01Y607750D02*
X126367Y608083D01*
X125867Y608250D01*
X125283Y608333D01*
X124700Y608167D01*
X124200Y607833D01*
X123867Y607333D01*
X123700Y606667D01*
X123867Y606000D01*
X124200Y605500D01*
X124700Y605167D01*
X125283Y605000D01*
X125867Y605083D01*
X126367Y605333D01*
X126700Y605667D01*
G01X134983Y605000D02*
Y610000D01*
G01Y607583D02*
X135400Y608000D01*
X135817Y608250D01*
X136483Y608333D01*
X136983Y608250D01*
X137567Y607917D01*
X137817Y607417D01*
Y605000D01*
G01X142000D02*
X141500Y605083D01*
X141000Y605417D01*
X140667Y606000D01*
X140500Y606667D01*
X140667Y607333D01*
X141000Y607917D01*
X141500Y608250D01*
X142000Y608333D01*
X142500Y608250D01*
X143000Y607917D01*
X143333Y607333D01*
X143417Y606667D01*
X143333Y606000D01*
X143000Y605417D01*
X142500Y605083D01*
X142000Y605000D01*
G01X147600D02*
Y610000D01*
G01X151950Y607250D02*
X154617D01*
X154367Y607833D01*
X153950Y608167D01*
X153367Y608333D01*
X152783Y608250D01*
X152283Y608000D01*
X151950Y607417D01*
X151783Y606917D01*
Y606417D01*
X151950Y605917D01*
X152367Y605417D01*
X152867Y605083D01*
X153450Y605000D01*
X154033Y605167D01*
X154617Y605667D01*
G01X164400Y610000D02*
Y605000D01*
G01X163233Y608333D02*
X165567D01*
G01X168583Y605000D02*
Y610000D01*
G01Y607583D02*
X169000Y608000D01*
X169417Y608250D01*
X170083Y608333D01*
X170583Y608250D01*
X171167Y607917D01*
X171417Y607417D01*
Y605000D01*
G01X174350Y607250D02*
X177017D01*
X176767Y607833D01*
X176350Y608167D01*
X175767Y608333D01*
X175183Y608250D01*
X174683Y608000D01*
X174350Y607417D01*
X174183Y606917D01*
Y606417D01*
X174350Y605917D01*
X174767Y605417D01*
X175267Y605083D01*
X175850Y605000D01*
X176433Y605167D01*
X177017Y605667D01*
G01X180033Y605000D02*
Y608333D01*
G01Y607667D02*
X180450Y608000D01*
X180867Y608250D01*
X181450Y608333D01*
X181867Y608250D01*
X182367Y608000D01*
G01X184300Y605000D02*
Y608333D01*
G01Y607417D02*
X184550Y607833D01*
X184967Y608167D01*
X185550Y608333D01*
X186133Y608167D01*
X186550Y607833D01*
X186800Y607417D01*
Y605000D01*
G01Y607417D02*
X187050Y607833D01*
X187467Y608167D01*
X188050Y608333D01*
X188633Y608167D01*
X189050Y607833D01*
X189300Y607333D01*
Y605000D01*
G01X193900D02*
Y608333D01*
G01Y607750D02*
X193567Y608083D01*
X193067Y608250D01*
X192483Y608333D01*
X191900Y608167D01*
X191400Y607833D01*
X191067Y607333D01*
X190900Y606667D01*
X191067Y606000D01*
X191400Y605500D01*
X191900Y605167D01*
X192483Y605000D01*
X193067Y605083D01*
X193567Y605333D01*
X193900Y605667D01*
G01X198000Y605000D02*
Y610000D01*
G01X207700Y603333D02*
Y608333D01*
G01Y607583D02*
X208117Y608000D01*
X208533Y608250D01*
X209200Y608333D01*
X209783Y608250D01*
X210367Y607833D01*
X210617Y607250D01*
X210700Y606667D01*
X210617Y606083D01*
X210367Y605500D01*
X209867Y605167D01*
X209200Y605000D01*
X208617Y605083D01*
X208033Y605333D01*
X207700Y605667D01*
G01X216300Y605000D02*
Y608333D01*
G01Y607750D02*
X215967Y608083D01*
X215467Y608250D01*
X214883Y608333D01*
X214300Y608167D01*
X213800Y607833D01*
X213467Y607333D01*
X213300Y606667D01*
X213467Y606000D01*
X213800Y605500D01*
X214300Y605167D01*
X214883Y605000D01*
X215467Y605083D01*
X215967Y605333D01*
X216300Y605667D01*
G01X221900Y610000D02*
Y605000D01*
G01Y605750D02*
X221567Y605333D01*
X221067Y605083D01*
X220483Y605000D01*
X219817Y605167D01*
X219317Y605583D01*
X218983Y606083D01*
X218900Y606667D01*
X218983Y607250D01*
X219317Y607750D01*
X219817Y608167D01*
X220483Y608333D01*
X221067Y608250D01*
X221483Y608083D01*
X221900Y607750D01*
G01X112250Y588500D02*
Y593500D01*
G01X115750D02*
Y588500D01*
G01Y591000D02*
X112250D01*
G01X119600Y588500D02*
X119100Y588583D01*
X118600Y588917D01*
X118267Y589500D01*
X118100Y590167D01*
X118267Y590833D01*
X118600Y591417D01*
X119100Y591750D01*
X119600Y591833D01*
X120100Y591750D01*
X120600Y591417D01*
X120933Y590833D01*
X121017Y590167D01*
X120933Y589500D01*
X120600Y588917D01*
X120100Y588583D01*
X119600Y588500D01*
G01X125200D02*
Y593500D01*
G01X129550Y590750D02*
X132217D01*
X131967Y591333D01*
X131550Y591667D01*
X130967Y591833D01*
X130383Y591750D01*
X129883Y591500D01*
X129550Y590917D01*
X129383Y590417D01*
Y589917D01*
X129550Y589417D01*
X129967Y588917D01*
X130467Y588583D01*
X131050Y588500D01*
X131633Y588667D01*
X132217Y589167D01*
G01X140500Y586833D02*
Y591833D01*
G01Y591083D02*
X140917Y591500D01*
X141333Y591750D01*
X142000Y591833D01*
X142583Y591750D01*
X143167Y591333D01*
X143417Y590750D01*
X143500Y590167D01*
X143417Y589583D01*
X143167Y589000D01*
X142667Y588667D01*
X142000Y588500D01*
X141417Y588583D01*
X140833Y588833D01*
X140500Y589167D01*
G01X147600Y588500D02*
X147100Y588583D01*
X146600Y588917D01*
X146267Y589500D01*
X146100Y590167D01*
X146267Y590833D01*
X146600Y591417D01*
X147100Y591750D01*
X147600Y591833D01*
X148100Y591750D01*
X148600Y591417D01*
X148933Y590833D01*
X149017Y590167D01*
X148933Y589500D01*
X148600Y588917D01*
X148100Y588583D01*
X147600Y588500D01*
G01X151950Y589083D02*
X152367Y588750D01*
X152950Y588500D01*
X153450D01*
X153950Y588667D01*
X154283Y588917D01*
X154450Y589250D01*
X154367Y589750D01*
X154033Y590000D01*
X152533Y590500D01*
X152200Y591083D01*
X152367Y591500D01*
X152700Y591750D01*
X153200Y591833D01*
X153700Y591750D01*
X154200Y591500D01*
G01X158800Y591833D02*
Y588500D01*
G01Y593167D02*
X158633Y593250D01*
Y593417D01*
X158800Y593500D01*
X158967Y593417D01*
Y593250D01*
X158800Y593167D01*
G01X164400Y593500D02*
Y588500D01*
G01X163233Y591833D02*
X165567D01*
G01X170000D02*
Y588500D01*
G01Y593167D02*
X169833Y593250D01*
Y593417D01*
X170000Y593500D01*
X170167Y593417D01*
Y593250D01*
X170000Y593167D01*
G01X175600Y588500D02*
X175100Y588583D01*
X174600Y588917D01*
X174267Y589500D01*
X174100Y590167D01*
X174267Y590833D01*
X174600Y591417D01*
X175100Y591750D01*
X175600Y591833D01*
X176100Y591750D01*
X176600Y591417D01*
X176933Y590833D01*
X177017Y590167D01*
X176933Y589500D01*
X176600Y588917D01*
X176100Y588583D01*
X175600Y588500D01*
G01X179783D02*
Y591833D01*
G01Y591000D02*
X180117Y591417D01*
X180617Y591750D01*
X181283Y591833D01*
X181867Y591750D01*
X182367Y591417D01*
X182617Y590833D01*
Y588500D01*
G01X192400Y593500D02*
Y588500D01*
G01X191233Y591833D02*
X193567D01*
G01X198000Y588500D02*
X197500Y588583D01*
X197000Y588917D01*
X196667Y589500D01*
X196500Y590167D01*
X196667Y590833D01*
X197000Y591417D01*
X197500Y591750D01*
X198000Y591833D01*
X198500Y591750D01*
X199000Y591417D01*
X199333Y590833D01*
X199417Y590167D01*
X199333Y589500D01*
X199000Y588917D01*
X198500Y588583D01*
X198000Y588500D01*
G01X203600D02*
Y593500D01*
G01X207950Y590750D02*
X210617D01*
X210367Y591333D01*
X209950Y591667D01*
X209367Y591833D01*
X208783Y591750D01*
X208283Y591500D01*
X207950Y590917D01*
X207783Y590417D01*
Y589917D01*
X207950Y589417D01*
X208367Y588917D01*
X208867Y588583D01*
X209450Y588500D01*
X210033Y588667D01*
X210617Y589167D01*
G01X213633Y588500D02*
Y591833D01*
G01Y591167D02*
X214050Y591500D01*
X214467Y591750D01*
X215050Y591833D01*
X215467Y591750D01*
X215967Y591500D01*
G01X221900Y588500D02*
Y591833D01*
G01Y591250D02*
X221567Y591583D01*
X221067Y591750D01*
X220483Y591833D01*
X219900Y591667D01*
X219400Y591333D01*
X219067Y590833D01*
X218900Y590167D01*
X219067Y589500D01*
X219400Y589000D01*
X219900Y588667D01*
X220483Y588500D01*
X221067Y588583D01*
X221567Y588833D01*
X221900Y589167D01*
G01X224583Y588500D02*
Y591833D01*
G01Y591000D02*
X224917Y591417D01*
X225417Y591750D01*
X226083Y591833D01*
X226667Y591750D01*
X227167Y591417D01*
X227417Y590833D01*
Y588500D01*
G01X232933Y591417D02*
X232350Y591750D01*
X231850Y591833D01*
X231183Y591667D01*
X230683Y591333D01*
X230350Y590750D01*
X230267Y590167D01*
X230350Y589583D01*
X230683Y589083D01*
X231183Y588667D01*
X231850Y588500D01*
X232433Y588667D01*
X232933Y589000D01*
G01X235950Y590750D02*
X238617D01*
X238367Y591333D01*
X237950Y591667D01*
X237367Y591833D01*
X236783Y591750D01*
X236283Y591500D01*
X235950Y590917D01*
X235783Y590417D01*
Y589917D01*
X235950Y589417D01*
X236367Y588917D01*
X236867Y588583D01*
X237450Y588500D01*
X238033Y588667D01*
X238617Y589167D01*
G01X111917Y620000D02*
X114000Y625000D01*
X116083Y620000D01*
G01X115333Y621750D02*
X112667D01*
G01X118183Y620000D02*
Y623333D01*
G01Y622500D02*
X118517Y622917D01*
X119017Y623250D01*
X119683Y623333D01*
X120267Y623250D01*
X120767Y622917D01*
X121017Y622333D01*
Y620000D01*
G01X125200Y625000D02*
Y620000D01*
G01X124033Y623333D02*
X126367D01*
G01X130800D02*
Y620000D01*
G01Y624667D02*
X130633Y624750D01*
Y624917D01*
X130800Y625000D01*
X130967Y624917D01*
Y624750D01*
X130800Y624667D01*
G01X135317Y621667D02*
X137483D01*
G01X146100Y618333D02*
Y623333D01*
G01Y622583D02*
X146517Y623000D01*
X146933Y623250D01*
X147600Y623333D01*
X148183Y623250D01*
X148767Y622833D01*
X149017Y622250D01*
X149100Y621667D01*
X149017Y621083D01*
X148767Y620500D01*
X148267Y620167D01*
X147600Y620000D01*
X147017Y620083D01*
X146433Y620333D01*
X146100Y620667D01*
G01X154700Y620000D02*
Y623333D01*
G01Y622750D02*
X154367Y623083D01*
X153867Y623250D01*
X153283Y623333D01*
X152700Y623167D01*
X152200Y622833D01*
X151867Y622333D01*
X151700Y621667D01*
X151867Y621000D01*
X152200Y620500D01*
X152700Y620167D01*
X153283Y620000D01*
X153867Y620083D01*
X154367Y620333D01*
X154700Y620667D01*
G01X160300Y625000D02*
Y620000D01*
G01Y620750D02*
X159967Y620333D01*
X159467Y620083D01*
X158883Y620000D01*
X158217Y620167D01*
X157717Y620583D01*
X157383Y621083D01*
X157300Y621667D01*
X157383Y622250D01*
X157717Y622750D01*
X158217Y623167D01*
X158883Y623333D01*
X159467Y623250D01*
X159883Y623083D01*
X160300Y622750D01*
G01X111843Y639590D02*
Y644590D01*
X115677Y639590D01*
Y644590D01*
G01X119360Y639590D02*
X118860Y639673D01*
X118360Y640007D01*
X118027Y640590D01*
X117860Y641257D01*
X118027Y641923D01*
X118360Y642507D01*
X118860Y642840D01*
X119360Y642923D01*
X119860Y642840D01*
X120360Y642507D01*
X120693Y641923D01*
X120777Y641257D01*
X120693Y640590D01*
X120360Y640007D01*
X119860Y639673D01*
X119360Y639590D01*
G01X123543D02*
Y642923D01*
G01Y642090D02*
X123877Y642507D01*
X124377Y642840D01*
X125043Y642923D01*
X125627Y642840D01*
X126127Y642507D01*
X126377Y641923D01*
Y639590D01*
G01X129477Y641257D02*
X131643D01*
G01X135660Y639590D02*
Y643840D01*
X135827Y644257D01*
X136160Y644507D01*
X136660Y644590D01*
X137160Y644423D01*
X137410Y644007D01*
G01X136410Y642590D02*
X134743D01*
G01X140343Y642923D02*
Y640590D01*
X140677Y640007D01*
X141177Y639673D01*
X141760Y639590D01*
X142343Y639673D01*
X142843Y640007D01*
X143177Y640590D01*
G01Y639590D02*
Y642923D01*
G01X145943Y639590D02*
Y642923D01*
G01Y642090D02*
X146277Y642507D01*
X146777Y642840D01*
X147443Y642923D01*
X148027Y642840D01*
X148527Y642507D01*
X148777Y641923D01*
Y639590D01*
G01X154293Y642507D02*
X153710Y642840D01*
X153210Y642923D01*
X152543Y642757D01*
X152043Y642423D01*
X151710Y641840D01*
X151627Y641257D01*
X151710Y640673D01*
X152043Y640173D01*
X152543Y639757D01*
X153210Y639590D01*
X153793Y639757D01*
X154293Y640090D01*
G01X158560Y644590D02*
Y639590D01*
G01X157393Y642923D02*
X159727D01*
G01X164160D02*
Y639590D01*
G01Y644257D02*
X163993Y644340D01*
Y644507D01*
X164160Y644590D01*
X164327Y644507D01*
Y644340D01*
X164160Y644257D01*
G01X169760Y639590D02*
X169260Y639673D01*
X168760Y640007D01*
X168427Y640590D01*
X168260Y641257D01*
X168427Y641923D01*
X168760Y642507D01*
X169260Y642840D01*
X169760Y642923D01*
X170260Y642840D01*
X170760Y642507D01*
X171093Y641923D01*
X171177Y641257D01*
X171093Y640590D01*
X170760Y640007D01*
X170260Y639673D01*
X169760Y639590D01*
G01X173943D02*
Y642923D01*
G01Y642090D02*
X174277Y642507D01*
X174777Y642840D01*
X175443Y642923D01*
X176027Y642840D01*
X176527Y642507D01*
X176777Y641923D01*
Y639590D01*
G01X182460D02*
Y642923D01*
G01Y642340D02*
X182127Y642673D01*
X181627Y642840D01*
X181043Y642923D01*
X180460Y642757D01*
X179960Y642423D01*
X179627Y641923D01*
X179460Y641257D01*
X179627Y640590D01*
X179960Y640090D01*
X180460Y639757D01*
X181043Y639590D01*
X181627Y639673D01*
X182127Y639923D01*
X182460Y640257D01*
G01X186560Y639590D02*
Y644590D01*
G01X196260Y637923D02*
Y642923D01*
G01Y642173D02*
X196677Y642590D01*
X197093Y642840D01*
X197760Y642923D01*
X198343Y642840D01*
X198927Y642423D01*
X199177Y641840D01*
X199260Y641257D01*
X199177Y640673D01*
X198927Y640090D01*
X198427Y639757D01*
X197760Y639590D01*
X197177Y639673D01*
X196593Y639923D01*
X196260Y640257D01*
G01X204860Y639590D02*
Y642923D01*
G01Y642340D02*
X204527Y642673D01*
X204027Y642840D01*
X203443Y642923D01*
X202860Y642757D01*
X202360Y642423D01*
X202027Y641923D01*
X201860Y641257D01*
X202027Y640590D01*
X202360Y640090D01*
X202860Y639757D01*
X203443Y639590D01*
X204027Y639673D01*
X204527Y639923D01*
X204860Y640257D01*
G01X210460Y644590D02*
Y639590D01*
G01Y640340D02*
X210127Y639923D01*
X209627Y639673D01*
X209043Y639590D01*
X208377Y639757D01*
X207877Y640173D01*
X207543Y640673D01*
X207460Y641257D01*
X207543Y641840D01*
X207877Y642340D01*
X208377Y642757D01*
X209043Y642923D01*
X209627Y642840D01*
X210043Y642673D01*
X210460Y642340D01*
G01X160333Y668083D02*
X159833Y668333D01*
X159250Y668500D01*
X158583D01*
X157833Y668250D01*
X157250Y667833D01*
X156833Y667333D01*
X156500Y666500D01*
X156417Y665750D01*
X156583Y665000D01*
X156833Y664500D01*
X157333Y664000D01*
X157917Y663667D01*
X158500Y663500D01*
X159083D01*
X159667Y663667D01*
X160167Y663917D01*
X160583Y664250D01*
G01X164100Y663500D02*
Y668500D01*
G01X171200Y663500D02*
Y666833D01*
G01Y666250D02*
X170867Y666583D01*
X170367Y666750D01*
X169783Y666833D01*
X169200Y666667D01*
X168700Y666333D01*
X168367Y665833D01*
X168200Y665167D01*
X168367Y664500D01*
X168700Y664000D01*
X169200Y663667D01*
X169783Y663500D01*
X170367Y663583D01*
X170867Y663833D01*
X171200Y664167D01*
G01X174050Y664083D02*
X174467Y663750D01*
X175050Y663500D01*
X175550D01*
X176050Y663667D01*
X176383Y663917D01*
X176550Y664250D01*
X176467Y664750D01*
X176133Y665000D01*
X174633Y665500D01*
X174300Y666083D01*
X174467Y666500D01*
X174800Y666750D01*
X175300Y666833D01*
X175800Y666750D01*
X176300Y666500D01*
G01X179650Y664083D02*
X180067Y663750D01*
X180650Y663500D01*
X181150D01*
X181650Y663667D01*
X181983Y663917D01*
X182150Y664250D01*
X182067Y664750D01*
X181733Y665000D01*
X180233Y665500D01*
X179900Y666083D01*
X180067Y666500D01*
X180400Y666750D01*
X180900Y666833D01*
X181400Y666750D01*
X181900Y666500D01*
G01X186500Y666833D02*
Y663500D01*
G01Y668167D02*
X186333Y668250D01*
Y668417D01*
X186500Y668500D01*
X186667Y668417D01*
Y668250D01*
X186500Y668167D01*
G01X191600Y663500D02*
Y667750D01*
X191767Y668167D01*
X192100Y668417D01*
X192600Y668500D01*
X193100Y668333D01*
X193350Y667917D01*
G01X192350Y666500D02*
X190683D01*
G01X195950Y662000D02*
X196450Y661833D01*
X197117Y662000D01*
X197533Y662333D01*
X197867Y662750D01*
X198367Y664083D01*
X199450Y666833D01*
G01X196783D02*
X198367Y664083D01*
G01X103500Y614000D02*
X694500D01*
G01X103500Y584000D02*
X694500D01*
G01X103500Y629000D02*
X694500D01*
G01X272500Y0D02*
Y-5000D01*
G01X270583Y0D02*
X274417D01*
G01X276683Y-5000D02*
Y0D01*
G01Y-2417D02*
X277100Y-2000D01*
X277517Y-1750D01*
X278183Y-1667D01*
X278683Y-1750D01*
X279267Y-2083D01*
X279517Y-2583D01*
Y-5000D01*
G01X282450Y-2750D02*
X285117D01*
X284867Y-2167D01*
X284450Y-1833D01*
X283867Y-1667D01*
X283283Y-1750D01*
X282783Y-2000D01*
X282450Y-2583D01*
X282283Y-3083D01*
Y-3583D01*
X282450Y-4083D01*
X282867Y-4583D01*
X283367Y-4917D01*
X283950Y-5000D01*
X284533Y-4833D01*
X285117Y-4333D01*
G01X294900Y-5000D02*
Y0D01*
G01X302000Y-5000D02*
Y-1667D01*
G01Y-2250D02*
X301667Y-1917D01*
X301167Y-1750D01*
X300583Y-1667D01*
X300000Y-1833D01*
X299500Y-2167D01*
X299167Y-2667D01*
X299000Y-3333D01*
X299167Y-4000D01*
X299500Y-4500D01*
X300000Y-4833D01*
X300583Y-5000D01*
X301167Y-4917D01*
X301667Y-4667D01*
X302000Y-4333D01*
G01X304933Y-5000D02*
Y-1667D01*
G01Y-2333D02*
X305350Y-2000D01*
X305767Y-1750D01*
X306350Y-1667D01*
X306767Y-1750D01*
X307267Y-2000D01*
G01X310533Y-6250D02*
X311117Y-6583D01*
X311783Y-6667D01*
X312367Y-6583D01*
X312867Y-6167D01*
X313200Y-5583D01*
Y-1667D01*
G01Y-2333D02*
X312867Y-2000D01*
X312367Y-1750D01*
X311783Y-1667D01*
X311117Y-1833D01*
X310700Y-2167D01*
X310367Y-2750D01*
X310200Y-3333D01*
X310283Y-3833D01*
X310617Y-4417D01*
X311117Y-4833D01*
X311783Y-5000D01*
X312283Y-4917D01*
X312867Y-4583D01*
X313200Y-4250D01*
G01X316050Y-2750D02*
X318717D01*
X318467Y-2167D01*
X318050Y-1833D01*
X317467Y-1667D01*
X316883Y-1750D01*
X316383Y-2000D01*
X316050Y-2583D01*
X315883Y-3083D01*
Y-3583D01*
X316050Y-4083D01*
X316467Y-4583D01*
X316967Y-4917D01*
X317550Y-5000D01*
X318133Y-4833D01*
X318717Y-4333D01*
G01X321650Y-4417D02*
X322067Y-4750D01*
X322650Y-5000D01*
X323150D01*
X323650Y-4833D01*
X323983Y-4583D01*
X324150Y-4250D01*
X324067Y-3750D01*
X323733Y-3500D01*
X322233Y-3000D01*
X321900Y-2417D01*
X322067Y-2000D01*
X322400Y-1750D01*
X322900Y-1667D01*
X323400Y-1750D01*
X323900Y-2000D01*
G01X328500Y0D02*
Y-5000D01*
G01X327333Y-1667D02*
X329667D01*
G01X341200Y0D02*
Y-5000D01*
G01Y-4250D02*
X340867Y-4667D01*
X340367Y-4917D01*
X339783Y-5000D01*
X339117Y-4833D01*
X338617Y-4417D01*
X338283Y-3917D01*
X338200Y-3333D01*
X338283Y-2750D01*
X338617Y-2250D01*
X339117Y-1833D01*
X339783Y-1667D01*
X340367Y-1750D01*
X340783Y-1917D01*
X341200Y-2250D01*
G01X345300Y-1667D02*
Y-5000D01*
G01Y-333D02*
X345133Y-250D01*
Y-83D01*
X345300Y0D01*
X345467Y-83D01*
Y-250D01*
X345300Y-333D01*
G01X348400Y-5000D02*
Y-1667D01*
G01Y-2583D02*
X348650Y-2167D01*
X349067Y-1833D01*
X349650Y-1667D01*
X350233Y-1833D01*
X350650Y-2167D01*
X350900Y-2583D01*
Y-5000D01*
G01Y-2583D02*
X351150Y-2167D01*
X351567Y-1833D01*
X352150Y-1667D01*
X352733Y-1833D01*
X353150Y-2167D01*
X353400Y-2667D01*
Y-5000D01*
G01X355250Y-2750D02*
X357917D01*
X357667Y-2167D01*
X357250Y-1833D01*
X356667Y-1667D01*
X356083Y-1750D01*
X355583Y-2000D01*
X355250Y-2583D01*
X355083Y-3083D01*
Y-3583D01*
X355250Y-4083D01*
X355667Y-4583D01*
X356167Y-4917D01*
X356750Y-5000D01*
X357333Y-4833D01*
X357917Y-4333D01*
G01X360683Y-5000D02*
Y-1667D01*
G01Y-2500D02*
X361017Y-2083D01*
X361517Y-1750D01*
X362183Y-1667D01*
X362767Y-1750D01*
X363267Y-2083D01*
X363517Y-2667D01*
Y-5000D01*
G01X366450Y-4417D02*
X366867Y-4750D01*
X367450Y-5000D01*
X367950D01*
X368450Y-4833D01*
X368783Y-4583D01*
X368950Y-4250D01*
X368867Y-3750D01*
X368533Y-3500D01*
X367033Y-3000D01*
X366700Y-2417D01*
X366867Y-2000D01*
X367200Y-1750D01*
X367700Y-1667D01*
X368200Y-1750D01*
X368700Y-2000D01*
G01X373300Y-1667D02*
Y-5000D01*
G01Y-333D02*
X373133Y-250D01*
Y-83D01*
X373300Y0D01*
X373467Y-83D01*
Y-250D01*
X373300Y-333D01*
G01X378900Y-5000D02*
X378400Y-4917D01*
X377900Y-4583D01*
X377567Y-4000D01*
X377400Y-3333D01*
X377567Y-2667D01*
X377900Y-2083D01*
X378400Y-1750D01*
X378900Y-1667D01*
X379400Y-1750D01*
X379900Y-2083D01*
X380233Y-2667D01*
X380317Y-3333D01*
X380233Y-4000D01*
X379900Y-4583D01*
X379400Y-4917D01*
X378900Y-5000D01*
G01X383083D02*
Y-1667D01*
G01Y-2500D02*
X383417Y-2083D01*
X383917Y-1750D01*
X384583Y-1667D01*
X385167Y-1750D01*
X385667Y-2083D01*
X385917Y-2667D01*
Y-5000D01*
G01X395700D02*
X395200Y-4917D01*
X394700Y-4583D01*
X394367Y-4000D01*
X394200Y-3333D01*
X394367Y-2667D01*
X394700Y-2083D01*
X395200Y-1750D01*
X395700Y-1667D01*
X396200Y-1750D01*
X396700Y-2083D01*
X397033Y-2667D01*
X397117Y-3333D01*
X397033Y-4000D01*
X396700Y-4583D01*
X396200Y-4917D01*
X395700Y-5000D01*
G01X400800D02*
Y-750D01*
X400967Y-333D01*
X401300Y-83D01*
X401800Y0D01*
X402300Y-167D01*
X402550Y-583D01*
G01X401550Y-2000D02*
X399883D01*
G01X411000Y-6667D02*
Y-1667D01*
G01Y-2417D02*
X411417Y-2000D01*
X411833Y-1750D01*
X412500Y-1667D01*
X413083Y-1750D01*
X413667Y-2167D01*
X413917Y-2750D01*
X414000Y-3333D01*
X413917Y-3917D01*
X413667Y-4500D01*
X413167Y-4833D01*
X412500Y-5000D01*
X411917Y-4917D01*
X411333Y-4667D01*
X411000Y-4333D01*
G01X419600Y-5000D02*
Y-1667D01*
G01Y-2250D02*
X419267Y-1917D01*
X418767Y-1750D01*
X418183Y-1667D01*
X417600Y-1833D01*
X417100Y-2167D01*
X416767Y-2667D01*
X416600Y-3333D01*
X416767Y-4000D01*
X417100Y-4500D01*
X417600Y-4833D01*
X418183Y-5000D01*
X418767Y-4917D01*
X419267Y-4667D01*
X419600Y-4333D01*
G01X425200Y0D02*
Y-5000D01*
G01Y-4250D02*
X424867Y-4667D01*
X424367Y-4917D01*
X423783Y-5000D01*
X423117Y-4833D01*
X422617Y-4417D01*
X422283Y-3917D01*
X422200Y-3333D01*
X422283Y-2750D01*
X422617Y-2250D01*
X423117Y-1833D01*
X423783Y-1667D01*
X424367Y-1750D01*
X424783Y-1917D01*
X425200Y-2250D01*
G01X434900Y-5000D02*
X434400Y-4917D01*
X433900Y-4583D01*
X433567Y-4000D01*
X433400Y-3333D01*
X433567Y-2667D01*
X433900Y-2083D01*
X434400Y-1750D01*
X434900Y-1667D01*
X435400Y-1750D01*
X435900Y-2083D01*
X436233Y-2667D01*
X436317Y-3333D01*
X436233Y-4000D01*
X435900Y-4583D01*
X435400Y-4917D01*
X434900Y-5000D01*
G01X439333D02*
Y-1667D01*
G01Y-2333D02*
X439750Y-2000D01*
X440167Y-1750D01*
X440750Y-1667D01*
X441167Y-1750D01*
X441667Y-2000D01*
G01X453200Y0D02*
Y-5000D01*
G01Y-4250D02*
X452867Y-4667D01*
X452367Y-4917D01*
X451783Y-5000D01*
X451117Y-4833D01*
X450617Y-4417D01*
X450283Y-3917D01*
X450200Y-3333D01*
X450283Y-2750D01*
X450617Y-2250D01*
X451117Y-1833D01*
X451783Y-1667D01*
X452367Y-1750D01*
X452783Y-1917D01*
X453200Y-2250D01*
G01X457300Y-1667D02*
Y-5000D01*
G01Y-333D02*
X457133Y-250D01*
Y-83D01*
X457300Y0D01*
X457467Y-83D01*
Y-250D01*
X457300Y-333D01*
G01X464400Y-5000D02*
Y-1667D01*
G01Y-2250D02*
X464067Y-1917D01*
X463567Y-1750D01*
X462983Y-1667D01*
X462400Y-1833D01*
X461900Y-2167D01*
X461567Y-2667D01*
X461400Y-3333D01*
X461567Y-4000D01*
X461900Y-4500D01*
X462400Y-4833D01*
X462983Y-5000D01*
X463567Y-4917D01*
X464067Y-4667D01*
X464400Y-4333D01*
G01X466000Y-5000D02*
Y-1667D01*
G01Y-2583D02*
X466250Y-2167D01*
X466667Y-1833D01*
X467250Y-1667D01*
X467833Y-1833D01*
X468250Y-2167D01*
X468500Y-2583D01*
Y-5000D01*
G01Y-2583D02*
X468750Y-2167D01*
X469167Y-1833D01*
X469750Y-1667D01*
X470333Y-1833D01*
X470750Y-2167D01*
X471000Y-2667D01*
Y-5000D01*
G01X472850Y-2750D02*
X475517D01*
X475267Y-2167D01*
X474850Y-1833D01*
X474267Y-1667D01*
X473683Y-1750D01*
X473183Y-2000D01*
X472850Y-2583D01*
X472683Y-3083D01*
Y-3583D01*
X472850Y-4083D01*
X473267Y-4583D01*
X473767Y-4917D01*
X474350Y-5000D01*
X474933Y-4833D01*
X475517Y-4333D01*
G01X479700Y0D02*
Y-5000D01*
G01X478533Y-1667D02*
X480867D01*
G01X484050Y-2750D02*
X486717D01*
X486467Y-2167D01*
X486050Y-1833D01*
X485467Y-1667D01*
X484883Y-1750D01*
X484383Y-2000D01*
X484050Y-2583D01*
X483883Y-3083D01*
Y-3583D01*
X484050Y-4083D01*
X484467Y-4583D01*
X484967Y-4917D01*
X485550Y-5000D01*
X486133Y-4833D01*
X486717Y-4333D01*
G01X489733Y-5000D02*
Y-1667D01*
G01Y-2333D02*
X490150Y-2000D01*
X490567Y-1750D01*
X491150Y-1667D01*
X491567Y-1750D01*
X492067Y-2000D01*
G01X503767Y-5000D02*
X500433Y-3333D01*
X503767Y-1667D01*
G01X506617Y-4083D02*
X508783D01*
G01Y-2583D02*
X506617D01*
G01X518900Y-5000D02*
Y0D01*
X517900Y-1000D01*
G01Y-5000D02*
X519900D01*
G01X525500D02*
Y0D01*
X522417Y-3583D01*
X526583D01*
G01X533200Y-5000D02*
Y-1667D01*
G01Y-2583D02*
X533450Y-2167D01*
X533867Y-1833D01*
X534450Y-1667D01*
X535033Y-1833D01*
X535450Y-2167D01*
X535700Y-2583D01*
Y-5000D01*
G01Y-2583D02*
X535950Y-2167D01*
X536367Y-1833D01*
X536950Y-1667D01*
X537533Y-1833D01*
X537950Y-2167D01*
X538200Y-2667D01*
Y-5000D01*
G01X541300Y-1667D02*
Y-5000D01*
G01Y-333D02*
X541133Y-250D01*
Y-83D01*
X541300Y0D01*
X541467Y-83D01*
Y-250D01*
X541300Y-333D01*
G01X546900Y-5000D02*
Y0D01*
G01X274000Y-63500D02*
Y-60167D01*
G01Y-60750D02*
X273667Y-60417D01*
X273167Y-60250D01*
X272583Y-60167D01*
X272000Y-60333D01*
X271500Y-60667D01*
X271167Y-61167D01*
X271000Y-61833D01*
X271167Y-62500D01*
X271500Y-63000D01*
X272000Y-63333D01*
X272583Y-63500D01*
X273167Y-63417D01*
X273667Y-63167D01*
X274000Y-62833D01*
G01X279600Y-58500D02*
Y-63500D01*
G01Y-62750D02*
X279267Y-63167D01*
X278767Y-63417D01*
X278183Y-63500D01*
X277517Y-63333D01*
X277017Y-62917D01*
X276683Y-62417D01*
X276600Y-61833D01*
X276683Y-61250D01*
X277017Y-60750D01*
X277517Y-60333D01*
X278183Y-60167D01*
X278767Y-60250D01*
X279183Y-60417D01*
X279600Y-60750D01*
G01X285200Y-58500D02*
Y-63500D01*
G01Y-62750D02*
X284867Y-63167D01*
X284367Y-63417D01*
X283783Y-63500D01*
X283117Y-63333D01*
X282617Y-62917D01*
X282283Y-62417D01*
X282200Y-61833D01*
X282283Y-61250D01*
X282617Y-60750D01*
X283117Y-60333D01*
X283783Y-60167D01*
X284367Y-60250D01*
X284783Y-60417D01*
X285200Y-60750D01*
G01X293650Y-62917D02*
X294067Y-63250D01*
X294650Y-63500D01*
X295150D01*
X295650Y-63333D01*
X295983Y-63083D01*
X296150Y-62750D01*
X296067Y-62250D01*
X295733Y-62000D01*
X294233Y-61500D01*
X293900Y-60917D01*
X294067Y-60500D01*
X294400Y-60250D01*
X294900Y-60167D01*
X295400Y-60250D01*
X295900Y-60500D01*
G01X299083Y-60167D02*
Y-62500D01*
X299417Y-63083D01*
X299917Y-63417D01*
X300500Y-63500D01*
X301083Y-63417D01*
X301583Y-63083D01*
X301917Y-62500D01*
G01Y-63500D02*
Y-60167D01*
G01X304600Y-65167D02*
Y-60167D01*
G01Y-60917D02*
X305017Y-60500D01*
X305433Y-60250D01*
X306100Y-60167D01*
X306683Y-60250D01*
X307267Y-60667D01*
X307517Y-61250D01*
X307600Y-61833D01*
X307517Y-62417D01*
X307267Y-63000D01*
X306767Y-63333D01*
X306100Y-63500D01*
X305517Y-63417D01*
X304933Y-63167D01*
X304600Y-62833D01*
G01X310200Y-65167D02*
Y-60167D01*
G01Y-60917D02*
X310617Y-60500D01*
X311033Y-60250D01*
X311700Y-60167D01*
X312283Y-60250D01*
X312867Y-60667D01*
X313117Y-61250D01*
X313200Y-61833D01*
X313117Y-62417D01*
X312867Y-63000D01*
X312367Y-63333D01*
X311700Y-63500D01*
X311117Y-63417D01*
X310533Y-63167D01*
X310200Y-62833D01*
G01X317300Y-63500D02*
Y-58500D01*
G01X322900Y-60167D02*
Y-63500D01*
G01Y-58833D02*
X322733Y-58750D01*
Y-58583D01*
X322900Y-58500D01*
X323067Y-58583D01*
Y-58750D01*
X322900Y-58833D01*
G01X327250Y-61250D02*
X329917D01*
X329667Y-60667D01*
X329250Y-60333D01*
X328667Y-60167D01*
X328083Y-60250D01*
X327583Y-60500D01*
X327250Y-61083D01*
X327083Y-61583D01*
Y-62083D01*
X327250Y-62583D01*
X327667Y-63083D01*
X328167Y-63417D01*
X328750Y-63500D01*
X329333Y-63333D01*
X329917Y-62833D01*
G01X332933Y-63500D02*
Y-60167D01*
G01Y-60833D02*
X333350Y-60500D01*
X333767Y-60250D01*
X334350Y-60167D01*
X334767Y-60250D01*
X335267Y-60500D01*
G01X339700Y-60167D02*
X340533Y-59125D01*
Y-58500D01*
X339908D01*
Y-59125D01*
X340533D01*
G01X344050Y-62917D02*
X344467Y-63250D01*
X345050Y-63500D01*
X345550D01*
X346050Y-63333D01*
X346383Y-63083D01*
X346550Y-62750D01*
X346467Y-62250D01*
X346133Y-62000D01*
X344633Y-61500D01*
X344300Y-60917D01*
X344467Y-60500D01*
X344800Y-60250D01*
X345300Y-60167D01*
X345800Y-60250D01*
X346300Y-60500D01*
G01X354833Y-58500D02*
Y-63500D01*
X358167D01*
G01X362100D02*
X361600Y-63417D01*
X361100Y-63083D01*
X360767Y-62500D01*
X360600Y-61833D01*
X360767Y-61167D01*
X361100Y-60583D01*
X361600Y-60250D01*
X362100Y-60167D01*
X362600Y-60250D01*
X363100Y-60583D01*
X363433Y-61167D01*
X363517Y-61833D01*
X363433Y-62500D01*
X363100Y-63083D01*
X362600Y-63417D01*
X362100Y-63500D01*
G01X366533Y-64750D02*
X367117Y-65083D01*
X367783Y-65167D01*
X368367Y-65083D01*
X368867Y-64667D01*
X369200Y-64083D01*
Y-60167D01*
G01Y-60833D02*
X368867Y-60500D01*
X368367Y-60250D01*
X367783Y-60167D01*
X367117Y-60333D01*
X366700Y-60667D01*
X366367Y-61250D01*
X366200Y-61833D01*
X366283Y-62333D01*
X366617Y-62917D01*
X367117Y-63333D01*
X367783Y-63500D01*
X368283Y-63417D01*
X368867Y-63083D01*
X369200Y-62750D01*
G01X373300Y-63500D02*
X372800Y-63417D01*
X372300Y-63083D01*
X371967Y-62500D01*
X371800Y-61833D01*
X371967Y-61167D01*
X372300Y-60583D01*
X372800Y-60250D01*
X373300Y-60167D01*
X373800Y-60250D01*
X374300Y-60583D01*
X374633Y-61167D01*
X374717Y-61833D01*
X374633Y-62500D01*
X374300Y-63083D01*
X373800Y-63417D01*
X373300Y-63500D01*
G01X386000D02*
Y-60167D01*
G01Y-60750D02*
X385667Y-60417D01*
X385167Y-60250D01*
X384583Y-60167D01*
X384000Y-60333D01*
X383500Y-60667D01*
X383167Y-61167D01*
X383000Y-61833D01*
X383167Y-62500D01*
X383500Y-63000D01*
X384000Y-63333D01*
X384583Y-63500D01*
X385167Y-63417D01*
X385667Y-63167D01*
X386000Y-62833D01*
G01X388683Y-63500D02*
Y-60167D01*
G01Y-61000D02*
X389017Y-60583D01*
X389517Y-60250D01*
X390183Y-60167D01*
X390767Y-60250D01*
X391267Y-60583D01*
X391517Y-61167D01*
Y-63500D01*
G01X397200Y-58500D02*
Y-63500D01*
G01Y-62750D02*
X396867Y-63167D01*
X396367Y-63417D01*
X395783Y-63500D01*
X395117Y-63333D01*
X394617Y-62917D01*
X394283Y-62417D01*
X394200Y-61833D01*
X394283Y-61250D01*
X394617Y-60750D01*
X395117Y-60333D01*
X395783Y-60167D01*
X396367Y-60250D01*
X396783Y-60417D01*
X397200Y-60750D01*
G01X405067Y-58500D02*
Y-62083D01*
X405400Y-62833D01*
X406067Y-63333D01*
X406900Y-63500D01*
X407733Y-63333D01*
X408400Y-62833D01*
X408733Y-62083D01*
Y-58500D01*
G01X410833D02*
Y-63500D01*
X414167D01*
G01X423200D02*
Y-59250D01*
X423367Y-58833D01*
X423700Y-58583D01*
X424200Y-58500D01*
X424700Y-58667D01*
X424950Y-59083D01*
G01X423950Y-60500D02*
X422283D01*
G01X429300Y-60167D02*
Y-63500D01*
G01Y-58833D02*
X429133Y-58750D01*
Y-58583D01*
X429300Y-58500D01*
X429467Y-58583D01*
Y-58750D01*
X429300Y-58833D01*
G01X434900Y-63500D02*
Y-58500D01*
G01X439250Y-61250D02*
X441917D01*
X441667Y-60667D01*
X441250Y-60333D01*
X440667Y-60167D01*
X440083Y-60250D01*
X439583Y-60500D01*
X439250Y-61083D01*
X439083Y-61583D01*
Y-62083D01*
X439250Y-62583D01*
X439667Y-63083D01*
X440167Y-63417D01*
X440750Y-63500D01*
X441333Y-63333D01*
X441917Y-62833D01*
G01X449783Y-63500D02*
Y-58500D01*
X453617Y-63500D01*
Y-58500D01*
G01X455883Y-60167D02*
Y-62500D01*
X456217Y-63083D01*
X456717Y-63417D01*
X457300Y-63500D01*
X457883Y-63417D01*
X458383Y-63083D01*
X458717Y-62500D01*
G01Y-63500D02*
Y-60167D01*
G01X460400Y-63500D02*
Y-60167D01*
G01Y-61083D02*
X460650Y-60667D01*
X461067Y-60333D01*
X461650Y-60167D01*
X462233Y-60333D01*
X462650Y-60667D01*
X462900Y-61083D01*
Y-63500D01*
G01Y-61083D02*
X463150Y-60667D01*
X463567Y-60333D01*
X464150Y-60167D01*
X464733Y-60333D01*
X465150Y-60667D01*
X465400Y-61167D01*
Y-63500D01*
G01X467000D02*
Y-58500D01*
G01Y-61000D02*
X467417Y-60500D01*
X467917Y-60250D01*
X468417Y-60167D01*
X469167Y-60333D01*
X469667Y-60667D01*
X470000Y-61250D01*
Y-61917D01*
X469833Y-62583D01*
X469500Y-63083D01*
X468917Y-63417D01*
X468417Y-63500D01*
X467917Y-63417D01*
X467417Y-63167D01*
X467000Y-62750D01*
G01X472850Y-61250D02*
X475517D01*
X475267Y-60667D01*
X474850Y-60333D01*
X474267Y-60167D01*
X473683Y-60250D01*
X473183Y-60500D01*
X472850Y-61083D01*
X472683Y-61583D01*
Y-62083D01*
X472850Y-62583D01*
X473267Y-63083D01*
X473767Y-63417D01*
X474350Y-63500D01*
X474933Y-63333D01*
X475517Y-62833D01*
G01X478533Y-63500D02*
Y-60167D01*
G01Y-60833D02*
X478950Y-60500D01*
X479367Y-60250D01*
X479950Y-60167D01*
X480367Y-60250D01*
X480867Y-60500D01*
G01X490900Y-60167D02*
Y-63500D01*
G01Y-58833D02*
X490733Y-58750D01*
Y-58583D01*
X490900Y-58500D01*
X491067Y-58583D01*
Y-58750D01*
X490900Y-58833D01*
G01X495083Y-63500D02*
Y-60167D01*
G01Y-61000D02*
X495417Y-60583D01*
X495917Y-60250D01*
X496583Y-60167D01*
X497167Y-60250D01*
X497667Y-60583D01*
X497917Y-61167D01*
Y-63500D01*
G01X506450Y-62917D02*
X506867Y-63250D01*
X507450Y-63500D01*
X507950D01*
X508450Y-63333D01*
X508783Y-63083D01*
X508950Y-62750D01*
X508867Y-62250D01*
X508533Y-62000D01*
X507033Y-61500D01*
X506700Y-60917D01*
X506867Y-60500D01*
X507200Y-60250D01*
X507700Y-60167D01*
X508200Y-60250D01*
X508700Y-60500D01*
G01X513300Y-60167D02*
Y-63500D01*
G01Y-58833D02*
X513133Y-58750D01*
Y-58583D01*
X513300Y-58500D01*
X513467Y-58583D01*
Y-58750D01*
X513300Y-58833D01*
G01X518900Y-63500D02*
Y-58500D01*
G01X523083Y-63500D02*
Y-58500D01*
G01X525750Y-60167D02*
X523083Y-62083D01*
G01X524167Y-61333D02*
X525917Y-63500D01*
G01X528850Y-62917D02*
X529267Y-63250D01*
X529850Y-63500D01*
X530350D01*
X530850Y-63333D01*
X531183Y-63083D01*
X531350Y-62750D01*
X531267Y-62250D01*
X530933Y-62000D01*
X529433Y-61500D01*
X529100Y-60917D01*
X529267Y-60500D01*
X529600Y-60250D01*
X530100Y-60167D01*
X530600Y-60250D01*
X531100Y-60500D01*
G01X537033Y-60583D02*
X536450Y-60250D01*
X535950Y-60167D01*
X535283Y-60333D01*
X534783Y-60667D01*
X534450Y-61250D01*
X534367Y-61833D01*
X534450Y-62417D01*
X534783Y-62917D01*
X535283Y-63333D01*
X535950Y-63500D01*
X536533Y-63333D01*
X537033Y-63000D01*
G01X540133Y-63500D02*
Y-60167D01*
G01Y-60833D02*
X540550Y-60500D01*
X540967Y-60250D01*
X541550Y-60167D01*
X541967Y-60250D01*
X542467Y-60500D01*
G01X545650Y-61250D02*
X548317D01*
X548067Y-60667D01*
X547650Y-60333D01*
X547067Y-60167D01*
X546483Y-60250D01*
X545983Y-60500D01*
X545650Y-61083D01*
X545483Y-61583D01*
Y-62083D01*
X545650Y-62583D01*
X546067Y-63083D01*
X546567Y-63417D01*
X547150Y-63500D01*
X547733Y-63333D01*
X548317Y-62833D01*
G01X551250Y-61250D02*
X553917D01*
X553667Y-60667D01*
X553250Y-60333D01*
X552667Y-60167D01*
X552083Y-60250D01*
X551583Y-60500D01*
X551250Y-61083D01*
X551083Y-61583D01*
Y-62083D01*
X551250Y-62583D01*
X551667Y-63083D01*
X552167Y-63417D01*
X552750Y-63500D01*
X553333Y-63333D01*
X553917Y-62833D01*
G01X556683Y-63500D02*
Y-60167D01*
G01Y-61000D02*
X557017Y-60583D01*
X557517Y-60250D01*
X558183Y-60167D01*
X558767Y-60250D01*
X559267Y-60583D01*
X559517Y-61167D01*
Y-63500D01*
G01X270750Y-47833D02*
X271417Y-48250D01*
X272167Y-48500D01*
X272833D01*
X273500Y-48250D01*
X274000Y-47833D01*
X274250Y-47250D01*
X274083Y-46667D01*
X273667Y-46167D01*
X272917Y-45833D01*
X271917Y-45667D01*
X271333Y-45333D01*
X271083Y-44750D01*
X271250Y-44167D01*
X271667Y-43750D01*
X272250Y-43500D01*
X272833D01*
X273417Y-43667D01*
X273917Y-44083D01*
G01X278100Y-48500D02*
X277600Y-48417D01*
X277100Y-48083D01*
X276767Y-47500D01*
X276600Y-46833D01*
X276767Y-46167D01*
X277100Y-45583D01*
X277600Y-45250D01*
X278100Y-45167D01*
X278600Y-45250D01*
X279100Y-45583D01*
X279433Y-46167D01*
X279517Y-46833D01*
X279433Y-47500D01*
X279100Y-48083D01*
X278600Y-48417D01*
X278100Y-48500D01*
G01X283700D02*
Y-43500D01*
G01X290800D02*
Y-48500D01*
G01Y-47750D02*
X290467Y-48167D01*
X289967Y-48417D01*
X289383Y-48500D01*
X288717Y-48333D01*
X288217Y-47917D01*
X287883Y-47417D01*
X287800Y-46833D01*
X287883Y-46250D01*
X288217Y-45750D01*
X288717Y-45333D01*
X289383Y-45167D01*
X289967Y-45250D01*
X290383Y-45417D01*
X290800Y-45750D01*
G01X293650Y-46250D02*
X296317D01*
X296067Y-45667D01*
X295650Y-45333D01*
X295067Y-45167D01*
X294483Y-45250D01*
X293983Y-45500D01*
X293650Y-46083D01*
X293483Y-46583D01*
Y-47083D01*
X293650Y-47583D01*
X294067Y-48083D01*
X294567Y-48417D01*
X295150Y-48500D01*
X295733Y-48333D01*
X296317Y-47833D01*
G01X299333Y-48500D02*
Y-45167D01*
G01Y-45833D02*
X299750Y-45500D01*
X300167Y-45250D01*
X300750Y-45167D01*
X301167Y-45250D01*
X301667Y-45500D01*
G01X309200Y-48500D02*
Y-45167D01*
G01Y-46083D02*
X309450Y-45667D01*
X309867Y-45333D01*
X310450Y-45167D01*
X311033Y-45333D01*
X311450Y-45667D01*
X311700Y-46083D01*
Y-48500D01*
G01Y-46083D02*
X311950Y-45667D01*
X312367Y-45333D01*
X312950Y-45167D01*
X313533Y-45333D01*
X313950Y-45667D01*
X314200Y-46167D01*
Y-48500D01*
G01X318800D02*
Y-45167D01*
G01Y-45750D02*
X318467Y-45417D01*
X317967Y-45250D01*
X317383Y-45167D01*
X316800Y-45333D01*
X316300Y-45667D01*
X315967Y-46167D01*
X315800Y-46833D01*
X315967Y-47500D01*
X316300Y-48000D01*
X316800Y-48333D01*
X317383Y-48500D01*
X317967Y-48417D01*
X318467Y-48167D01*
X318800Y-47833D01*
G01X321650Y-47917D02*
X322067Y-48250D01*
X322650Y-48500D01*
X323150D01*
X323650Y-48333D01*
X323983Y-48083D01*
X324150Y-47750D01*
X324067Y-47250D01*
X323733Y-47000D01*
X322233Y-46500D01*
X321900Y-45917D01*
X322067Y-45500D01*
X322400Y-45250D01*
X322900Y-45167D01*
X323400Y-45250D01*
X323900Y-45500D01*
G01X327083Y-48500D02*
Y-43500D01*
G01X329750Y-45167D02*
X327083Y-47083D01*
G01X328167Y-46333D02*
X329917Y-48500D01*
G01X339700Y-43500D02*
Y-48500D01*
G01X338533Y-45167D02*
X340867D01*
G01X343883Y-48500D02*
Y-43500D01*
G01Y-45917D02*
X344300Y-45500D01*
X344717Y-45250D01*
X345383Y-45167D01*
X345883Y-45250D01*
X346467Y-45583D01*
X346717Y-46083D01*
Y-48500D01*
G01X350900Y-45167D02*
Y-48500D01*
G01Y-43833D02*
X350733Y-43750D01*
Y-43583D01*
X350900Y-43500D01*
X351067Y-43583D01*
Y-43750D01*
X350900Y-43833D01*
G01X357833Y-45583D02*
X357250Y-45250D01*
X356750Y-45167D01*
X356083Y-45333D01*
X355583Y-45667D01*
X355250Y-46250D01*
X355167Y-46833D01*
X355250Y-47417D01*
X355583Y-47917D01*
X356083Y-48333D01*
X356750Y-48500D01*
X357333Y-48333D01*
X357833Y-48000D01*
G01X360683Y-48500D02*
Y-43500D01*
G01X363350Y-45167D02*
X360683Y-47083D01*
G01X361767Y-46333D02*
X363517Y-48500D01*
G01X366283D02*
Y-45167D01*
G01Y-46000D02*
X366617Y-45583D01*
X367117Y-45250D01*
X367783Y-45167D01*
X368367Y-45250D01*
X368867Y-45583D01*
X369117Y-46167D01*
Y-48500D01*
G01X372050Y-46250D02*
X374717D01*
X374467Y-45667D01*
X374050Y-45333D01*
X373467Y-45167D01*
X372883Y-45250D01*
X372383Y-45500D01*
X372050Y-46083D01*
X371883Y-46583D01*
Y-47083D01*
X372050Y-47583D01*
X372467Y-48083D01*
X372967Y-48417D01*
X373550Y-48500D01*
X374133Y-48333D01*
X374717Y-47833D01*
G01X377650Y-47917D02*
X378067Y-48250D01*
X378650Y-48500D01*
X379150D01*
X379650Y-48333D01*
X379983Y-48083D01*
X380150Y-47750D01*
X380067Y-47250D01*
X379733Y-47000D01*
X378233Y-46500D01*
X377900Y-45917D01*
X378067Y-45500D01*
X378400Y-45250D01*
X378900Y-45167D01*
X379400Y-45250D01*
X379900Y-45500D01*
G01X383250Y-47917D02*
X383667Y-48250D01*
X384250Y-48500D01*
X384750D01*
X385250Y-48333D01*
X385583Y-48083D01*
X385750Y-47750D01*
X385667Y-47250D01*
X385333Y-47000D01*
X383833Y-46500D01*
X383500Y-45917D01*
X383667Y-45500D01*
X384000Y-45250D01*
X384500Y-45167D01*
X385000Y-45250D01*
X385500Y-45500D01*
G01X394200Y-50167D02*
Y-45167D01*
G01Y-45917D02*
X394617Y-45500D01*
X395033Y-45250D01*
X395700Y-45167D01*
X396283Y-45250D01*
X396867Y-45667D01*
X397117Y-46250D01*
X397200Y-46833D01*
X397117Y-47417D01*
X396867Y-48000D01*
X396367Y-48333D01*
X395700Y-48500D01*
X395117Y-48417D01*
X394533Y-48167D01*
X394200Y-47833D01*
G01X401300Y-48500D02*
Y-43500D01*
G01X405483Y-45167D02*
Y-47500D01*
X405817Y-48083D01*
X406317Y-48417D01*
X406900Y-48500D01*
X407483Y-48417D01*
X407983Y-48083D01*
X408317Y-47500D01*
G01Y-48500D02*
Y-45167D01*
G01X411250Y-47917D02*
X411667Y-48250D01*
X412250Y-48500D01*
X412750D01*
X413250Y-48333D01*
X413583Y-48083D01*
X413750Y-47750D01*
X413667Y-47250D01*
X413333Y-47000D01*
X411833Y-46500D01*
X411500Y-45917D01*
X411667Y-45500D01*
X412000Y-45250D01*
X412500Y-45167D01*
X413000Y-45250D01*
X413500Y-45500D01*
G01X423700Y-48500D02*
Y-43500D01*
G01X428050Y-46250D02*
X430717D01*
X430467Y-45667D01*
X430050Y-45333D01*
X429467Y-45167D01*
X428883Y-45250D01*
X428383Y-45500D01*
X428050Y-46083D01*
X427883Y-46583D01*
Y-47083D01*
X428050Y-47583D01*
X428467Y-48083D01*
X428967Y-48417D01*
X429550Y-48500D01*
X430133Y-48333D01*
X430717Y-47833D01*
G01X433733Y-49750D02*
X434317Y-50083D01*
X434983Y-50167D01*
X435567Y-50083D01*
X436067Y-49667D01*
X436400Y-49083D01*
Y-45167D01*
G01Y-45833D02*
X436067Y-45500D01*
X435567Y-45250D01*
X434983Y-45167D01*
X434317Y-45333D01*
X433900Y-45667D01*
X433567Y-46250D01*
X433400Y-46833D01*
X433483Y-47333D01*
X433817Y-47917D01*
X434317Y-48333D01*
X434983Y-48500D01*
X435483Y-48417D01*
X436067Y-48083D01*
X436400Y-47750D01*
G01X439250Y-46250D02*
X441917D01*
X441667Y-45667D01*
X441250Y-45333D01*
X440667Y-45167D01*
X440083Y-45250D01*
X439583Y-45500D01*
X439250Y-46083D01*
X439083Y-46583D01*
Y-47083D01*
X439250Y-47583D01*
X439667Y-48083D01*
X440167Y-48417D01*
X440750Y-48500D01*
X441333Y-48333D01*
X441917Y-47833D01*
G01X444683Y-48500D02*
Y-45167D01*
G01Y-46000D02*
X445017Y-45583D01*
X445517Y-45250D01*
X446183Y-45167D01*
X446767Y-45250D01*
X447267Y-45583D01*
X447517Y-46167D01*
Y-48500D01*
G01X453200Y-43500D02*
Y-48500D01*
G01Y-47750D02*
X452867Y-48167D01*
X452367Y-48417D01*
X451783Y-48500D01*
X451117Y-48333D01*
X450617Y-47917D01*
X450283Y-47417D01*
X450200Y-46833D01*
X450283Y-46250D01*
X450617Y-45750D01*
X451117Y-45333D01*
X451783Y-45167D01*
X452367Y-45250D01*
X452783Y-45417D01*
X453200Y-45750D01*
G01X462900Y-43500D02*
Y-48500D01*
G01X461733Y-45167D02*
X464067D01*
G01X467083Y-48500D02*
Y-43500D01*
G01Y-45917D02*
X467500Y-45500D01*
X467917Y-45250D01*
X468583Y-45167D01*
X469083Y-45250D01*
X469667Y-45583D01*
X469917Y-46083D01*
Y-48500D01*
G01X474100Y-45167D02*
Y-48500D01*
G01Y-43833D02*
X473933Y-43750D01*
Y-43583D01*
X474100Y-43500D01*
X474267Y-43583D01*
Y-43750D01*
X474100Y-43833D01*
G01X481033Y-45583D02*
X480450Y-45250D01*
X479950Y-45167D01*
X479283Y-45333D01*
X478783Y-45667D01*
X478450Y-46250D01*
X478367Y-46833D01*
X478450Y-47417D01*
X478783Y-47917D01*
X479283Y-48333D01*
X479950Y-48500D01*
X480533Y-48333D01*
X481033Y-48000D01*
G01X483883Y-48500D02*
Y-43500D01*
G01X486550Y-45167D02*
X483883Y-47083D01*
G01X484967Y-46333D02*
X486717Y-48500D01*
G01X489483D02*
Y-45167D01*
G01Y-46000D02*
X489817Y-45583D01*
X490317Y-45250D01*
X490983Y-45167D01*
X491567Y-45250D01*
X492067Y-45583D01*
X492317Y-46167D01*
Y-48500D01*
G01X495250Y-46250D02*
X497917D01*
X497667Y-45667D01*
X497250Y-45333D01*
X496667Y-45167D01*
X496083Y-45250D01*
X495583Y-45500D01*
X495250Y-46083D01*
X495083Y-46583D01*
Y-47083D01*
X495250Y-47583D01*
X495667Y-48083D01*
X496167Y-48417D01*
X496750Y-48500D01*
X497333Y-48333D01*
X497917Y-47833D01*
G01X500850Y-47917D02*
X501267Y-48250D01*
X501850Y-48500D01*
X502350D01*
X502850Y-48333D01*
X503183Y-48083D01*
X503350Y-47750D01*
X503267Y-47250D01*
X502933Y-47000D01*
X501433Y-46500D01*
X501100Y-45917D01*
X501267Y-45500D01*
X501600Y-45250D01*
X502100Y-45167D01*
X502600Y-45250D01*
X503100Y-45500D01*
G01X506450Y-47917D02*
X506867Y-48250D01*
X507450Y-48500D01*
X507950D01*
X508450Y-48333D01*
X508783Y-48083D01*
X508950Y-47750D01*
X508867Y-47250D01*
X508533Y-47000D01*
X507033Y-46500D01*
X506700Y-45917D01*
X506867Y-45500D01*
X507200Y-45250D01*
X507700Y-45167D01*
X508200Y-45250D01*
X508700Y-45500D01*
G01X518900Y-48500D02*
X518400Y-48417D01*
X517900Y-48083D01*
X517567Y-47500D01*
X517400Y-46833D01*
X517567Y-46167D01*
X517900Y-45583D01*
X518400Y-45250D01*
X518900Y-45167D01*
X519400Y-45250D01*
X519900Y-45583D01*
X520233Y-46167D01*
X520317Y-46833D01*
X520233Y-47500D01*
X519900Y-48083D01*
X519400Y-48417D01*
X518900Y-48500D01*
G01X523083D02*
Y-45167D01*
G01Y-46000D02*
X523417Y-45583D01*
X523917Y-45250D01*
X524583Y-45167D01*
X525167Y-45250D01*
X525667Y-45583D01*
X525917Y-46167D01*
Y-48500D01*
G01X535700Y-43500D02*
Y-48500D01*
G01X534533Y-45167D02*
X536867D01*
G01X540133Y-48500D02*
Y-45167D01*
G01Y-45833D02*
X540550Y-45500D01*
X540967Y-45250D01*
X541550Y-45167D01*
X541967Y-45250D01*
X542467Y-45500D01*
G01X548400Y-48500D02*
Y-45167D01*
G01Y-45750D02*
X548067Y-45417D01*
X547567Y-45250D01*
X546983Y-45167D01*
X546400Y-45333D01*
X545900Y-45667D01*
X545567Y-46167D01*
X545400Y-46833D01*
X545567Y-47500D01*
X545900Y-48000D01*
X546400Y-48333D01*
X546983Y-48500D01*
X547567Y-48417D01*
X548067Y-48167D01*
X548400Y-47833D01*
G01X553833Y-45583D02*
X553250Y-45250D01*
X552750Y-45167D01*
X552083Y-45333D01*
X551583Y-45667D01*
X551250Y-46250D01*
X551167Y-46833D01*
X551250Y-47417D01*
X551583Y-47917D01*
X552083Y-48333D01*
X552750Y-48500D01*
X553333Y-48333D01*
X553833Y-48000D01*
G01X556850Y-46250D02*
X559517D01*
X559267Y-45667D01*
X558850Y-45333D01*
X558267Y-45167D01*
X557683Y-45250D01*
X557183Y-45500D01*
X556850Y-46083D01*
X556683Y-46583D01*
Y-47083D01*
X556850Y-47583D01*
X557267Y-48083D01*
X557767Y-48417D01*
X558350Y-48500D01*
X558933Y-48333D01*
X559517Y-47833D01*
G01X563700Y-48667D02*
X563533Y-48583D01*
Y-48417D01*
X563700Y-48333D01*
X563867Y-48417D01*
Y-48583D01*
X563700Y-48667D01*
G01X272500Y-33500D02*
Y-28500D01*
G01X276850Y-31250D02*
X279517D01*
X279267Y-30667D01*
X278850Y-30333D01*
X278267Y-30167D01*
X277683Y-30250D01*
X277183Y-30500D01*
X276850Y-31083D01*
X276683Y-31583D01*
Y-32083D01*
X276850Y-32583D01*
X277267Y-33083D01*
X277767Y-33417D01*
X278350Y-33500D01*
X278933Y-33333D01*
X279517Y-32833D01*
G01X282533Y-34750D02*
X283117Y-35083D01*
X283783Y-35167D01*
X284367Y-35083D01*
X284867Y-34667D01*
X285200Y-34083D01*
Y-30167D01*
G01Y-30833D02*
X284867Y-30500D01*
X284367Y-30250D01*
X283783Y-30167D01*
X283117Y-30333D01*
X282700Y-30667D01*
X282367Y-31250D01*
X282200Y-31833D01*
X282283Y-32333D01*
X282617Y-32917D01*
X283117Y-33333D01*
X283783Y-33500D01*
X284283Y-33417D01*
X284867Y-33083D01*
X285200Y-32750D01*
G01X288050Y-31250D02*
X290717D01*
X290467Y-30667D01*
X290050Y-30333D01*
X289467Y-30167D01*
X288883Y-30250D01*
X288383Y-30500D01*
X288050Y-31083D01*
X287883Y-31583D01*
Y-32083D01*
X288050Y-32583D01*
X288467Y-33083D01*
X288967Y-33417D01*
X289550Y-33500D01*
X290133Y-33333D01*
X290717Y-32833D01*
G01X293483Y-33500D02*
Y-30167D01*
G01Y-31000D02*
X293817Y-30583D01*
X294317Y-30250D01*
X294983Y-30167D01*
X295567Y-30250D01*
X296067Y-30583D01*
X296317Y-31167D01*
Y-33500D01*
G01X302000Y-28500D02*
Y-33500D01*
G01Y-32750D02*
X301667Y-33167D01*
X301167Y-33417D01*
X300583Y-33500D01*
X299917Y-33333D01*
X299417Y-32917D01*
X299083Y-32417D01*
X299000Y-31833D01*
X299083Y-31250D01*
X299417Y-30750D01*
X299917Y-30333D01*
X300583Y-30167D01*
X301167Y-30250D01*
X301583Y-30417D01*
X302000Y-30750D01*
G01X311700Y-28500D02*
Y-33500D01*
G01X310533Y-30167D02*
X312867D01*
G01X315883Y-33500D02*
Y-28500D01*
G01Y-30917D02*
X316300Y-30500D01*
X316717Y-30250D01*
X317383Y-30167D01*
X317883Y-30250D01*
X318467Y-30583D01*
X318717Y-31083D01*
Y-33500D01*
G01X322900Y-30167D02*
Y-33500D01*
G01Y-28833D02*
X322733Y-28750D01*
Y-28583D01*
X322900Y-28500D01*
X323067Y-28583D01*
Y-28750D01*
X322900Y-28833D01*
G01X329833Y-30583D02*
X329250Y-30250D01*
X328750Y-30167D01*
X328083Y-30333D01*
X327583Y-30667D01*
X327250Y-31250D01*
X327167Y-31833D01*
X327250Y-32417D01*
X327583Y-32917D01*
X328083Y-33333D01*
X328750Y-33500D01*
X329333Y-33333D01*
X329833Y-33000D01*
G01X332683Y-33500D02*
Y-28500D01*
G01X335350Y-30167D02*
X332683Y-32083D01*
G01X333767Y-31333D02*
X335517Y-33500D01*
G01X338283D02*
Y-30167D01*
G01Y-31000D02*
X338617Y-30583D01*
X339117Y-30250D01*
X339783Y-30167D01*
X340367Y-30250D01*
X340867Y-30583D01*
X341117Y-31167D01*
Y-33500D01*
G01X344050Y-31250D02*
X346717D01*
X346467Y-30667D01*
X346050Y-30333D01*
X345467Y-30167D01*
X344883Y-30250D01*
X344383Y-30500D01*
X344050Y-31083D01*
X343883Y-31583D01*
Y-32083D01*
X344050Y-32583D01*
X344467Y-33083D01*
X344967Y-33417D01*
X345550Y-33500D01*
X346133Y-33333D01*
X346717Y-32833D01*
G01X349650Y-32917D02*
X350067Y-33250D01*
X350650Y-33500D01*
X351150D01*
X351650Y-33333D01*
X351983Y-33083D01*
X352150Y-32750D01*
X352067Y-32250D01*
X351733Y-32000D01*
X350233Y-31500D01*
X349900Y-30917D01*
X350067Y-30500D01*
X350400Y-30250D01*
X350900Y-30167D01*
X351400Y-30250D01*
X351900Y-30500D01*
G01X355250Y-32917D02*
X355667Y-33250D01*
X356250Y-33500D01*
X356750D01*
X357250Y-33333D01*
X357583Y-33083D01*
X357750Y-32750D01*
X357667Y-32250D01*
X357333Y-32000D01*
X355833Y-31500D01*
X355500Y-30917D01*
X355667Y-30500D01*
X356000Y-30250D01*
X356500Y-30167D01*
X357000Y-30250D01*
X357500Y-30500D01*
G01X367700Y-33500D02*
X367200Y-33417D01*
X366700Y-33083D01*
X366367Y-32500D01*
X366200Y-31833D01*
X366367Y-31167D01*
X366700Y-30583D01*
X367200Y-30250D01*
X367700Y-30167D01*
X368200Y-30250D01*
X368700Y-30583D01*
X369033Y-31167D01*
X369117Y-31833D01*
X369033Y-32500D01*
X368700Y-33083D01*
X368200Y-33417D01*
X367700Y-33500D01*
G01X371883D02*
Y-30167D01*
G01Y-31000D02*
X372217Y-30583D01*
X372717Y-30250D01*
X373383Y-30167D01*
X373967Y-30250D01*
X374467Y-30583D01*
X374717Y-31167D01*
Y-33500D01*
G01X385833Y-30583D02*
X385250Y-30250D01*
X384750Y-30167D01*
X384083Y-30333D01*
X383583Y-30667D01*
X383250Y-31250D01*
X383167Y-31833D01*
X383250Y-32417D01*
X383583Y-32917D01*
X384083Y-33333D01*
X384750Y-33500D01*
X385333Y-33333D01*
X385833Y-33000D01*
G01X390100Y-33500D02*
X389600Y-33417D01*
X389100Y-33083D01*
X388767Y-32500D01*
X388600Y-31833D01*
X388767Y-31167D01*
X389100Y-30583D01*
X389600Y-30250D01*
X390100Y-30167D01*
X390600Y-30250D01*
X391100Y-30583D01*
X391433Y-31167D01*
X391517Y-31833D01*
X391433Y-32500D01*
X391100Y-33083D01*
X390600Y-33417D01*
X390100Y-33500D01*
G01X394200Y-35167D02*
Y-30167D01*
G01Y-30917D02*
X394617Y-30500D01*
X395033Y-30250D01*
X395700Y-30167D01*
X396283Y-30250D01*
X396867Y-30667D01*
X397117Y-31250D01*
X397200Y-31833D01*
X397117Y-32417D01*
X396867Y-33000D01*
X396367Y-33333D01*
X395700Y-33500D01*
X395117Y-33417D01*
X394533Y-33167D01*
X394200Y-32833D01*
G01X399800Y-35167D02*
Y-30167D01*
G01Y-30917D02*
X400217Y-30500D01*
X400633Y-30250D01*
X401300Y-30167D01*
X401883Y-30250D01*
X402467Y-30667D01*
X402717Y-31250D01*
X402800Y-31833D01*
X402717Y-32417D01*
X402467Y-33000D01*
X401967Y-33333D01*
X401300Y-33500D01*
X400717Y-33417D01*
X400133Y-33167D01*
X399800Y-32833D01*
G01X405650Y-31250D02*
X408317D01*
X408067Y-30667D01*
X407650Y-30333D01*
X407067Y-30167D01*
X406483Y-30250D01*
X405983Y-30500D01*
X405650Y-31083D01*
X405483Y-31583D01*
Y-32083D01*
X405650Y-32583D01*
X406067Y-33083D01*
X406567Y-33417D01*
X407150Y-33500D01*
X407733Y-33333D01*
X408317Y-32833D01*
G01X411333Y-33500D02*
Y-30167D01*
G01Y-30833D02*
X411750Y-30500D01*
X412167Y-30250D01*
X412750Y-30167D01*
X413167Y-30250D01*
X413667Y-30500D01*
G01X423283Y-35167D02*
X422450Y-34333D01*
X422033Y-33500D01*
Y-30167D01*
X422450Y-29333D01*
X423283Y-28500D01*
G01X427217Y-30167D02*
X428217Y-33500D01*
X429300Y-30167D01*
X430383Y-33500D01*
X431383Y-30167D01*
G01X433483Y-33500D02*
Y-28500D01*
G01Y-30917D02*
X433900Y-30500D01*
X434317Y-30250D01*
X434983Y-30167D01*
X435483Y-30250D01*
X436067Y-30583D01*
X436317Y-31083D01*
Y-33500D01*
G01X440500Y-30167D02*
Y-33500D01*
G01Y-28833D02*
X440333Y-28750D01*
Y-28583D01*
X440500Y-28500D01*
X440667Y-28583D01*
Y-28750D01*
X440500Y-28833D01*
G01X447433Y-30583D02*
X446850Y-30250D01*
X446350Y-30167D01*
X445683Y-30333D01*
X445183Y-30667D01*
X444850Y-31250D01*
X444767Y-31833D01*
X444850Y-32417D01*
X445183Y-32917D01*
X445683Y-33333D01*
X446350Y-33500D01*
X446933Y-33333D01*
X447433Y-33000D01*
G01X450283Y-33500D02*
Y-28500D01*
G01Y-30917D02*
X450700Y-30500D01*
X451117Y-30250D01*
X451783Y-30167D01*
X452283Y-30250D01*
X452867Y-30583D01*
X453117Y-31083D01*
Y-33500D01*
G01X462900Y-30167D02*
Y-33500D01*
G01Y-28833D02*
X462733Y-28750D01*
Y-28583D01*
X462900Y-28500D01*
X463067Y-28583D01*
Y-28750D01*
X462900Y-28833D01*
G01X467250Y-32917D02*
X467667Y-33250D01*
X468250Y-33500D01*
X468750D01*
X469250Y-33333D01*
X469583Y-33083D01*
X469750Y-32750D01*
X469667Y-32250D01*
X469333Y-32000D01*
X467833Y-31500D01*
X467500Y-30917D01*
X467667Y-30500D01*
X468000Y-30250D01*
X468500Y-30167D01*
X469000Y-30250D01*
X469500Y-30500D01*
G01X478200Y-33500D02*
Y-28500D01*
G01Y-31000D02*
X478617Y-30500D01*
X479117Y-30250D01*
X479617Y-30167D01*
X480367Y-30333D01*
X480867Y-30667D01*
X481200Y-31250D01*
Y-31917D01*
X481033Y-32583D01*
X480700Y-33083D01*
X480117Y-33417D01*
X479617Y-33500D01*
X479117Y-33417D01*
X478617Y-33167D01*
X478200Y-32750D01*
G01X484050Y-31250D02*
X486717D01*
X486467Y-30667D01*
X486050Y-30333D01*
X485467Y-30167D01*
X484883Y-30250D01*
X484383Y-30500D01*
X484050Y-31083D01*
X483883Y-31583D01*
Y-32083D01*
X484050Y-32583D01*
X484467Y-33083D01*
X484967Y-33417D01*
X485550Y-33500D01*
X486133Y-33333D01*
X486717Y-32833D01*
G01X490900Y-28500D02*
Y-33500D01*
G01X489733Y-30167D02*
X492067D01*
G01X496500Y-28500D02*
Y-33500D01*
G01X495333Y-30167D02*
X497667D01*
G01X500850Y-31250D02*
X503517D01*
X503267Y-30667D01*
X502850Y-30333D01*
X502267Y-30167D01*
X501683Y-30250D01*
X501183Y-30500D01*
X500850Y-31083D01*
X500683Y-31583D01*
Y-32083D01*
X500850Y-32583D01*
X501267Y-33083D01*
X501767Y-33417D01*
X502350Y-33500D01*
X502933Y-33333D01*
X503517Y-32833D01*
G01X506533Y-33500D02*
Y-30167D01*
G01Y-30833D02*
X506950Y-30500D01*
X507367Y-30250D01*
X507950Y-30167D01*
X508367Y-30250D01*
X508867Y-30500D01*
G01X513717Y-35167D02*
X514550Y-34333D01*
X514967Y-33500D01*
Y-30167D01*
X514550Y-29333D01*
X513717Y-28500D01*
G01X271250Y-19417D02*
X271667Y-19750D01*
X272250Y-20000D01*
X272750D01*
X273250Y-19833D01*
X273583Y-19583D01*
X273750Y-19250D01*
X273667Y-18750D01*
X273333Y-18500D01*
X271833Y-18000D01*
X271500Y-17417D01*
X271667Y-17000D01*
X272000Y-16750D01*
X272500Y-16667D01*
X273000Y-16750D01*
X273500Y-17000D01*
G01X278100Y-20000D02*
X277600Y-19917D01*
X277100Y-19583D01*
X276767Y-19000D01*
X276600Y-18333D01*
X276767Y-17667D01*
X277100Y-17083D01*
X277600Y-16750D01*
X278100Y-16667D01*
X278600Y-16750D01*
X279100Y-17083D01*
X279433Y-17667D01*
X279517Y-18333D01*
X279433Y-19000D01*
X279100Y-19583D01*
X278600Y-19917D01*
X278100Y-20000D01*
G01X283700D02*
Y-15000D01*
G01X290800D02*
Y-20000D01*
G01Y-19250D02*
X290467Y-19667D01*
X289967Y-19917D01*
X289383Y-20000D01*
X288717Y-19833D01*
X288217Y-19417D01*
X287883Y-18917D01*
X287800Y-18333D01*
X287883Y-17750D01*
X288217Y-17250D01*
X288717Y-16833D01*
X289383Y-16667D01*
X289967Y-16750D01*
X290383Y-16917D01*
X290800Y-17250D01*
G01X293650Y-17750D02*
X296317D01*
X296067Y-17167D01*
X295650Y-16833D01*
X295067Y-16667D01*
X294483Y-16750D01*
X293983Y-17000D01*
X293650Y-17583D01*
X293483Y-18083D01*
Y-18583D01*
X293650Y-19083D01*
X294067Y-19583D01*
X294567Y-19917D01*
X295150Y-20000D01*
X295733Y-19833D01*
X296317Y-19333D01*
G01X299333Y-20000D02*
Y-16667D01*
G01Y-17333D02*
X299750Y-17000D01*
X300167Y-16750D01*
X300750Y-16667D01*
X301167Y-16750D01*
X301667Y-17000D01*
G01X309200Y-20000D02*
Y-16667D01*
G01Y-17583D02*
X309450Y-17167D01*
X309867Y-16833D01*
X310450Y-16667D01*
X311033Y-16833D01*
X311450Y-17167D01*
X311700Y-17583D01*
Y-20000D01*
G01Y-17583D02*
X311950Y-17167D01*
X312367Y-16833D01*
X312950Y-16667D01*
X313533Y-16833D01*
X313950Y-17167D01*
X314200Y-17667D01*
Y-20000D01*
G01X318800D02*
Y-16667D01*
G01Y-17250D02*
X318467Y-16917D01*
X317967Y-16750D01*
X317383Y-16667D01*
X316800Y-16833D01*
X316300Y-17167D01*
X315967Y-17667D01*
X315800Y-18333D01*
X315967Y-19000D01*
X316300Y-19500D01*
X316800Y-19833D01*
X317383Y-20000D01*
X317967Y-19917D01*
X318467Y-19667D01*
X318800Y-19333D01*
G01X321650Y-19417D02*
X322067Y-19750D01*
X322650Y-20000D01*
X323150D01*
X323650Y-19833D01*
X323983Y-19583D01*
X324150Y-19250D01*
X324067Y-18750D01*
X323733Y-18500D01*
X322233Y-18000D01*
X321900Y-17417D01*
X322067Y-17000D01*
X322400Y-16750D01*
X322900Y-16667D01*
X323400Y-16750D01*
X323900Y-17000D01*
G01X327083Y-20000D02*
Y-15000D01*
G01X329750Y-16667D02*
X327083Y-18583D01*
G01X328167Y-17833D02*
X329917Y-20000D01*
G01X339700Y-15000D02*
Y-20000D01*
G01X338533Y-16667D02*
X340867D01*
G01X343883Y-20000D02*
Y-15000D01*
G01Y-17417D02*
X344300Y-17000D01*
X344717Y-16750D01*
X345383Y-16667D01*
X345883Y-16750D01*
X346467Y-17083D01*
X346717Y-17583D01*
Y-20000D01*
G01X350900Y-16667D02*
Y-20000D01*
G01Y-15333D02*
X350733Y-15250D01*
Y-15083D01*
X350900Y-15000D01*
X351067Y-15083D01*
Y-15250D01*
X350900Y-15333D01*
G01X357833Y-17083D02*
X357250Y-16750D01*
X356750Y-16667D01*
X356083Y-16833D01*
X355583Y-17167D01*
X355250Y-17750D01*
X355167Y-18333D01*
X355250Y-18917D01*
X355583Y-19417D01*
X356083Y-19833D01*
X356750Y-20000D01*
X357333Y-19833D01*
X357833Y-19500D01*
G01X360683Y-20000D02*
Y-15000D01*
G01X363350Y-16667D02*
X360683Y-18583D01*
G01X361767Y-17833D02*
X363517Y-20000D01*
G01X366283D02*
Y-16667D01*
G01Y-17500D02*
X366617Y-17083D01*
X367117Y-16750D01*
X367783Y-16667D01*
X368367Y-16750D01*
X368867Y-17083D01*
X369117Y-17667D01*
Y-20000D01*
G01X372050Y-17750D02*
X374717D01*
X374467Y-17167D01*
X374050Y-16833D01*
X373467Y-16667D01*
X372883Y-16750D01*
X372383Y-17000D01*
X372050Y-17583D01*
X371883Y-18083D01*
Y-18583D01*
X372050Y-19083D01*
X372467Y-19583D01*
X372967Y-19917D01*
X373550Y-20000D01*
X374133Y-19833D01*
X374717Y-19333D01*
G01X377650Y-19417D02*
X378067Y-19750D01*
X378650Y-20000D01*
X379150D01*
X379650Y-19833D01*
X379983Y-19583D01*
X380150Y-19250D01*
X380067Y-18750D01*
X379733Y-18500D01*
X378233Y-18000D01*
X377900Y-17417D01*
X378067Y-17000D01*
X378400Y-16750D01*
X378900Y-16667D01*
X379400Y-16750D01*
X379900Y-17000D01*
G01X383250Y-19417D02*
X383667Y-19750D01*
X384250Y-20000D01*
X384750D01*
X385250Y-19833D01*
X385583Y-19583D01*
X385750Y-19250D01*
X385667Y-18750D01*
X385333Y-18500D01*
X383833Y-18000D01*
X383500Y-17417D01*
X383667Y-17000D01*
X384000Y-16750D01*
X384500Y-16667D01*
X385000Y-16750D01*
X385500Y-17000D01*
G01X264000Y-39500D02*
X694500D01*
G01X262500Y-69500D02*
Y439000D01*
G01X270667Y82250D02*
X271167Y81833D01*
X271750Y81583D01*
X272500Y81500D01*
X273250Y81667D01*
X273833Y82000D01*
X274250Y82583D01*
X274333Y83250D01*
X274167Y83917D01*
X273750Y84333D01*
X273167Y84667D01*
X272583Y84750D01*
X272000Y84667D01*
X271250Y84333D01*
X271500Y86500D01*
X273750D01*
G01X281200Y81500D02*
Y84833D01*
G01Y83917D02*
X281450Y84333D01*
X281867Y84667D01*
X282450Y84833D01*
X283033Y84667D01*
X283450Y84333D01*
X283700Y83917D01*
Y81500D01*
G01Y83917D02*
X283950Y84333D01*
X284367Y84667D01*
X284950Y84833D01*
X285533Y84667D01*
X285950Y84333D01*
X286200Y83833D01*
Y81500D01*
G01X289300Y84833D02*
Y81500D01*
G01Y86167D02*
X289133Y86250D01*
Y86417D01*
X289300Y86500D01*
X289467Y86417D01*
Y86250D01*
X289300Y86167D01*
G01X294900Y81500D02*
Y86500D01*
G01X307767Y81500D02*
X304433Y83167D01*
X307767Y84833D01*
G01X317300Y86500D02*
Y81500D01*
G01X316133Y84833D02*
X318467D01*
G01X321733Y81500D02*
Y84833D01*
G01Y84167D02*
X322150Y84500D01*
X322567Y84750D01*
X323150Y84833D01*
X323567Y84750D01*
X324067Y84500D01*
G01X330000Y81500D02*
Y84833D01*
G01Y84250D02*
X329667Y84583D01*
X329167Y84750D01*
X328583Y84833D01*
X328000Y84667D01*
X327500Y84333D01*
X327167Y83833D01*
X327000Y83167D01*
X327167Y82500D01*
X327500Y82000D01*
X328000Y81667D01*
X328583Y81500D01*
X329167Y81583D01*
X329667Y81833D01*
X330000Y82167D01*
G01X335433Y84417D02*
X334850Y84750D01*
X334350Y84833D01*
X333683Y84667D01*
X333183Y84333D01*
X332850Y83750D01*
X332767Y83167D01*
X332850Y82583D01*
X333183Y82083D01*
X333683Y81667D01*
X334350Y81500D01*
X334933Y81667D01*
X335433Y82000D01*
G01X338450Y83750D02*
X341117D01*
X340867Y84333D01*
X340450Y84667D01*
X339867Y84833D01*
X339283Y84750D01*
X338783Y84500D01*
X338450Y83917D01*
X338283Y83417D01*
Y82917D01*
X338450Y82417D01*
X338867Y81917D01*
X339367Y81583D01*
X339950Y81500D01*
X340533Y81667D01*
X341117Y82167D01*
G01X348817Y84833D02*
X349817Y81500D01*
X350900Y84833D01*
X351983Y81500D01*
X352983Y84833D01*
G01X356500D02*
Y81500D01*
G01Y86167D02*
X356333Y86250D01*
Y86417D01*
X356500Y86500D01*
X356667Y86417D01*
Y86250D01*
X356500Y86167D01*
G01X363600Y86500D02*
Y81500D01*
G01Y82250D02*
X363267Y81833D01*
X362767Y81583D01*
X362183Y81500D01*
X361517Y81667D01*
X361017Y82083D01*
X360683Y82583D01*
X360600Y83167D01*
X360683Y83750D01*
X361017Y84250D01*
X361517Y84667D01*
X362183Y84833D01*
X362767Y84750D01*
X363183Y84583D01*
X363600Y84250D01*
G01X367700Y86500D02*
Y81500D01*
G01X366533Y84833D02*
X368867D01*
G01X371883Y81500D02*
Y86500D01*
G01Y84083D02*
X372300Y84500D01*
X372717Y84750D01*
X373383Y84833D01*
X373883Y84750D01*
X374467Y84417D01*
X374717Y83917D01*
Y81500D01*
G01X386167D02*
X382833Y83167D01*
X386167Y84833D01*
G01X389017Y82417D02*
X391183D01*
G01Y83917D02*
X389017D01*
G01X401133Y81500D02*
X401300Y82583D01*
X401550Y83500D01*
X401883Y84333D01*
X402300Y85250D01*
X402967Y86500D01*
X399633D01*
G01X410000Y81500D02*
Y84833D01*
G01Y83917D02*
X410250Y84333D01*
X410667Y84667D01*
X411250Y84833D01*
X411833Y84667D01*
X412250Y84333D01*
X412500Y83917D01*
Y81500D01*
G01Y83917D02*
X412750Y84333D01*
X413167Y84667D01*
X413750Y84833D01*
X414333Y84667D01*
X414750Y84333D01*
X415000Y83833D01*
Y81500D01*
G01X418100Y84833D02*
Y81500D01*
G01Y86167D02*
X417933Y86250D01*
Y86417D01*
X418100Y86500D01*
X418267Y86417D01*
Y86250D01*
X418100Y86167D01*
G01X423700Y81500D02*
Y86500D01*
G01X272500Y71500D02*
Y66500D01*
G01X271333Y69833D02*
X273667D01*
G01X276933Y66500D02*
Y69833D01*
G01Y69167D02*
X277350Y69500D01*
X277767Y69750D01*
X278350Y69833D01*
X278767Y69750D01*
X279267Y69500D01*
G01X285200Y66500D02*
Y69833D01*
G01Y69250D02*
X284867Y69583D01*
X284367Y69750D01*
X283783Y69833D01*
X283200Y69667D01*
X282700Y69333D01*
X282367Y68833D01*
X282200Y68167D01*
X282367Y67500D01*
X282700Y67000D01*
X283200Y66667D01*
X283783Y66500D01*
X284367Y66583D01*
X284867Y66833D01*
X285200Y67167D01*
G01X290633Y69417D02*
X290050Y69750D01*
X289550Y69833D01*
X288883Y69667D01*
X288383Y69333D01*
X288050Y68750D01*
X287967Y68167D01*
X288050Y67583D01*
X288383Y67083D01*
X288883Y66667D01*
X289550Y66500D01*
X290133Y66667D01*
X290633Y67000D01*
G01X293650Y68750D02*
X296317D01*
X296067Y69333D01*
X295650Y69667D01*
X295067Y69833D01*
X294483Y69750D01*
X293983Y69500D01*
X293650Y68917D01*
X293483Y68417D01*
Y67917D01*
X293650Y67417D01*
X294067Y66917D01*
X294567Y66583D01*
X295150Y66500D01*
X295733Y66667D01*
X296317Y67167D01*
G01X304017Y69833D02*
X305017Y66500D01*
X306100Y69833D01*
X307183Y66500D01*
X308183Y69833D01*
G01X311700D02*
Y66500D01*
G01Y71167D02*
X311533Y71250D01*
Y71417D01*
X311700Y71500D01*
X311867Y71417D01*
Y71250D01*
X311700Y71167D01*
G01X318800Y71500D02*
Y66500D01*
G01Y67250D02*
X318467Y66833D01*
X317967Y66583D01*
X317383Y66500D01*
X316717Y66667D01*
X316217Y67083D01*
X315883Y67583D01*
X315800Y68167D01*
X315883Y68750D01*
X316217Y69250D01*
X316717Y69667D01*
X317383Y69833D01*
X317967Y69750D01*
X318383Y69583D01*
X318800Y69250D01*
G01X322900Y71500D02*
Y66500D01*
G01X321733Y69833D02*
X324067D01*
G01X327083Y66500D02*
Y71500D01*
G01Y69083D02*
X327500Y69500D01*
X327917Y69750D01*
X328583Y69833D01*
X329083Y69750D01*
X329667Y69417D01*
X329917Y68917D01*
Y66500D01*
G01X338033D02*
X341367Y68167D01*
X338033Y69833D01*
G01X350733Y66500D02*
X350900Y67583D01*
X351150Y68500D01*
X351483Y69333D01*
X351900Y70250D01*
X352567Y71500D01*
X349233D01*
G01X359600Y66500D02*
Y69833D01*
G01Y68917D02*
X359850Y69333D01*
X360267Y69667D01*
X360850Y69833D01*
X361433Y69667D01*
X361850Y69333D01*
X362100Y68917D01*
Y66500D01*
G01Y68917D02*
X362350Y69333D01*
X362767Y69667D01*
X363350Y69833D01*
X363933Y69667D01*
X364350Y69333D01*
X364600Y68833D01*
Y66500D01*
G01X367700Y69833D02*
Y66500D01*
G01Y71167D02*
X367533Y71250D01*
Y71417D01*
X367700Y71500D01*
X367867Y71417D01*
Y71250D01*
X367700Y71167D01*
G01X373300Y66500D02*
Y71500D01*
G01X272500Y52000D02*
Y47000D01*
G01X270583Y52000D02*
X274417D01*
G01X276683Y47000D02*
Y52000D01*
G01Y49583D02*
X277100Y50000D01*
X277517Y50250D01*
X278183Y50333D01*
X278683Y50250D01*
X279267Y49917D01*
X279517Y49417D01*
Y47000D01*
G01X282450Y49250D02*
X285117D01*
X284867Y49833D01*
X284450Y50167D01*
X283867Y50333D01*
X283283Y50250D01*
X282783Y50000D01*
X282450Y49417D01*
X282283Y48917D01*
Y48417D01*
X282450Y47917D01*
X282867Y47417D01*
X283367Y47083D01*
X283950Y47000D01*
X284533Y47167D01*
X285117Y47667D01*
G01X294900Y47000D02*
Y52000D01*
G01X302000Y47000D02*
Y50333D01*
G01Y49750D02*
X301667Y50083D01*
X301167Y50250D01*
X300583Y50333D01*
X300000Y50167D01*
X299500Y49833D01*
X299167Y49333D01*
X299000Y48667D01*
X299167Y48000D01*
X299500Y47500D01*
X300000Y47167D01*
X300583Y47000D01*
X301167Y47083D01*
X301667Y47333D01*
X302000Y47667D01*
G01X304933Y47000D02*
Y50333D01*
G01Y49667D02*
X305350Y50000D01*
X305767Y50250D01*
X306350Y50333D01*
X306767Y50250D01*
X307267Y50000D01*
G01X310533Y45750D02*
X311117Y45417D01*
X311783Y45333D01*
X312367Y45417D01*
X312867Y45833D01*
X313200Y46417D01*
Y50333D01*
G01Y49667D02*
X312867Y50000D01*
X312367Y50250D01*
X311783Y50333D01*
X311117Y50167D01*
X310700Y49833D01*
X310367Y49250D01*
X310200Y48667D01*
X310283Y48167D01*
X310617Y47583D01*
X311117Y47167D01*
X311783Y47000D01*
X312283Y47083D01*
X312867Y47417D01*
X313200Y47750D01*
G01X316050Y49250D02*
X318717D01*
X318467Y49833D01*
X318050Y50167D01*
X317467Y50333D01*
X316883Y50250D01*
X316383Y50000D01*
X316050Y49417D01*
X315883Y48917D01*
Y48417D01*
X316050Y47917D01*
X316467Y47417D01*
X316967Y47083D01*
X317550Y47000D01*
X318133Y47167D01*
X318717Y47667D01*
G01X321650Y47583D02*
X322067Y47250D01*
X322650Y47000D01*
X323150D01*
X323650Y47167D01*
X323983Y47417D01*
X324150Y47750D01*
X324067Y48250D01*
X323733Y48500D01*
X322233Y49000D01*
X321900Y49583D01*
X322067Y50000D01*
X322400Y50250D01*
X322900Y50333D01*
X323400Y50250D01*
X323900Y50000D01*
G01X328500Y52000D02*
Y47000D01*
G01X327333Y50333D02*
X329667D01*
G01X341200Y52000D02*
Y47000D01*
G01Y47750D02*
X340867Y47333D01*
X340367Y47083D01*
X339783Y47000D01*
X339117Y47167D01*
X338617Y47583D01*
X338283Y48083D01*
X338200Y48667D01*
X338283Y49250D01*
X338617Y49750D01*
X339117Y50167D01*
X339783Y50333D01*
X340367Y50250D01*
X340783Y50083D01*
X341200Y49750D01*
G01X345300Y50333D02*
Y47000D01*
G01Y51667D02*
X345133Y51750D01*
Y51917D01*
X345300Y52000D01*
X345467Y51917D01*
Y51750D01*
X345300Y51667D01*
G01X348400Y47000D02*
Y50333D01*
G01Y49417D02*
X348650Y49833D01*
X349067Y50167D01*
X349650Y50333D01*
X350233Y50167D01*
X350650Y49833D01*
X350900Y49417D01*
Y47000D01*
G01Y49417D02*
X351150Y49833D01*
X351567Y50167D01*
X352150Y50333D01*
X352733Y50167D01*
X353150Y49833D01*
X353400Y49333D01*
Y47000D01*
G01X355250Y49250D02*
X357917D01*
X357667Y49833D01*
X357250Y50167D01*
X356667Y50333D01*
X356083Y50250D01*
X355583Y50000D01*
X355250Y49417D01*
X355083Y48917D01*
Y48417D01*
X355250Y47917D01*
X355667Y47417D01*
X356167Y47083D01*
X356750Y47000D01*
X357333Y47167D01*
X357917Y47667D01*
G01X360683Y47000D02*
Y50333D01*
G01Y49500D02*
X361017Y49917D01*
X361517Y50250D01*
X362183Y50333D01*
X362767Y50250D01*
X363267Y49917D01*
X363517Y49333D01*
Y47000D01*
G01X366450Y47583D02*
X366867Y47250D01*
X367450Y47000D01*
X367950D01*
X368450Y47167D01*
X368783Y47417D01*
X368950Y47750D01*
X368867Y48250D01*
X368533Y48500D01*
X367033Y49000D01*
X366700Y49583D01*
X366867Y50000D01*
X367200Y50250D01*
X367700Y50333D01*
X368200Y50250D01*
X368700Y50000D01*
G01X373300Y50333D02*
Y47000D01*
G01Y51667D02*
X373133Y51750D01*
Y51917D01*
X373300Y52000D01*
X373467Y51917D01*
Y51750D01*
X373300Y51667D01*
G01X378900Y47000D02*
X378400Y47083D01*
X377900Y47417D01*
X377567Y48000D01*
X377400Y48667D01*
X377567Y49333D01*
X377900Y49917D01*
X378400Y50250D01*
X378900Y50333D01*
X379400Y50250D01*
X379900Y49917D01*
X380233Y49333D01*
X380317Y48667D01*
X380233Y48000D01*
X379900Y47417D01*
X379400Y47083D01*
X378900Y47000D01*
G01X383083D02*
Y50333D01*
G01Y49500D02*
X383417Y49917D01*
X383917Y50250D01*
X384583Y50333D01*
X385167Y50250D01*
X385667Y49917D01*
X385917Y49333D01*
Y47000D01*
G01X395700D02*
X395200Y47083D01*
X394700Y47417D01*
X394367Y48000D01*
X394200Y48667D01*
X394367Y49333D01*
X394700Y49917D01*
X395200Y50250D01*
X395700Y50333D01*
X396200Y50250D01*
X396700Y49917D01*
X397033Y49333D01*
X397117Y48667D01*
X397033Y48000D01*
X396700Y47417D01*
X396200Y47083D01*
X395700Y47000D01*
G01X400800D02*
Y51250D01*
X400967Y51667D01*
X401300Y51917D01*
X401800Y52000D01*
X402300Y51833D01*
X402550Y51417D01*
G01X401550Y50000D02*
X399883D01*
G01X411000Y45333D02*
Y50333D01*
G01Y49583D02*
X411417Y50000D01*
X411833Y50250D01*
X412500Y50333D01*
X413083Y50250D01*
X413667Y49833D01*
X413917Y49250D01*
X414000Y48667D01*
X413917Y48083D01*
X413667Y47500D01*
X413167Y47167D01*
X412500Y47000D01*
X411917Y47083D01*
X411333Y47333D01*
X411000Y47667D01*
G01X419600Y47000D02*
Y50333D01*
G01Y49750D02*
X419267Y50083D01*
X418767Y50250D01*
X418183Y50333D01*
X417600Y50167D01*
X417100Y49833D01*
X416767Y49333D01*
X416600Y48667D01*
X416767Y48000D01*
X417100Y47500D01*
X417600Y47167D01*
X418183Y47000D01*
X418767Y47083D01*
X419267Y47333D01*
X419600Y47667D01*
G01X425200Y52000D02*
Y47000D01*
G01Y47750D02*
X424867Y47333D01*
X424367Y47083D01*
X423783Y47000D01*
X423117Y47167D01*
X422617Y47583D01*
X422283Y48083D01*
X422200Y48667D01*
X422283Y49250D01*
X422617Y49750D01*
X423117Y50167D01*
X423783Y50333D01*
X424367Y50250D01*
X424783Y50083D01*
X425200Y49750D01*
G01X434900Y47000D02*
X434400Y47083D01*
X433900Y47417D01*
X433567Y48000D01*
X433400Y48667D01*
X433567Y49333D01*
X433900Y49917D01*
X434400Y50250D01*
X434900Y50333D01*
X435400Y50250D01*
X435900Y49917D01*
X436233Y49333D01*
X436317Y48667D01*
X436233Y48000D01*
X435900Y47417D01*
X435400Y47083D01*
X434900Y47000D01*
G01X439333D02*
Y50333D01*
G01Y49667D02*
X439750Y50000D01*
X440167Y50250D01*
X440750Y50333D01*
X441167Y50250D01*
X441667Y50000D01*
G01X453200Y52000D02*
Y47000D01*
G01Y47750D02*
X452867Y47333D01*
X452367Y47083D01*
X451783Y47000D01*
X451117Y47167D01*
X450617Y47583D01*
X450283Y48083D01*
X450200Y48667D01*
X450283Y49250D01*
X450617Y49750D01*
X451117Y50167D01*
X451783Y50333D01*
X452367Y50250D01*
X452783Y50083D01*
X453200Y49750D01*
G01X457300Y50333D02*
Y47000D01*
G01Y51667D02*
X457133Y51750D01*
Y51917D01*
X457300Y52000D01*
X457467Y51917D01*
Y51750D01*
X457300Y51667D01*
G01X464400Y47000D02*
Y50333D01*
G01Y49750D02*
X464067Y50083D01*
X463567Y50250D01*
X462983Y50333D01*
X462400Y50167D01*
X461900Y49833D01*
X461567Y49333D01*
X461400Y48667D01*
X461567Y48000D01*
X461900Y47500D01*
X462400Y47167D01*
X462983Y47000D01*
X463567Y47083D01*
X464067Y47333D01*
X464400Y47667D01*
G01X466000Y47000D02*
Y50333D01*
G01Y49417D02*
X466250Y49833D01*
X466667Y50167D01*
X467250Y50333D01*
X467833Y50167D01*
X468250Y49833D01*
X468500Y49417D01*
Y47000D01*
G01Y49417D02*
X468750Y49833D01*
X469167Y50167D01*
X469750Y50333D01*
X470333Y50167D01*
X470750Y49833D01*
X471000Y49333D01*
Y47000D01*
G01X472850Y49250D02*
X475517D01*
X475267Y49833D01*
X474850Y50167D01*
X474267Y50333D01*
X473683Y50250D01*
X473183Y50000D01*
X472850Y49417D01*
X472683Y48917D01*
Y48417D01*
X472850Y47917D01*
X473267Y47417D01*
X473767Y47083D01*
X474350Y47000D01*
X474933Y47167D01*
X475517Y47667D01*
G01X479700Y52000D02*
Y47000D01*
G01X478533Y50333D02*
X480867D01*
G01X484050Y49250D02*
X486717D01*
X486467Y49833D01*
X486050Y50167D01*
X485467Y50333D01*
X484883Y50250D01*
X484383Y50000D01*
X484050Y49417D01*
X483883Y48917D01*
Y48417D01*
X484050Y47917D01*
X484467Y47417D01*
X484967Y47083D01*
X485550Y47000D01*
X486133Y47167D01*
X486717Y47667D01*
G01X489733Y47000D02*
Y50333D01*
G01Y49667D02*
X490150Y50000D01*
X490567Y50250D01*
X491150Y50333D01*
X491567Y50250D01*
X492067Y50000D01*
G01X500433Y47000D02*
X503767Y48667D01*
X500433Y50333D01*
G01X513300Y47000D02*
Y52000D01*
X512300Y51000D01*
G01Y47000D02*
X514300D01*
G01X519900D02*
Y52000D01*
X516817Y48417D01*
X520983D01*
G01X527600Y47000D02*
Y50333D01*
G01Y49417D02*
X527850Y49833D01*
X528267Y50167D01*
X528850Y50333D01*
X529433Y50167D01*
X529850Y49833D01*
X530100Y49417D01*
Y47000D01*
G01Y49417D02*
X530350Y49833D01*
X530767Y50167D01*
X531350Y50333D01*
X531933Y50167D01*
X532350Y49833D01*
X532600Y49333D01*
Y47000D01*
G01X535700Y50333D02*
Y47000D01*
G01Y51667D02*
X535533Y51750D01*
Y51917D01*
X535700Y52000D01*
X535867Y51917D01*
Y51750D01*
X535700Y51667D01*
G01X541300Y47000D02*
Y52000D01*
G01X273580Y32670D02*
Y27670D01*
G01X271663Y32670D02*
X275497D01*
G01X277763Y27670D02*
Y32670D01*
G01Y30253D02*
X278180Y30670D01*
X278597Y30920D01*
X279263Y31003D01*
X279763Y30920D01*
X280347Y30587D01*
X280597Y30087D01*
Y27670D01*
G01X283530Y29920D02*
X286197D01*
X285947Y30503D01*
X285530Y30837D01*
X284947Y31003D01*
X284363Y30920D01*
X283863Y30670D01*
X283530Y30087D01*
X283363Y29587D01*
Y29087D01*
X283530Y28587D01*
X283947Y28087D01*
X284447Y27753D01*
X285030Y27670D01*
X285613Y27837D01*
X286197Y28337D01*
G01X295980Y27670D02*
Y32670D01*
G01X303080Y27670D02*
Y31003D01*
G01Y30420D02*
X302747Y30753D01*
X302247Y30920D01*
X301663Y31003D01*
X301080Y30837D01*
X300580Y30503D01*
X300247Y30003D01*
X300080Y29337D01*
X300247Y28670D01*
X300580Y28170D01*
X301080Y27837D01*
X301663Y27670D01*
X302247Y27753D01*
X302747Y28003D01*
X303080Y28337D01*
G01X306013Y27670D02*
Y31003D01*
G01Y30337D02*
X306430Y30670D01*
X306847Y30920D01*
X307430Y31003D01*
X307847Y30920D01*
X308347Y30670D01*
G01X311613Y26420D02*
X312197Y26087D01*
X312863Y26003D01*
X313447Y26087D01*
X313947Y26503D01*
X314280Y27087D01*
Y31003D01*
G01Y30337D02*
X313947Y30670D01*
X313447Y30920D01*
X312863Y31003D01*
X312197Y30837D01*
X311780Y30503D01*
X311447Y29920D01*
X311280Y29337D01*
X311363Y28837D01*
X311697Y28253D01*
X312197Y27837D01*
X312863Y27670D01*
X313363Y27753D01*
X313947Y28087D01*
X314280Y28420D01*
G01X317130Y29920D02*
X319797D01*
X319547Y30503D01*
X319130Y30837D01*
X318547Y31003D01*
X317963Y30920D01*
X317463Y30670D01*
X317130Y30087D01*
X316963Y29587D01*
Y29087D01*
X317130Y28587D01*
X317547Y28087D01*
X318047Y27753D01*
X318630Y27670D01*
X319213Y27837D01*
X319797Y28337D01*
G01X322730Y28253D02*
X323147Y27920D01*
X323730Y27670D01*
X324230D01*
X324730Y27837D01*
X325063Y28087D01*
X325230Y28420D01*
X325147Y28920D01*
X324813Y29170D01*
X323313Y29670D01*
X322980Y30253D01*
X323147Y30670D01*
X323480Y30920D01*
X323980Y31003D01*
X324480Y30920D01*
X324980Y30670D01*
G01X329580Y32670D02*
Y27670D01*
G01X328413Y31003D02*
X330747D01*
G01X342280Y32670D02*
Y27670D01*
G01Y28420D02*
X341947Y28003D01*
X341447Y27753D01*
X340863Y27670D01*
X340197Y27837D01*
X339697Y28253D01*
X339363Y28753D01*
X339280Y29337D01*
X339363Y29920D01*
X339697Y30420D01*
X340197Y30837D01*
X340863Y31003D01*
X341447Y30920D01*
X341863Y30753D01*
X342280Y30420D01*
G01X346380Y31003D02*
Y27670D01*
G01Y32337D02*
X346213Y32420D01*
Y32587D01*
X346380Y32670D01*
X346547Y32587D01*
Y32420D01*
X346380Y32337D01*
G01X349480Y27670D02*
Y31003D01*
G01Y30087D02*
X349730Y30503D01*
X350147Y30837D01*
X350730Y31003D01*
X351313Y30837D01*
X351730Y30503D01*
X351980Y30087D01*
Y27670D01*
G01Y30087D02*
X352230Y30503D01*
X352647Y30837D01*
X353230Y31003D01*
X353813Y30837D01*
X354230Y30503D01*
X354480Y30003D01*
Y27670D01*
G01X356330Y29920D02*
X358997D01*
X358747Y30503D01*
X358330Y30837D01*
X357747Y31003D01*
X357163Y30920D01*
X356663Y30670D01*
X356330Y30087D01*
X356163Y29587D01*
Y29087D01*
X356330Y28587D01*
X356747Y28087D01*
X357247Y27753D01*
X357830Y27670D01*
X358413Y27837D01*
X358997Y28337D01*
G01X361763Y27670D02*
Y31003D01*
G01Y30170D02*
X362097Y30587D01*
X362597Y30920D01*
X363263Y31003D01*
X363847Y30920D01*
X364347Y30587D01*
X364597Y30003D01*
Y27670D01*
G01X367530Y28253D02*
X367947Y27920D01*
X368530Y27670D01*
X369030D01*
X369530Y27837D01*
X369863Y28087D01*
X370030Y28420D01*
X369947Y28920D01*
X369613Y29170D01*
X368113Y29670D01*
X367780Y30253D01*
X367947Y30670D01*
X368280Y30920D01*
X368780Y31003D01*
X369280Y30920D01*
X369780Y30670D01*
G01X374380Y31003D02*
Y27670D01*
G01Y32337D02*
X374213Y32420D01*
Y32587D01*
X374380Y32670D01*
X374547Y32587D01*
Y32420D01*
X374380Y32337D01*
G01X379980Y27670D02*
X379480Y27753D01*
X378980Y28087D01*
X378647Y28670D01*
X378480Y29337D01*
X378647Y30003D01*
X378980Y30587D01*
X379480Y30920D01*
X379980Y31003D01*
X380480Y30920D01*
X380980Y30587D01*
X381313Y30003D01*
X381397Y29337D01*
X381313Y28670D01*
X380980Y28087D01*
X380480Y27753D01*
X379980Y27670D01*
G01X384163D02*
Y31003D01*
G01Y30170D02*
X384497Y30587D01*
X384997Y30920D01*
X385663Y31003D01*
X386247Y30920D01*
X386747Y30587D01*
X386997Y30003D01*
Y27670D01*
G01X396780D02*
X396280Y27753D01*
X395780Y28087D01*
X395447Y28670D01*
X395280Y29337D01*
X395447Y30003D01*
X395780Y30587D01*
X396280Y30920D01*
X396780Y31003D01*
X397280Y30920D01*
X397780Y30587D01*
X398113Y30003D01*
X398197Y29337D01*
X398113Y28670D01*
X397780Y28087D01*
X397280Y27753D01*
X396780Y27670D01*
G01X401880D02*
Y31920D01*
X402047Y32337D01*
X402380Y32587D01*
X402880Y32670D01*
X403380Y32503D01*
X403630Y32087D01*
G01X402630Y30670D02*
X400963D01*
G01X412080Y26003D02*
Y31003D01*
G01Y30253D02*
X412497Y30670D01*
X412913Y30920D01*
X413580Y31003D01*
X414163Y30920D01*
X414747Y30503D01*
X414997Y29920D01*
X415080Y29337D01*
X414997Y28753D01*
X414747Y28170D01*
X414247Y27837D01*
X413580Y27670D01*
X412997Y27753D01*
X412413Y28003D01*
X412080Y28337D01*
G01X420680Y27670D02*
Y31003D01*
G01Y30420D02*
X420347Y30753D01*
X419847Y30920D01*
X419263Y31003D01*
X418680Y30837D01*
X418180Y30503D01*
X417847Y30003D01*
X417680Y29337D01*
X417847Y28670D01*
X418180Y28170D01*
X418680Y27837D01*
X419263Y27670D01*
X419847Y27753D01*
X420347Y28003D01*
X420680Y28337D01*
G01X426280Y32670D02*
Y27670D01*
G01Y28420D02*
X425947Y28003D01*
X425447Y27753D01*
X424863Y27670D01*
X424197Y27837D01*
X423697Y28253D01*
X423363Y28753D01*
X423280Y29337D01*
X423363Y29920D01*
X423697Y30420D01*
X424197Y30837D01*
X424863Y31003D01*
X425447Y30920D01*
X425863Y30753D01*
X426280Y30420D01*
G01X435980Y27670D02*
X435480Y27753D01*
X434980Y28087D01*
X434647Y28670D01*
X434480Y29337D01*
X434647Y30003D01*
X434980Y30587D01*
X435480Y30920D01*
X435980Y31003D01*
X436480Y30920D01*
X436980Y30587D01*
X437313Y30003D01*
X437397Y29337D01*
X437313Y28670D01*
X436980Y28087D01*
X436480Y27753D01*
X435980Y27670D01*
G01X440413D02*
Y31003D01*
G01Y30337D02*
X440830Y30670D01*
X441247Y30920D01*
X441830Y31003D01*
X442247Y30920D01*
X442747Y30670D01*
G01X454280Y32670D02*
Y27670D01*
G01Y28420D02*
X453947Y28003D01*
X453447Y27753D01*
X452863Y27670D01*
X452197Y27837D01*
X451697Y28253D01*
X451363Y28753D01*
X451280Y29337D01*
X451363Y29920D01*
X451697Y30420D01*
X452197Y30837D01*
X452863Y31003D01*
X453447Y30920D01*
X453863Y30753D01*
X454280Y30420D01*
G01X458380Y31003D02*
Y27670D01*
G01Y32337D02*
X458213Y32420D01*
Y32587D01*
X458380Y32670D01*
X458547Y32587D01*
Y32420D01*
X458380Y32337D01*
G01X465480Y27670D02*
Y31003D01*
G01Y30420D02*
X465147Y30753D01*
X464647Y30920D01*
X464063Y31003D01*
X463480Y30837D01*
X462980Y30503D01*
X462647Y30003D01*
X462480Y29337D01*
X462647Y28670D01*
X462980Y28170D01*
X463480Y27837D01*
X464063Y27670D01*
X464647Y27753D01*
X465147Y28003D01*
X465480Y28337D01*
G01X467080Y27670D02*
Y31003D01*
G01Y30087D02*
X467330Y30503D01*
X467747Y30837D01*
X468330Y31003D01*
X468913Y30837D01*
X469330Y30503D01*
X469580Y30087D01*
Y27670D01*
G01Y30087D02*
X469830Y30503D01*
X470247Y30837D01*
X470830Y31003D01*
X471413Y30837D01*
X471830Y30503D01*
X472080Y30003D01*
Y27670D01*
G01X473930Y29920D02*
X476597D01*
X476347Y30503D01*
X475930Y30837D01*
X475347Y31003D01*
X474763Y30920D01*
X474263Y30670D01*
X473930Y30087D01*
X473763Y29587D01*
Y29087D01*
X473930Y28587D01*
X474347Y28087D01*
X474847Y27753D01*
X475430Y27670D01*
X476013Y27837D01*
X476597Y28337D01*
G01X480780Y32670D02*
Y27670D01*
G01X479613Y31003D02*
X481947D01*
G01X485130Y29920D02*
X487797D01*
X487547Y30503D01*
X487130Y30837D01*
X486547Y31003D01*
X485963Y30920D01*
X485463Y30670D01*
X485130Y30087D01*
X484963Y29587D01*
Y29087D01*
X485130Y28587D01*
X485547Y28087D01*
X486047Y27753D01*
X486630Y27670D01*
X487213Y27837D01*
X487797Y28337D01*
G01X490813Y27670D02*
Y31003D01*
G01Y30337D02*
X491230Y30670D01*
X491647Y30920D01*
X492230Y31003D01*
X492647Y30920D01*
X493147Y30670D01*
G01X504847Y27670D02*
X501513Y29337D01*
X504847Y31003D01*
G01X507697Y28587D02*
X509863D01*
G01Y30087D02*
X507697D01*
G01X519980Y27670D02*
Y32670D01*
X518980Y31670D01*
G01Y27670D02*
X520980D01*
G01X526580D02*
Y32670D01*
X523497Y29087D01*
X527663D01*
G01X534280Y27670D02*
Y31003D01*
G01Y30087D02*
X534530Y30503D01*
X534947Y30837D01*
X535530Y31003D01*
X536113Y30837D01*
X536530Y30503D01*
X536780Y30087D01*
Y27670D01*
G01Y30087D02*
X537030Y30503D01*
X537447Y30837D01*
X538030Y31003D01*
X538613Y30837D01*
X539030Y30503D01*
X539280Y30003D01*
Y27670D01*
G01X542380Y31003D02*
Y27670D01*
G01Y32337D02*
X542213Y32420D01*
Y32587D01*
X542380Y32670D01*
X542547Y32587D01*
Y32420D01*
X542380Y32337D01*
G01X547980Y27670D02*
Y32670D01*
G01X272500Y15000D02*
Y10000D01*
G01X270583Y15000D02*
X274417D01*
G01X276683Y10000D02*
Y15000D01*
G01Y12583D02*
X277100Y13000D01*
X277517Y13250D01*
X278183Y13333D01*
X278683Y13250D01*
X279267Y12917D01*
X279517Y12417D01*
Y10000D01*
G01X282450Y12250D02*
X285117D01*
X284867Y12833D01*
X284450Y13167D01*
X283867Y13333D01*
X283283Y13250D01*
X282783Y13000D01*
X282450Y12417D01*
X282283Y11917D01*
Y11417D01*
X282450Y10917D01*
X282867Y10417D01*
X283367Y10083D01*
X283950Y10000D01*
X284533Y10167D01*
X285117Y10667D01*
G01X294900Y10000D02*
Y15000D01*
G01X302000Y10000D02*
Y13333D01*
G01Y12750D02*
X301667Y13083D01*
X301167Y13250D01*
X300583Y13333D01*
X300000Y13167D01*
X299500Y12833D01*
X299167Y12333D01*
X299000Y11667D01*
X299167Y11000D01*
X299500Y10500D01*
X300000Y10167D01*
X300583Y10000D01*
X301167Y10083D01*
X301667Y10333D01*
X302000Y10667D01*
G01X304933Y10000D02*
Y13333D01*
G01Y12667D02*
X305350Y13000D01*
X305767Y13250D01*
X306350Y13333D01*
X306767Y13250D01*
X307267Y13000D01*
G01X310533Y8750D02*
X311117Y8417D01*
X311783Y8333D01*
X312367Y8417D01*
X312867Y8833D01*
X313200Y9417D01*
Y13333D01*
G01Y12667D02*
X312867Y13000D01*
X312367Y13250D01*
X311783Y13333D01*
X311117Y13167D01*
X310700Y12833D01*
X310367Y12250D01*
X310200Y11667D01*
X310283Y11167D01*
X310617Y10583D01*
X311117Y10167D01*
X311783Y10000D01*
X312283Y10083D01*
X312867Y10417D01*
X313200Y10750D01*
G01X316050Y12250D02*
X318717D01*
X318467Y12833D01*
X318050Y13167D01*
X317467Y13333D01*
X316883Y13250D01*
X316383Y13000D01*
X316050Y12417D01*
X315883Y11917D01*
Y11417D01*
X316050Y10917D01*
X316467Y10417D01*
X316967Y10083D01*
X317550Y10000D01*
X318133Y10167D01*
X318717Y10667D01*
G01X321650Y10583D02*
X322067Y10250D01*
X322650Y10000D01*
X323150D01*
X323650Y10167D01*
X323983Y10417D01*
X324150Y10750D01*
X324067Y11250D01*
X323733Y11500D01*
X322233Y12000D01*
X321900Y12583D01*
X322067Y13000D01*
X322400Y13250D01*
X322900Y13333D01*
X323400Y13250D01*
X323900Y13000D01*
G01X328500Y15000D02*
Y10000D01*
G01X327333Y13333D02*
X329667D01*
G01X341200Y15000D02*
Y10000D01*
G01Y10750D02*
X340867Y10333D01*
X340367Y10083D01*
X339783Y10000D01*
X339117Y10167D01*
X338617Y10583D01*
X338283Y11083D01*
X338200Y11667D01*
X338283Y12250D01*
X338617Y12750D01*
X339117Y13167D01*
X339783Y13333D01*
X340367Y13250D01*
X340783Y13083D01*
X341200Y12750D01*
G01X345300Y13333D02*
Y10000D01*
G01Y14667D02*
X345133Y14750D01*
Y14917D01*
X345300Y15000D01*
X345467Y14917D01*
Y14750D01*
X345300Y14667D01*
G01X348400Y10000D02*
Y13333D01*
G01Y12417D02*
X348650Y12833D01*
X349067Y13167D01*
X349650Y13333D01*
X350233Y13167D01*
X350650Y12833D01*
X350900Y12417D01*
Y10000D01*
G01Y12417D02*
X351150Y12833D01*
X351567Y13167D01*
X352150Y13333D01*
X352733Y13167D01*
X353150Y12833D01*
X353400Y12333D01*
Y10000D01*
G01X355250Y12250D02*
X357917D01*
X357667Y12833D01*
X357250Y13167D01*
X356667Y13333D01*
X356083Y13250D01*
X355583Y13000D01*
X355250Y12417D01*
X355083Y11917D01*
Y11417D01*
X355250Y10917D01*
X355667Y10417D01*
X356167Y10083D01*
X356750Y10000D01*
X357333Y10167D01*
X357917Y10667D01*
G01X360683Y10000D02*
Y13333D01*
G01Y12500D02*
X361017Y12917D01*
X361517Y13250D01*
X362183Y13333D01*
X362767Y13250D01*
X363267Y12917D01*
X363517Y12333D01*
Y10000D01*
G01X366450Y10583D02*
X366867Y10250D01*
X367450Y10000D01*
X367950D01*
X368450Y10167D01*
X368783Y10417D01*
X368950Y10750D01*
X368867Y11250D01*
X368533Y11500D01*
X367033Y12000D01*
X366700Y12583D01*
X366867Y13000D01*
X367200Y13250D01*
X367700Y13333D01*
X368200Y13250D01*
X368700Y13000D01*
G01X373300Y13333D02*
Y10000D01*
G01Y14667D02*
X373133Y14750D01*
Y14917D01*
X373300Y15000D01*
X373467Y14917D01*
Y14750D01*
X373300Y14667D01*
G01X378900Y10000D02*
X378400Y10083D01*
X377900Y10417D01*
X377567Y11000D01*
X377400Y11667D01*
X377567Y12333D01*
X377900Y12917D01*
X378400Y13250D01*
X378900Y13333D01*
X379400Y13250D01*
X379900Y12917D01*
X380233Y12333D01*
X380317Y11667D01*
X380233Y11000D01*
X379900Y10417D01*
X379400Y10083D01*
X378900Y10000D01*
G01X383083D02*
Y13333D01*
G01Y12500D02*
X383417Y12917D01*
X383917Y13250D01*
X384583Y13333D01*
X385167Y13250D01*
X385667Y12917D01*
X385917Y12333D01*
Y10000D01*
G01X395700D02*
X395200Y10083D01*
X394700Y10417D01*
X394367Y11000D01*
X394200Y11667D01*
X394367Y12333D01*
X394700Y12917D01*
X395200Y13250D01*
X395700Y13333D01*
X396200Y13250D01*
X396700Y12917D01*
X397033Y12333D01*
X397117Y11667D01*
X397033Y11000D01*
X396700Y10417D01*
X396200Y10083D01*
X395700Y10000D01*
G01X400800D02*
Y14250D01*
X400967Y14667D01*
X401300Y14917D01*
X401800Y15000D01*
X402300Y14833D01*
X402550Y14417D01*
G01X401550Y13000D02*
X399883D01*
G01X411000Y8333D02*
Y13333D01*
G01Y12583D02*
X411417Y13000D01*
X411833Y13250D01*
X412500Y13333D01*
X413083Y13250D01*
X413667Y12833D01*
X413917Y12250D01*
X414000Y11667D01*
X413917Y11083D01*
X413667Y10500D01*
X413167Y10167D01*
X412500Y10000D01*
X411917Y10083D01*
X411333Y10333D01*
X411000Y10667D01*
G01X419600Y10000D02*
Y13333D01*
G01Y12750D02*
X419267Y13083D01*
X418767Y13250D01*
X418183Y13333D01*
X417600Y13167D01*
X417100Y12833D01*
X416767Y12333D01*
X416600Y11667D01*
X416767Y11000D01*
X417100Y10500D01*
X417600Y10167D01*
X418183Y10000D01*
X418767Y10083D01*
X419267Y10333D01*
X419600Y10667D01*
G01X425200Y15000D02*
Y10000D01*
G01Y10750D02*
X424867Y10333D01*
X424367Y10083D01*
X423783Y10000D01*
X423117Y10167D01*
X422617Y10583D01*
X422283Y11083D01*
X422200Y11667D01*
X422283Y12250D01*
X422617Y12750D01*
X423117Y13167D01*
X423783Y13333D01*
X424367Y13250D01*
X424783Y13083D01*
X425200Y12750D01*
G01X434900Y10000D02*
X434400Y10083D01*
X433900Y10417D01*
X433567Y11000D01*
X433400Y11667D01*
X433567Y12333D01*
X433900Y12917D01*
X434400Y13250D01*
X434900Y13333D01*
X435400Y13250D01*
X435900Y12917D01*
X436233Y12333D01*
X436317Y11667D01*
X436233Y11000D01*
X435900Y10417D01*
X435400Y10083D01*
X434900Y10000D01*
G01X439333D02*
Y13333D01*
G01Y12667D02*
X439750Y13000D01*
X440167Y13250D01*
X440750Y13333D01*
X441167Y13250D01*
X441667Y13000D01*
G01X453200Y15000D02*
Y10000D01*
G01Y10750D02*
X452867Y10333D01*
X452367Y10083D01*
X451783Y10000D01*
X451117Y10167D01*
X450617Y10583D01*
X450283Y11083D01*
X450200Y11667D01*
X450283Y12250D01*
X450617Y12750D01*
X451117Y13167D01*
X451783Y13333D01*
X452367Y13250D01*
X452783Y13083D01*
X453200Y12750D01*
G01X457300Y13333D02*
Y10000D01*
G01Y14667D02*
X457133Y14750D01*
Y14917D01*
X457300Y15000D01*
X457467Y14917D01*
Y14750D01*
X457300Y14667D01*
G01X464400Y10000D02*
Y13333D01*
G01Y12750D02*
X464067Y13083D01*
X463567Y13250D01*
X462983Y13333D01*
X462400Y13167D01*
X461900Y12833D01*
X461567Y12333D01*
X461400Y11667D01*
X461567Y11000D01*
X461900Y10500D01*
X462400Y10167D01*
X462983Y10000D01*
X463567Y10083D01*
X464067Y10333D01*
X464400Y10667D01*
G01X466000Y10000D02*
Y13333D01*
G01Y12417D02*
X466250Y12833D01*
X466667Y13167D01*
X467250Y13333D01*
X467833Y13167D01*
X468250Y12833D01*
X468500Y12417D01*
Y10000D01*
G01Y12417D02*
X468750Y12833D01*
X469167Y13167D01*
X469750Y13333D01*
X470333Y13167D01*
X470750Y12833D01*
X471000Y12333D01*
Y10000D01*
G01X472850Y12250D02*
X475517D01*
X475267Y12833D01*
X474850Y13167D01*
X474267Y13333D01*
X473683Y13250D01*
X473183Y13000D01*
X472850Y12417D01*
X472683Y11917D01*
Y11417D01*
X472850Y10917D01*
X473267Y10417D01*
X473767Y10083D01*
X474350Y10000D01*
X474933Y10167D01*
X475517Y10667D01*
G01X479700Y15000D02*
Y10000D01*
G01X478533Y13333D02*
X480867D01*
G01X484050Y12250D02*
X486717D01*
X486467Y12833D01*
X486050Y13167D01*
X485467Y13333D01*
X484883Y13250D01*
X484383Y13000D01*
X484050Y12417D01*
X483883Y11917D01*
Y11417D01*
X484050Y10917D01*
X484467Y10417D01*
X484967Y10083D01*
X485550Y10000D01*
X486133Y10167D01*
X486717Y10667D01*
G01X489733Y10000D02*
Y13333D01*
G01Y12667D02*
X490150Y13000D01*
X490567Y13250D01*
X491150Y13333D01*
X491567Y13250D01*
X492067Y13000D01*
G01X500433Y10000D02*
X503767Y11667D01*
X500433Y13333D01*
G01X507700Y10000D02*
Y15000D01*
X506700Y14000D01*
G01Y10000D02*
X508700D01*
G01X514300D02*
Y15000D01*
X511217Y11417D01*
X515383D01*
G01X522000Y10000D02*
Y13333D01*
G01Y12417D02*
X522250Y12833D01*
X522667Y13167D01*
X523250Y13333D01*
X523833Y13167D01*
X524250Y12833D01*
X524500Y12417D01*
Y10000D01*
G01Y12417D02*
X524750Y12833D01*
X525167Y13167D01*
X525750Y13333D01*
X526333Y13167D01*
X526750Y12833D01*
X527000Y12333D01*
Y10000D01*
G01X530100Y13333D02*
Y10000D01*
G01Y14667D02*
X529933Y14750D01*
Y14917D01*
X530100Y15000D01*
X530267Y14917D01*
Y14750D01*
X530100Y14667D01*
G01X535700Y10000D02*
Y15000D01*
G01X264000Y5500D02*
X694500D01*
G01X264000Y40500D02*
X694500D01*
G01X264000Y75500D02*
X694500D01*
G01X264000Y90500D02*
X694500D01*
G01X271250Y141583D02*
X271667Y141250D01*
X272250Y141000D01*
X272750D01*
X273250Y141167D01*
X273583Y141417D01*
X273750Y141750D01*
X273667Y142250D01*
X273333Y142500D01*
X271833Y143000D01*
X271500Y143583D01*
X271667Y144000D01*
X272000Y144250D01*
X272500Y144333D01*
X273000Y144250D01*
X273500Y144000D01*
G01X276600Y139333D02*
Y144333D01*
G01Y143583D02*
X277017Y144000D01*
X277433Y144250D01*
X278100Y144333D01*
X278683Y144250D01*
X279267Y143833D01*
X279517Y143250D01*
X279600Y142667D01*
X279517Y142083D01*
X279267Y141500D01*
X278767Y141167D01*
X278100Y141000D01*
X277517Y141083D01*
X276933Y141333D01*
X276600Y141667D01*
G01X282450Y143250D02*
X285117D01*
X284867Y143833D01*
X284450Y144167D01*
X283867Y144333D01*
X283283Y144250D01*
X282783Y144000D01*
X282450Y143417D01*
X282283Y142917D01*
Y142417D01*
X282450Y141917D01*
X282867Y141417D01*
X283367Y141083D01*
X283950Y141000D01*
X284533Y141167D01*
X285117Y141667D01*
G01X290633Y143917D02*
X290050Y144250D01*
X289550Y144333D01*
X288883Y144167D01*
X288383Y143833D01*
X288050Y143250D01*
X287967Y142667D01*
X288050Y142083D01*
X288383Y141583D01*
X288883Y141167D01*
X289550Y141000D01*
X290133Y141167D01*
X290633Y141500D01*
G01X294900Y144333D02*
Y141000D01*
G01Y145667D02*
X294733Y145750D01*
Y145917D01*
X294900Y146000D01*
X295067Y145917D01*
Y145750D01*
X294900Y145667D01*
G01X300000Y141000D02*
Y145250D01*
X300167Y145667D01*
X300500Y145917D01*
X301000Y146000D01*
X301500Y145833D01*
X301750Y145417D01*
G01X300750Y144000D02*
X299083D01*
G01X306100Y144333D02*
Y141000D01*
G01Y145667D02*
X305933Y145750D01*
Y145917D01*
X306100Y146000D01*
X306267Y145917D01*
Y145750D01*
X306100Y145667D01*
G01X313033Y143917D02*
X312450Y144250D01*
X311950Y144333D01*
X311283Y144167D01*
X310783Y143833D01*
X310450Y143250D01*
X310367Y142667D01*
X310450Y142083D01*
X310783Y141583D01*
X311283Y141167D01*
X311950Y141000D01*
X312533Y141167D01*
X313033Y141500D01*
G01X318800Y141000D02*
Y144333D01*
G01Y143750D02*
X318467Y144083D01*
X317967Y144250D01*
X317383Y144333D01*
X316800Y144167D01*
X316300Y143833D01*
X315967Y143333D01*
X315800Y142667D01*
X315967Y142000D01*
X316300Y141500D01*
X316800Y141167D01*
X317383Y141000D01*
X317967Y141083D01*
X318467Y141333D01*
X318800Y141667D01*
G01X322900Y146000D02*
Y141000D01*
G01X321733Y144333D02*
X324067D01*
G01X328500D02*
Y141000D01*
G01Y145667D02*
X328333Y145750D01*
Y145917D01*
X328500Y146000D01*
X328667Y145917D01*
Y145750D01*
X328500Y145667D01*
G01X334100Y141000D02*
X333600Y141083D01*
X333100Y141417D01*
X332767Y142000D01*
X332600Y142667D01*
X332767Y143333D01*
X333100Y143917D01*
X333600Y144250D01*
X334100Y144333D01*
X334600Y144250D01*
X335100Y143917D01*
X335433Y143333D01*
X335517Y142667D01*
X335433Y142000D01*
X335100Y141417D01*
X334600Y141083D01*
X334100Y141000D01*
G01X338283D02*
Y144333D01*
G01Y143500D02*
X338617Y143917D01*
X339117Y144250D01*
X339783Y144333D01*
X340367Y144250D01*
X340867Y143917D01*
X341117Y143333D01*
Y141000D01*
G01X345300Y140833D02*
X345133Y140917D01*
Y141083D01*
X345300Y141167D01*
X345467Y141083D01*
Y140917D01*
X345300Y140833D01*
G01X272500Y101500D02*
Y96500D01*
G01X271333Y99833D02*
X273667D01*
G01X276933Y96500D02*
Y99833D01*
G01Y99167D02*
X277350Y99500D01*
X277767Y99750D01*
X278350Y99833D01*
X278767Y99750D01*
X279267Y99500D01*
G01X285200Y96500D02*
Y99833D01*
G01Y99250D02*
X284867Y99583D01*
X284367Y99750D01*
X283783Y99833D01*
X283200Y99667D01*
X282700Y99333D01*
X282367Y98833D01*
X282200Y98167D01*
X282367Y97500D01*
X282700Y97000D01*
X283200Y96667D01*
X283783Y96500D01*
X284367Y96583D01*
X284867Y96833D01*
X285200Y97167D01*
G01X290633Y99417D02*
X290050Y99750D01*
X289550Y99833D01*
X288883Y99667D01*
X288383Y99333D01*
X288050Y98750D01*
X287967Y98167D01*
X288050Y97583D01*
X288383Y97083D01*
X288883Y96667D01*
X289550Y96500D01*
X290133Y96667D01*
X290633Y97000D01*
G01X293650Y98750D02*
X296317D01*
X296067Y99333D01*
X295650Y99667D01*
X295067Y99833D01*
X294483Y99750D01*
X293983Y99500D01*
X293650Y98917D01*
X293483Y98417D01*
Y97917D01*
X293650Y97417D01*
X294067Y96917D01*
X294567Y96583D01*
X295150Y96500D01*
X295733Y96667D01*
X296317Y97167D01*
G01X304017Y99833D02*
X305017Y96500D01*
X306100Y99833D01*
X307183Y96500D01*
X308183Y99833D01*
G01X311700D02*
Y96500D01*
G01Y101167D02*
X311533Y101250D01*
Y101417D01*
X311700Y101500D01*
X311867Y101417D01*
Y101250D01*
X311700Y101167D01*
G01X318800Y101500D02*
Y96500D01*
G01Y97250D02*
X318467Y96833D01*
X317967Y96583D01*
X317383Y96500D01*
X316717Y96667D01*
X316217Y97083D01*
X315883Y97583D01*
X315800Y98167D01*
X315883Y98750D01*
X316217Y99250D01*
X316717Y99667D01*
X317383Y99833D01*
X317967Y99750D01*
X318383Y99583D01*
X318800Y99250D01*
G01X322900Y101500D02*
Y96500D01*
G01X321733Y99833D02*
X324067D01*
G01X327083Y96500D02*
Y101500D01*
G01Y99083D02*
X327500Y99500D01*
X327917Y99750D01*
X328583Y99833D01*
X329083Y99750D01*
X329667Y99417D01*
X329917Y98917D01*
Y96500D01*
G01X341367D02*
X338033Y98167D01*
X341367Y99833D01*
G01X344217Y97417D02*
X346383D01*
G01Y98917D02*
X344217D01*
G01X354667Y97250D02*
X355167Y96833D01*
X355750Y96583D01*
X356500Y96500D01*
X357250Y96667D01*
X357833Y97000D01*
X358250Y97583D01*
X358333Y98250D01*
X358167Y98917D01*
X357750Y99333D01*
X357167Y99667D01*
X356583Y99750D01*
X356000Y99667D01*
X355250Y99333D01*
X355500Y101500D01*
X357750D01*
G01X365200Y96500D02*
Y99833D01*
G01Y98917D02*
X365450Y99333D01*
X365867Y99667D01*
X366450Y99833D01*
X367033Y99667D01*
X367450Y99333D01*
X367700Y98917D01*
Y96500D01*
G01Y98917D02*
X367950Y99333D01*
X368367Y99667D01*
X368950Y99833D01*
X369533Y99667D01*
X369950Y99333D01*
X370200Y98833D01*
Y96500D01*
G01X373300Y99833D02*
Y96500D01*
G01Y101167D02*
X373133Y101250D01*
Y101417D01*
X373300Y101500D01*
X373467Y101417D01*
Y101250D01*
X373300Y101167D01*
G01X378900Y96500D02*
Y101500D01*
G01X270833Y110000D02*
Y115000D01*
X272917D01*
X273583Y114750D01*
X274000Y114417D01*
X274167Y113750D01*
X274000Y113083D01*
X273500Y112667D01*
X272917Y112417D01*
X270833D01*
G01X272917D02*
X274167Y110000D01*
G01X276850Y112250D02*
X279517D01*
X279267Y112833D01*
X278850Y113167D01*
X278267Y113333D01*
X277683Y113250D01*
X277183Y113000D01*
X276850Y112417D01*
X276683Y111917D01*
Y111417D01*
X276850Y110917D01*
X277267Y110417D01*
X277767Y110083D01*
X278350Y110000D01*
X278933Y110167D01*
X279517Y110667D01*
G01X283700Y110000D02*
Y115000D01*
G01X290800Y110000D02*
Y113333D01*
G01Y112750D02*
X290467Y113083D01*
X289967Y113250D01*
X289383Y113333D01*
X288800Y113167D01*
X288300Y112833D01*
X287967Y112333D01*
X287800Y111667D01*
X287967Y111000D01*
X288300Y110500D01*
X288800Y110167D01*
X289383Y110000D01*
X289967Y110083D01*
X290467Y110333D01*
X290800Y110667D01*
G01X294900Y115000D02*
Y110000D01*
G01X293733Y113333D02*
X296067D01*
G01X300500D02*
Y110000D01*
G01Y114667D02*
X300333Y114750D01*
Y114917D01*
X300500Y115000D01*
X300667Y114917D01*
Y114750D01*
X300500Y114667D01*
G01X304600Y113333D02*
X306100Y110000D01*
X307600Y113333D01*
G01X310450Y112250D02*
X313117D01*
X312867Y112833D01*
X312450Y113167D01*
X311867Y113333D01*
X311283Y113250D01*
X310783Y113000D01*
X310450Y112417D01*
X310283Y111917D01*
Y111417D01*
X310450Y110917D01*
X310867Y110417D01*
X311367Y110083D01*
X311950Y110000D01*
X312533Y110167D01*
X313117Y110667D01*
G01X321400Y108333D02*
Y113333D01*
G01Y112583D02*
X321817Y113000D01*
X322233Y113250D01*
X322900Y113333D01*
X323483Y113250D01*
X324067Y112833D01*
X324317Y112250D01*
X324400Y111667D01*
X324317Y111083D01*
X324067Y110500D01*
X323567Y110167D01*
X322900Y110000D01*
X322317Y110083D01*
X321733Y110333D01*
X321400Y110667D01*
G01X328500Y110000D02*
X328000Y110083D01*
X327500Y110417D01*
X327167Y111000D01*
X327000Y111667D01*
X327167Y112333D01*
X327500Y112917D01*
X328000Y113250D01*
X328500Y113333D01*
X329000Y113250D01*
X329500Y112917D01*
X329833Y112333D01*
X329917Y111667D01*
X329833Y111000D01*
X329500Y110417D01*
X329000Y110083D01*
X328500Y110000D01*
G01X332850Y110583D02*
X333267Y110250D01*
X333850Y110000D01*
X334350D01*
X334850Y110167D01*
X335183Y110417D01*
X335350Y110750D01*
X335267Y111250D01*
X334933Y111500D01*
X333433Y112000D01*
X333100Y112583D01*
X333267Y113000D01*
X333600Y113250D01*
X334100Y113333D01*
X334600Y113250D01*
X335100Y113000D01*
G01X339700Y113333D02*
Y110000D01*
G01Y114667D02*
X339533Y114750D01*
Y114917D01*
X339700Y115000D01*
X339867Y114917D01*
Y114750D01*
X339700Y114667D01*
G01X345300Y115000D02*
Y110000D01*
G01X344133Y113333D02*
X346467D01*
G01X350900D02*
Y110000D01*
G01Y114667D02*
X350733Y114750D01*
Y114917D01*
X350900Y115000D01*
X351067Y114917D01*
Y114750D01*
X350900Y114667D01*
G01X356500Y110000D02*
X356000Y110083D01*
X355500Y110417D01*
X355167Y111000D01*
X355000Y111667D01*
X355167Y112333D01*
X355500Y112917D01*
X356000Y113250D01*
X356500Y113333D01*
X357000Y113250D01*
X357500Y112917D01*
X357833Y112333D01*
X357917Y111667D01*
X357833Y111000D01*
X357500Y110417D01*
X357000Y110083D01*
X356500Y110000D01*
G01X360683D02*
Y113333D01*
G01Y112500D02*
X361017Y112917D01*
X361517Y113250D01*
X362183Y113333D01*
X362767Y113250D01*
X363267Y112917D01*
X363517Y112333D01*
Y110000D01*
G01X371800D02*
Y115000D01*
G01Y112500D02*
X372217Y113000D01*
X372717Y113250D01*
X373217Y113333D01*
X373967Y113167D01*
X374467Y112833D01*
X374800Y112250D01*
Y111583D01*
X374633Y110917D01*
X374300Y110417D01*
X373717Y110083D01*
X373217Y110000D01*
X372717Y110083D01*
X372217Y110333D01*
X371800Y110750D01*
G01X377650Y112250D02*
X380317D01*
X380067Y112833D01*
X379650Y113167D01*
X379067Y113333D01*
X378483Y113250D01*
X377983Y113000D01*
X377650Y112417D01*
X377483Y111917D01*
Y111417D01*
X377650Y110917D01*
X378067Y110417D01*
X378567Y110083D01*
X379150Y110000D01*
X379733Y110167D01*
X380317Y110667D01*
G01X384500Y115000D02*
Y110000D01*
G01X383333Y113333D02*
X385667D01*
G01X388017D02*
X389017Y110000D01*
X390100Y113333D01*
X391183Y110000D01*
X392183Y113333D01*
G01X394450Y112250D02*
X397117D01*
X396867Y112833D01*
X396450Y113167D01*
X395867Y113333D01*
X395283Y113250D01*
X394783Y113000D01*
X394450Y112417D01*
X394283Y111917D01*
Y111417D01*
X394450Y110917D01*
X394867Y110417D01*
X395367Y110083D01*
X395950Y110000D01*
X396533Y110167D01*
X397117Y110667D01*
G01X400050Y112250D02*
X402717D01*
X402467Y112833D01*
X402050Y113167D01*
X401467Y113333D01*
X400883Y113250D01*
X400383Y113000D01*
X400050Y112417D01*
X399883Y111917D01*
Y111417D01*
X400050Y110917D01*
X400467Y110417D01*
X400967Y110083D01*
X401550Y110000D01*
X402133Y110167D01*
X402717Y110667D01*
G01X405483Y110000D02*
Y113333D01*
G01Y112500D02*
X405817Y112917D01*
X406317Y113250D01*
X406983Y113333D01*
X407567Y113250D01*
X408067Y112917D01*
X408317Y112333D01*
Y110000D01*
G01X419600D02*
Y113333D01*
G01Y112750D02*
X419267Y113083D01*
X418767Y113250D01*
X418183Y113333D01*
X417600Y113167D01*
X417100Y112833D01*
X416767Y112333D01*
X416600Y111667D01*
X416767Y111000D01*
X417100Y110500D01*
X417600Y110167D01*
X418183Y110000D01*
X418767Y110083D01*
X419267Y110333D01*
X419600Y110667D01*
G01X422283Y110000D02*
Y113333D01*
G01Y112500D02*
X422617Y112917D01*
X423117Y113250D01*
X423783Y113333D01*
X424367Y113250D01*
X424867Y112917D01*
X425117Y112333D01*
Y110000D01*
G01X427550Y108500D02*
X428050Y108333D01*
X428717Y108500D01*
X429133Y108833D01*
X429467Y109250D01*
X429967Y110583D01*
X431050Y113333D01*
G01X428383D02*
X429967Y110583D01*
G01X439000Y108333D02*
Y113333D01*
G01Y112583D02*
X439417Y113000D01*
X439833Y113250D01*
X440500Y113333D01*
X441083Y113250D01*
X441667Y112833D01*
X441917Y112250D01*
X442000Y111667D01*
X441917Y111083D01*
X441667Y110500D01*
X441167Y110167D01*
X440500Y110000D01*
X439917Y110083D01*
X439333Y110333D01*
X439000Y110667D01*
G01X447600Y110000D02*
Y113333D01*
G01Y112750D02*
X447267Y113083D01*
X446767Y113250D01*
X446183Y113333D01*
X445600Y113167D01*
X445100Y112833D01*
X444767Y112333D01*
X444600Y111667D01*
X444767Y111000D01*
X445100Y110500D01*
X445600Y110167D01*
X446183Y110000D01*
X446767Y110083D01*
X447267Y110333D01*
X447600Y110667D01*
G01X453200Y115000D02*
Y110000D01*
G01Y110750D02*
X452867Y110333D01*
X452367Y110083D01*
X451783Y110000D01*
X451117Y110167D01*
X450617Y110583D01*
X450283Y111083D01*
X450200Y111667D01*
X450283Y112250D01*
X450617Y112750D01*
X451117Y113167D01*
X451783Y113333D01*
X452367Y113250D01*
X452783Y113083D01*
X453200Y112750D01*
G01X462900Y115000D02*
Y110000D01*
G01X461733Y113333D02*
X464067D01*
G01X468500Y110000D02*
X468000Y110083D01*
X467500Y110417D01*
X467167Y111000D01*
X467000Y111667D01*
X467167Y112333D01*
X467500Y112917D01*
X468000Y113250D01*
X468500Y113333D01*
X469000Y113250D01*
X469500Y112917D01*
X469833Y112333D01*
X469917Y111667D01*
X469833Y111000D01*
X469500Y110417D01*
X469000Y110083D01*
X468500Y110000D01*
G01X478200Y108333D02*
Y113333D01*
G01Y112583D02*
X478617Y113000D01*
X479033Y113250D01*
X479700Y113333D01*
X480283Y113250D01*
X480867Y112833D01*
X481117Y112250D01*
X481200Y111667D01*
X481117Y111083D01*
X480867Y110500D01*
X480367Y110167D01*
X479700Y110000D01*
X479117Y110083D01*
X478533Y110333D01*
X478200Y110667D01*
G01X486800Y110000D02*
Y113333D01*
G01Y112750D02*
X486467Y113083D01*
X485967Y113250D01*
X485383Y113333D01*
X484800Y113167D01*
X484300Y112833D01*
X483967Y112333D01*
X483800Y111667D01*
X483967Y111000D01*
X484300Y110500D01*
X484800Y110167D01*
X485383Y110000D01*
X485967Y110083D01*
X486467Y110333D01*
X486800Y110667D01*
G01X492400Y115000D02*
Y110000D01*
G01Y110750D02*
X492067Y110333D01*
X491567Y110083D01*
X490983Y110000D01*
X490317Y110167D01*
X489817Y110583D01*
X489483Y111083D01*
X489400Y111667D01*
X489483Y112250D01*
X489817Y112750D01*
X490317Y113167D01*
X490983Y113333D01*
X491567Y113250D01*
X491983Y113083D01*
X492400Y112750D01*
G01X270750Y125000D02*
Y130000D01*
G01X274250D02*
Y125000D01*
G01Y127500D02*
X270750D01*
G01X276267Y125000D02*
Y130000D01*
X277933D01*
X278600Y129750D01*
X279100Y129417D01*
X279517Y128917D01*
X279850Y128333D01*
X279933Y127500D01*
X279850Y126667D01*
X279517Y126083D01*
X279100Y125583D01*
X278600Y125250D01*
X277933Y125000D01*
X276267D01*
G01X282700Y130000D02*
X284700D01*
G01X283700D02*
Y125000D01*
G01X282700D02*
X284700D01*
G01X293233D02*
Y130000D01*
X295233D01*
X295900Y129750D01*
X296400Y129167D01*
X296567Y128500D01*
X296400Y127833D01*
X295983Y127333D01*
X295233Y127083D01*
X293233D01*
G01X302333Y129583D02*
X301833Y129833D01*
X301250Y130000D01*
X300583D01*
X299833Y129750D01*
X299250Y129333D01*
X298833Y128833D01*
X298500Y128000D01*
X298417Y127250D01*
X298583Y126500D01*
X298833Y126000D01*
X299333Y125500D01*
X299917Y125167D01*
X300500Y125000D01*
X301083D01*
X301667Y125167D01*
X302167Y125417D01*
X302583Y125750D01*
G01X306767Y127667D02*
X307100Y127917D01*
X307350Y128333D01*
X307517Y128917D01*
X307350Y129417D01*
X307017Y129750D01*
X306433Y130000D01*
X304183D01*
Y125000D01*
X306933D01*
X307517Y125333D01*
X307850Y125833D01*
X308017Y126417D01*
X307850Y127000D01*
X307350Y127500D01*
X306767Y127667D01*
X304183D01*
G01X311700Y124833D02*
X311533Y124917D01*
Y125083D01*
X311700Y125167D01*
X311867Y125083D01*
Y124917D01*
X311700Y124833D01*
G01X270750Y150667D02*
X271417Y150250D01*
X272167Y150000D01*
X272833D01*
X273500Y150250D01*
X274000Y150667D01*
X274250Y151250D01*
X274083Y151833D01*
X273667Y152333D01*
X272917Y152667D01*
X271917Y152833D01*
X271333Y153167D01*
X271083Y153750D01*
X271250Y154333D01*
X271667Y154750D01*
X272250Y155000D01*
X272833D01*
X273417Y154833D01*
X273917Y154417D01*
G01X276850Y152250D02*
X279517D01*
X279267Y152833D01*
X278850Y153167D01*
X278267Y153333D01*
X277683Y153250D01*
X277183Y153000D01*
X276850Y152417D01*
X276683Y151917D01*
Y151417D01*
X276850Y150917D01*
X277267Y150417D01*
X277767Y150083D01*
X278350Y150000D01*
X278933Y150167D01*
X279517Y150667D01*
G01X282533Y150000D02*
Y153333D01*
G01Y152667D02*
X282950Y153000D01*
X283367Y153250D01*
X283950Y153333D01*
X284367Y153250D01*
X284867Y153000D01*
G01X287800Y153333D02*
X289300Y150000D01*
X290800Y153333D01*
G01X293650Y152250D02*
X296317D01*
X296067Y152833D01*
X295650Y153167D01*
X295067Y153333D01*
X294483Y153250D01*
X293983Y153000D01*
X293650Y152417D01*
X293483Y151917D01*
Y151417D01*
X293650Y150917D01*
X294067Y150417D01*
X294567Y150083D01*
X295150Y150000D01*
X295733Y150167D01*
X296317Y150667D01*
G01X299333Y150000D02*
Y153333D01*
G01Y152667D02*
X299750Y153000D01*
X300167Y153250D01*
X300750Y153333D01*
X301167Y153250D01*
X301667Y153000D01*
G01X310033Y150000D02*
Y155000D01*
X312033D01*
X312700Y154750D01*
X313200Y154167D01*
X313367Y153500D01*
X313200Y152833D01*
X312783Y152333D01*
X312033Y152083D01*
X310033D01*
G01X319133Y154583D02*
X318633Y154833D01*
X318050Y155000D01*
X317383D01*
X316633Y154750D01*
X316050Y154333D01*
X315633Y153833D01*
X315300Y153000D01*
X315217Y152250D01*
X315383Y151500D01*
X315633Y151000D01*
X316133Y150500D01*
X316717Y150167D01*
X317300Y150000D01*
X317883D01*
X318467Y150167D01*
X318967Y150417D01*
X319383Y150750D01*
G01X323567Y152667D02*
X323900Y152917D01*
X324150Y153333D01*
X324317Y153917D01*
X324150Y154417D01*
X323817Y154750D01*
X323233Y155000D01*
X320983D01*
Y150000D01*
X323733D01*
X324317Y150333D01*
X324650Y150833D01*
X324817Y151417D01*
X324650Y152000D01*
X324150Y152500D01*
X323567Y152667D01*
X320983D01*
G01X328500Y149833D02*
X328333Y149917D01*
Y150083D01*
X328500Y150167D01*
X328667Y150083D01*
Y149917D01*
X328500Y149833D01*
G01Y152083D02*
X328333Y152167D01*
Y152333D01*
X328500Y152417D01*
X328667Y152333D01*
Y152167D01*
X328500Y152083D01*
G01X332517Y150000D02*
Y155000D01*
X335683D01*
G01X334517Y152583D02*
X332517D01*
G01X339700Y150000D02*
X339200Y150083D01*
X338700Y150417D01*
X338367Y151000D01*
X338200Y151667D01*
X338367Y152333D01*
X338700Y152917D01*
X339200Y153250D01*
X339700Y153333D01*
X340200Y153250D01*
X340700Y152917D01*
X341033Y152333D01*
X341117Y151667D01*
X341033Y151000D01*
X340700Y150417D01*
X340200Y150083D01*
X339700Y150000D01*
G01X345300D02*
Y155000D01*
G01X350900Y150000D02*
Y155000D01*
G01X356500Y150000D02*
X356000Y150083D01*
X355500Y150417D01*
X355167Y151000D01*
X355000Y151667D01*
X355167Y152333D01*
X355500Y152917D01*
X356000Y153250D01*
X356500Y153333D01*
X357000Y153250D01*
X357500Y152917D01*
X357833Y152333D01*
X357917Y151667D01*
X357833Y151000D01*
X357500Y150417D01*
X357000Y150083D01*
X356500Y150000D01*
G01X360017Y153333D02*
X361017Y150000D01*
X362100Y153333D01*
X363183Y150000D01*
X364183Y153333D01*
G01X372133Y150000D02*
Y153333D01*
G01Y152667D02*
X372550Y153000D01*
X372967Y153250D01*
X373550Y153333D01*
X373967Y153250D01*
X374467Y153000D01*
G01X378900Y153333D02*
Y150000D01*
G01Y154667D02*
X378733Y154750D01*
Y154917D01*
X378900Y155000D01*
X379067Y154917D01*
Y154750D01*
X378900Y154667D01*
G01X383333Y148750D02*
X383917Y148417D01*
X384583Y148333D01*
X385167Y148417D01*
X385667Y148833D01*
X386000Y149417D01*
Y153333D01*
G01Y152667D02*
X385667Y153000D01*
X385167Y153250D01*
X384583Y153333D01*
X383917Y153167D01*
X383500Y152833D01*
X383167Y152250D01*
X383000Y151667D01*
X383083Y151167D01*
X383417Y150583D01*
X383917Y150167D01*
X384583Y150000D01*
X385083Y150083D01*
X385667Y150417D01*
X386000Y150750D01*
G01X388683Y150000D02*
Y155000D01*
G01Y152583D02*
X389100Y153000D01*
X389517Y153250D01*
X390183Y153333D01*
X390683Y153250D01*
X391267Y152917D01*
X391517Y152417D01*
Y150000D01*
G01X395700Y155000D02*
Y150000D01*
G01X394533Y153333D02*
X396867D01*
G01X405650Y150583D02*
X406067Y150250D01*
X406650Y150000D01*
X407150D01*
X407650Y150167D01*
X407983Y150417D01*
X408150Y150750D01*
X408067Y151250D01*
X407733Y151500D01*
X406233Y152000D01*
X405900Y152583D01*
X406067Y153000D01*
X406400Y153250D01*
X406900Y153333D01*
X407400Y153250D01*
X407900Y153000D01*
G01X412500Y153333D02*
Y150000D01*
G01Y154667D02*
X412333Y154750D01*
Y154917D01*
X412500Y155000D01*
X412667Y154917D01*
Y154750D01*
X412500Y154667D01*
G01X419600Y155000D02*
Y150000D01*
G01Y150750D02*
X419267Y150333D01*
X418767Y150083D01*
X418183Y150000D01*
X417517Y150167D01*
X417017Y150583D01*
X416683Y151083D01*
X416600Y151667D01*
X416683Y152250D01*
X417017Y152750D01*
X417517Y153167D01*
X418183Y153333D01*
X418767Y153250D01*
X419183Y153083D01*
X419600Y152750D01*
G01X422450Y152250D02*
X425117D01*
X424867Y152833D01*
X424450Y153167D01*
X423867Y153333D01*
X423283Y153250D01*
X422783Y153000D01*
X422450Y152417D01*
X422283Y151917D01*
Y151417D01*
X422450Y150917D01*
X422867Y150417D01*
X423367Y150083D01*
X423950Y150000D01*
X424533Y150167D01*
X425117Y150667D01*
G01X433650Y150583D02*
X434067Y150250D01*
X434650Y150000D01*
X435150D01*
X435650Y150167D01*
X435983Y150417D01*
X436150Y150750D01*
X436067Y151250D01*
X435733Y151500D01*
X434233Y152000D01*
X433900Y152583D01*
X434067Y153000D01*
X434400Y153250D01*
X434900Y153333D01*
X435400Y153250D01*
X435900Y153000D01*
G01X439000Y148333D02*
Y153333D01*
G01Y152583D02*
X439417Y153000D01*
X439833Y153250D01*
X440500Y153333D01*
X441083Y153250D01*
X441667Y152833D01*
X441917Y152250D01*
X442000Y151667D01*
X441917Y151083D01*
X441667Y150500D01*
X441167Y150167D01*
X440500Y150000D01*
X439917Y150083D01*
X439333Y150333D01*
X439000Y150667D01*
G01X444850Y152250D02*
X447517D01*
X447267Y152833D01*
X446850Y153167D01*
X446267Y153333D01*
X445683Y153250D01*
X445183Y153000D01*
X444850Y152417D01*
X444683Y151917D01*
Y151417D01*
X444850Y150917D01*
X445267Y150417D01*
X445767Y150083D01*
X446350Y150000D01*
X446933Y150167D01*
X447517Y150667D01*
G01X453033Y152917D02*
X452450Y153250D01*
X451950Y153333D01*
X451283Y153167D01*
X450783Y152833D01*
X450450Y152250D01*
X450367Y151667D01*
X450450Y151083D01*
X450783Y150583D01*
X451283Y150167D01*
X451950Y150000D01*
X452533Y150167D01*
X453033Y150500D01*
G01X462733Y149083D02*
X463067Y150167D01*
G01X468500Y153333D02*
Y150000D01*
G01Y154667D02*
X468333Y154750D01*
Y154917D01*
X468500Y155000D01*
X468667Y154917D01*
Y154750D01*
X468500Y154667D01*
G01X473600Y150000D02*
Y154250D01*
X473767Y154667D01*
X474100Y154917D01*
X474600Y155000D01*
X475100Y154833D01*
X475350Y154417D01*
G01X474350Y153000D02*
X472683D01*
G01X484050Y150583D02*
X484467Y150250D01*
X485050Y150000D01*
X485550D01*
X486050Y150167D01*
X486383Y150417D01*
X486550Y150750D01*
X486467Y151250D01*
X486133Y151500D01*
X484633Y152000D01*
X484300Y152583D01*
X484467Y153000D01*
X484800Y153250D01*
X485300Y153333D01*
X485800Y153250D01*
X486300Y153000D01*
G01X490900Y155000D02*
Y150000D01*
G01X489733Y153333D02*
X492067D01*
G01X498000Y150000D02*
Y153333D01*
G01Y152750D02*
X497667Y153083D01*
X497167Y153250D01*
X496583Y153333D01*
X496000Y153167D01*
X495500Y152833D01*
X495167Y152333D01*
X495000Y151667D01*
X495167Y151000D01*
X495500Y150500D01*
X496000Y150167D01*
X496583Y150000D01*
X497167Y150083D01*
X497667Y150333D01*
X498000Y150667D01*
G01X503433Y152917D02*
X502850Y153250D01*
X502350Y153333D01*
X501683Y153167D01*
X501183Y152833D01*
X500850Y152250D01*
X500767Y151667D01*
X500850Y151083D01*
X501183Y150583D01*
X501683Y150167D01*
X502350Y150000D01*
X502933Y150167D01*
X503433Y150500D01*
G01X506283Y150000D02*
Y155000D01*
G01X508950Y153333D02*
X506283Y151417D01*
G01X507367Y152167D02*
X509117Y150000D01*
G01X517483Y153333D02*
Y151000D01*
X517817Y150417D01*
X518317Y150083D01*
X518900Y150000D01*
X519483Y150083D01*
X519983Y150417D01*
X520317Y151000D01*
G01Y150000D02*
Y153333D01*
G01X523000Y148333D02*
Y153333D01*
G01Y152583D02*
X523417Y153000D01*
X523833Y153250D01*
X524500Y153333D01*
X525083Y153250D01*
X525667Y152833D01*
X525917Y152250D01*
X526000Y151667D01*
X525917Y151083D01*
X525667Y150500D01*
X525167Y150167D01*
X524500Y150000D01*
X523917Y150083D01*
X523333Y150333D01*
X523000Y150667D01*
G01X533617Y153333D02*
X534617Y150000D01*
X535700Y153333D01*
X536783Y150000D01*
X537783Y153333D01*
G01X541300D02*
Y150000D01*
G01Y154667D02*
X541133Y154750D01*
Y154917D01*
X541300Y155000D01*
X541467Y154917D01*
Y154750D01*
X541300Y154667D01*
G01X546900Y155000D02*
Y150000D01*
G01X545733Y153333D02*
X548067D01*
G01X551083Y150000D02*
Y155000D01*
G01Y152583D02*
X551500Y153000D01*
X551917Y153250D01*
X552583Y153333D01*
X553083Y153250D01*
X553667Y152917D01*
X553917Y152417D01*
Y150000D01*
G01X558100D02*
X557600Y150083D01*
X557100Y150417D01*
X556767Y151000D01*
X556600Y151667D01*
X556767Y152333D01*
X557100Y152917D01*
X557600Y153250D01*
X558100Y153333D01*
X558600Y153250D01*
X559100Y152917D01*
X559433Y152333D01*
X559517Y151667D01*
X559433Y151000D01*
X559100Y150417D01*
X558600Y150083D01*
X558100Y150000D01*
G01X562283Y153333D02*
Y151000D01*
X562617Y150417D01*
X563117Y150083D01*
X563700Y150000D01*
X564283Y150083D01*
X564783Y150417D01*
X565117Y151000D01*
G01Y150000D02*
Y153333D01*
G01X569300Y155000D02*
Y150000D01*
G01X568133Y153333D02*
X570467D01*
G01X272500Y170000D02*
Y165000D01*
G01X270583Y170000D02*
X274417D01*
G01X276933Y165000D02*
Y168333D01*
G01Y167667D02*
X277350Y168000D01*
X277767Y168250D01*
X278350Y168333D01*
X278767Y168250D01*
X279267Y168000D01*
G01X285200Y165000D02*
Y168333D01*
G01Y167750D02*
X284867Y168083D01*
X284367Y168250D01*
X283783Y168333D01*
X283200Y168167D01*
X282700Y167833D01*
X282367Y167333D01*
X282200Y166667D01*
X282367Y166000D01*
X282700Y165500D01*
X283200Y165167D01*
X283783Y165000D01*
X284367Y165083D01*
X284867Y165333D01*
X285200Y165667D01*
G01X290800Y170000D02*
Y165000D01*
G01Y165750D02*
X290467Y165333D01*
X289967Y165083D01*
X289383Y165000D01*
X288717Y165167D01*
X288217Y165583D01*
X287883Y166083D01*
X287800Y166667D01*
X287883Y167250D01*
X288217Y167750D01*
X288717Y168167D01*
X289383Y168333D01*
X289967Y168250D01*
X290383Y168083D01*
X290800Y167750D01*
G01X294900Y168333D02*
Y165000D01*
G01Y169667D02*
X294733Y169750D01*
Y169917D01*
X294900Y170000D01*
X295067Y169917D01*
Y169750D01*
X294900Y169667D01*
G01X300500Y170000D02*
Y165000D01*
G01X299333Y168333D02*
X301667D01*
G01X306100D02*
Y165000D01*
G01Y169667D02*
X305933Y169750D01*
Y169917D01*
X306100Y170000D01*
X306267Y169917D01*
Y169750D01*
X306100Y169667D01*
G01X311700Y165000D02*
X311200Y165083D01*
X310700Y165417D01*
X310367Y166000D01*
X310200Y166667D01*
X310367Y167333D01*
X310700Y167917D01*
X311200Y168250D01*
X311700Y168333D01*
X312200Y168250D01*
X312700Y167917D01*
X313033Y167333D01*
X313117Y166667D01*
X313033Y166000D01*
X312700Y165417D01*
X312200Y165083D01*
X311700Y165000D01*
G01X315883D02*
Y168333D01*
G01Y167500D02*
X316217Y167917D01*
X316717Y168250D01*
X317383Y168333D01*
X317967Y168250D01*
X318467Y167917D01*
X318717Y167333D01*
Y165000D01*
G01X324400D02*
Y168333D01*
G01Y167750D02*
X324067Y168083D01*
X323567Y168250D01*
X322983Y168333D01*
X322400Y168167D01*
X321900Y167833D01*
X321567Y167333D01*
X321400Y166667D01*
X321567Y166000D01*
X321900Y165500D01*
X322400Y165167D01*
X322983Y165000D01*
X323567Y165083D01*
X324067Y165333D01*
X324400Y165667D01*
G01X328500Y165000D02*
Y170000D01*
G01X338033Y165000D02*
Y170000D01*
X340033D01*
X340700Y169750D01*
X341200Y169167D01*
X341367Y168500D01*
X341200Y167833D01*
X340783Y167333D01*
X340033Y167083D01*
X338033D01*
G01X347133Y169583D02*
X346633Y169833D01*
X346050Y170000D01*
X345383D01*
X344633Y169750D01*
X344050Y169333D01*
X343633Y168833D01*
X343300Y168000D01*
X343217Y167250D01*
X343383Y166500D01*
X343633Y166000D01*
X344133Y165500D01*
X344717Y165167D01*
X345300Y165000D01*
X345883D01*
X346467Y165167D01*
X346967Y165417D01*
X347383Y165750D01*
G01X351567Y167667D02*
X351900Y167917D01*
X352150Y168333D01*
X352317Y168917D01*
X352150Y169417D01*
X351817Y169750D01*
X351233Y170000D01*
X348983D01*
Y165000D01*
X351733D01*
X352317Y165333D01*
X352650Y165833D01*
X352817Y166417D01*
X352650Y167000D01*
X352150Y167500D01*
X351567Y167667D01*
X348983D01*
G01X356500Y164833D02*
X356333Y164917D01*
Y165083D01*
X356500Y165167D01*
X356667Y165083D01*
Y164917D01*
X356500Y164833D01*
G01X264000Y135500D02*
X694500D01*
G01X264000Y160500D02*
X694500D01*
G01X262500Y237500D02*
X694500D01*
G01X270000Y374000D02*
Y369000D01*
G01X268833Y372333D02*
X271167D01*
G01X275600Y369000D02*
X275100Y369083D01*
X274600Y369417D01*
X274267Y370000D01*
X274100Y370667D01*
X274267Y371333D01*
X274600Y371917D01*
X275100Y372250D01*
X275600Y372333D01*
X276100Y372250D01*
X276600Y371917D01*
X276933Y371333D01*
X277017Y370667D01*
X276933Y370000D01*
X276600Y369417D01*
X276100Y369083D01*
X275600Y369000D01*
G01X281200D02*
Y374000D01*
G01X285550Y371250D02*
X288217D01*
X287967Y371833D01*
X287550Y372167D01*
X286967Y372333D01*
X286383Y372250D01*
X285883Y372000D01*
X285550Y371417D01*
X285383Y370917D01*
Y370417D01*
X285550Y369917D01*
X285967Y369417D01*
X286467Y369083D01*
X287050Y369000D01*
X287633Y369167D01*
X288217Y369667D01*
G01X291233Y369000D02*
Y372333D01*
G01Y371667D02*
X291650Y372000D01*
X292067Y372250D01*
X292650Y372333D01*
X293067Y372250D01*
X293567Y372000D01*
G01X299500Y369000D02*
Y372333D01*
G01Y371750D02*
X299167Y372083D01*
X298667Y372250D01*
X298083Y372333D01*
X297500Y372167D01*
X297000Y371833D01*
X296667Y371333D01*
X296500Y370667D01*
X296667Y370000D01*
X297000Y369500D01*
X297500Y369167D01*
X298083Y369000D01*
X298667Y369083D01*
X299167Y369333D01*
X299500Y369667D01*
G01X302183Y369000D02*
Y372333D01*
G01Y371500D02*
X302517Y371917D01*
X303017Y372250D01*
X303683Y372333D01*
X304267Y372250D01*
X304767Y371917D01*
X305017Y371333D01*
Y369000D01*
G01X310533Y371917D02*
X309950Y372250D01*
X309450Y372333D01*
X308783Y372167D01*
X308283Y371833D01*
X307950Y371250D01*
X307867Y370667D01*
X307950Y370083D01*
X308283Y369583D01*
X308783Y369167D01*
X309450Y369000D01*
X310033Y369167D01*
X310533Y369500D01*
G01X313550Y371250D02*
X316217D01*
X315967Y371833D01*
X315550Y372167D01*
X314967Y372333D01*
X314383Y372250D01*
X313883Y372000D01*
X313550Y371417D01*
X313383Y370917D01*
Y370417D01*
X313550Y369917D01*
X313967Y369417D01*
X314467Y369083D01*
X315050Y369000D01*
X315633Y369167D01*
X316217Y369667D01*
G01X326000Y374000D02*
Y369000D01*
G01X324833Y372333D02*
X327167D01*
G01X333100Y369000D02*
Y372333D01*
G01Y371750D02*
X332767Y372083D01*
X332267Y372250D01*
X331683Y372333D01*
X331100Y372167D01*
X330600Y371833D01*
X330267Y371333D01*
X330100Y370667D01*
X330267Y370000D01*
X330600Y369500D01*
X331100Y369167D01*
X331683Y369000D01*
X332267Y369083D01*
X332767Y369333D01*
X333100Y369667D01*
G01X335700Y369000D02*
Y374000D01*
G01Y371500D02*
X336117Y372000D01*
X336617Y372250D01*
X337117Y372333D01*
X337867Y372167D01*
X338367Y371833D01*
X338700Y371250D01*
Y370583D01*
X338533Y369917D01*
X338200Y369417D01*
X337617Y369083D01*
X337117Y369000D01*
X336617Y369083D01*
X336117Y369333D01*
X335700Y369750D01*
G01X342800Y369000D02*
Y374000D01*
G01X347150Y371250D02*
X349817D01*
X349567Y371833D01*
X349150Y372167D01*
X348567Y372333D01*
X347983Y372250D01*
X347483Y372000D01*
X347150Y371417D01*
X346983Y370917D01*
Y370417D01*
X347150Y369917D01*
X347567Y369417D01*
X348067Y369083D01*
X348650Y369000D01*
X349233Y369167D01*
X349817Y369667D01*
G01X354000Y368833D02*
X353833Y368917D01*
Y369083D01*
X354000Y369167D01*
X354167Y369083D01*
Y368917D01*
X354000Y368833D01*
G01X268667Y379750D02*
X269250Y379417D01*
X269750Y379333D01*
X270417Y379500D01*
X270917Y379917D01*
X271167Y380667D01*
Y384333D01*
G01Y385667D02*
X271000Y385750D01*
Y385917D01*
X271167Y386000D01*
X271333Y385917D01*
Y385750D01*
X271167Y385667D01*
G01X274183Y384333D02*
Y382000D01*
X274517Y381417D01*
X275017Y381083D01*
X275600Y381000D01*
X276183Y381083D01*
X276683Y381417D01*
X277017Y382000D01*
G01Y381000D02*
Y384333D01*
G01X279783Y381000D02*
Y384333D01*
G01Y383500D02*
X280117Y383917D01*
X280617Y384250D01*
X281283Y384333D01*
X281867Y384250D01*
X282367Y383917D01*
X282617Y383333D01*
Y381000D01*
G01X288133Y383917D02*
X287550Y384250D01*
X287050Y384333D01*
X286383Y384167D01*
X285883Y383833D01*
X285550Y383250D01*
X285467Y382667D01*
X285550Y382083D01*
X285883Y381583D01*
X286383Y381167D01*
X287050Y381000D01*
X287633Y381167D01*
X288133Y381500D01*
G01X292400Y386000D02*
Y381000D01*
G01X291233Y384333D02*
X293567D01*
G01X298000D02*
Y381000D01*
G01Y385667D02*
X297833Y385750D01*
Y385917D01*
X298000Y386000D01*
X298167Y385917D01*
Y385750D01*
X298000Y385667D01*
G01X303600Y381000D02*
X303100Y381083D01*
X302600Y381417D01*
X302267Y382000D01*
X302100Y382667D01*
X302267Y383333D01*
X302600Y383917D01*
X303100Y384250D01*
X303600Y384333D01*
X304100Y384250D01*
X304600Y383917D01*
X304933Y383333D01*
X305017Y382667D01*
X304933Y382000D01*
X304600Y381417D01*
X304100Y381083D01*
X303600Y381000D01*
G01X307783D02*
Y384333D01*
G01Y383500D02*
X308117Y383917D01*
X308617Y384250D01*
X309283Y384333D01*
X309867Y384250D01*
X310367Y383917D01*
X310617Y383333D01*
Y381000D01*
G01X318900D02*
Y386000D01*
G01Y383500D02*
X319317Y384000D01*
X319817Y384250D01*
X320317Y384333D01*
X321067Y384167D01*
X321567Y383833D01*
X321900Y383250D01*
Y382583D01*
X321733Y381917D01*
X321400Y381417D01*
X320817Y381083D01*
X320317Y381000D01*
X319817Y381083D01*
X319317Y381333D01*
X318900Y381750D01*
G01X324750Y383250D02*
X327417D01*
X327167Y383833D01*
X326750Y384167D01*
X326167Y384333D01*
X325583Y384250D01*
X325083Y384000D01*
X324750Y383417D01*
X324583Y382917D01*
Y382417D01*
X324750Y381917D01*
X325167Y381417D01*
X325667Y381083D01*
X326250Y381000D01*
X326833Y381167D01*
X327417Y381667D01*
G01X331600Y381000D02*
Y386000D01*
G01X337200Y381000D02*
X336700Y381083D01*
X336200Y381417D01*
X335867Y382000D01*
X335700Y382667D01*
X335867Y383333D01*
X336200Y383917D01*
X336700Y384250D01*
X337200Y384333D01*
X337700Y384250D01*
X338200Y383917D01*
X338533Y383333D01*
X338617Y382667D01*
X338533Y382000D01*
X338200Y381417D01*
X337700Y381083D01*
X337200Y381000D01*
G01X340717Y384333D02*
X341717Y381000D01*
X342800Y384333D01*
X343883Y381000D01*
X344883Y384333D01*
G01X354000Y386000D02*
Y381000D01*
G01X352833Y384333D02*
X355167D01*
G01X358183Y381000D02*
Y386000D01*
G01Y383583D02*
X358600Y384000D01*
X359017Y384250D01*
X359683Y384333D01*
X360183Y384250D01*
X360767Y383917D01*
X361017Y383417D01*
Y381000D01*
G01X363950Y383250D02*
X366617D01*
X366367Y383833D01*
X365950Y384167D01*
X365367Y384333D01*
X364783Y384250D01*
X364283Y384000D01*
X363950Y383417D01*
X363783Y382917D01*
Y382417D01*
X363950Y381917D01*
X364367Y381417D01*
X364867Y381083D01*
X365450Y381000D01*
X366033Y381167D01*
X366617Y381667D01*
G01X373900Y381000D02*
Y384333D01*
G01Y383417D02*
X374150Y383833D01*
X374567Y384167D01*
X375150Y384333D01*
X375733Y384167D01*
X376150Y383833D01*
X376400Y383417D01*
Y381000D01*
G01Y383417D02*
X376650Y383833D01*
X377067Y384167D01*
X377650Y384333D01*
X378233Y384167D01*
X378650Y383833D01*
X378900Y383333D01*
Y381000D01*
G01X382000Y384333D02*
Y381000D01*
G01Y385667D02*
X381833Y385750D01*
Y385917D01*
X382000Y386000D01*
X382167Y385917D01*
Y385750D01*
X382000Y385667D01*
G01X386183Y381000D02*
Y384333D01*
G01Y383500D02*
X386517Y383917D01*
X387017Y384250D01*
X387683Y384333D01*
X388267Y384250D01*
X388767Y383917D01*
X389017Y383333D01*
Y381000D01*
G01X400133Y383917D02*
X399550Y384250D01*
X399050Y384333D01*
X398383Y384167D01*
X397883Y383833D01*
X397550Y383250D01*
X397467Y382667D01*
X397550Y382083D01*
X397883Y381583D01*
X398383Y381167D01*
X399050Y381000D01*
X399633Y381167D01*
X400133Y381500D01*
G01X404400Y381000D02*
X403900Y381083D01*
X403400Y381417D01*
X403067Y382000D01*
X402900Y382667D01*
X403067Y383333D01*
X403400Y383917D01*
X403900Y384250D01*
X404400Y384333D01*
X404900Y384250D01*
X405400Y383917D01*
X405733Y383333D01*
X405817Y382667D01*
X405733Y382000D01*
X405400Y381417D01*
X404900Y381083D01*
X404400Y381000D01*
G01X408583D02*
Y384333D01*
G01Y383500D02*
X408917Y383917D01*
X409417Y384250D01*
X410083Y384333D01*
X410667Y384250D01*
X411167Y383917D01*
X411417Y383333D01*
Y381000D01*
G01X417100Y386000D02*
Y381000D01*
G01Y381750D02*
X416767Y381333D01*
X416267Y381083D01*
X415683Y381000D01*
X415017Y381167D01*
X414517Y381583D01*
X414183Y382083D01*
X414100Y382667D01*
X414183Y383250D01*
X414517Y383750D01*
X415017Y384167D01*
X415683Y384333D01*
X416267Y384250D01*
X416683Y384083D01*
X417100Y383750D01*
G01X419783Y384333D02*
Y382000D01*
X420117Y381417D01*
X420617Y381083D01*
X421200Y381000D01*
X421783Y381083D01*
X422283Y381417D01*
X422617Y382000D01*
G01Y381000D02*
Y384333D01*
G01X428133Y383917D02*
X427550Y384250D01*
X427050Y384333D01*
X426383Y384167D01*
X425883Y383833D01*
X425550Y383250D01*
X425467Y382667D01*
X425550Y382083D01*
X425883Y381583D01*
X426383Y381167D01*
X427050Y381000D01*
X427633Y381167D01*
X428133Y381500D01*
G01X432400Y386000D02*
Y381000D01*
G01X431233Y384333D02*
X433567D01*
G01X438000Y381000D02*
X437500Y381083D01*
X437000Y381417D01*
X436667Y382000D01*
X436500Y382667D01*
X436667Y383333D01*
X437000Y383917D01*
X437500Y384250D01*
X438000Y384333D01*
X438500Y384250D01*
X439000Y383917D01*
X439333Y383333D01*
X439417Y382667D01*
X439333Y382000D01*
X439000Y381417D01*
X438500Y381083D01*
X438000Y381000D01*
G01X442433D02*
Y384333D01*
G01Y383667D02*
X442850Y384000D01*
X443267Y384250D01*
X443850Y384333D01*
X444267Y384250D01*
X444767Y384000D01*
G01X452717Y384333D02*
X453717Y381000D01*
X454800Y384333D01*
X455883Y381000D01*
X456883Y384333D01*
G01X460400D02*
Y381000D01*
G01Y385667D02*
X460233Y385750D01*
Y385917D01*
X460400Y386000D01*
X460567Y385917D01*
Y385750D01*
X460400Y385667D01*
G01X467500Y386000D02*
Y381000D01*
G01Y381750D02*
X467167Y381333D01*
X466667Y381083D01*
X466083Y381000D01*
X465417Y381167D01*
X464917Y381583D01*
X464583Y382083D01*
X464500Y382667D01*
X464583Y383250D01*
X464917Y383750D01*
X465417Y384167D01*
X466083Y384333D01*
X466667Y384250D01*
X467083Y384083D01*
X467500Y383750D01*
G01X471600Y386000D02*
Y381000D01*
G01X470433Y384333D02*
X472767D01*
G01X475783Y381000D02*
Y386000D01*
G01Y383583D02*
X476200Y384000D01*
X476617Y384250D01*
X477283Y384333D01*
X477783Y384250D01*
X478367Y383917D01*
X478617Y383417D01*
Y381000D01*
G01X487150Y381583D02*
X487567Y381250D01*
X488150Y381000D01*
X488650D01*
X489150Y381167D01*
X489483Y381417D01*
X489650Y381750D01*
X489567Y382250D01*
X489233Y382500D01*
X487733Y383000D01*
X487400Y383583D01*
X487567Y384000D01*
X487900Y384250D01*
X488400Y384333D01*
X488900Y384250D01*
X489400Y384000D01*
G01X492500Y379333D02*
Y384333D01*
G01Y383583D02*
X492917Y384000D01*
X493333Y384250D01*
X494000Y384333D01*
X494583Y384250D01*
X495167Y383833D01*
X495417Y383250D01*
X495500Y382667D01*
X495417Y382083D01*
X495167Y381500D01*
X494667Y381167D01*
X494000Y381000D01*
X493417Y381083D01*
X492833Y381333D01*
X492500Y381667D01*
G01X498350Y383250D02*
X501017D01*
X500767Y383833D01*
X500350Y384167D01*
X499767Y384333D01*
X499183Y384250D01*
X498683Y384000D01*
X498350Y383417D01*
X498183Y382917D01*
Y382417D01*
X498350Y381917D01*
X498767Y381417D01*
X499267Y381083D01*
X499850Y381000D01*
X500433Y381167D01*
X501017Y381667D01*
G01X506533Y383917D02*
X505950Y384250D01*
X505450Y384333D01*
X504783Y384167D01*
X504283Y383833D01*
X503950Y383250D01*
X503867Y382667D01*
X503950Y382083D01*
X504283Y381583D01*
X504783Y381167D01*
X505450Y381000D01*
X506033Y381167D01*
X506533Y381500D01*
G01X510800Y384333D02*
Y381000D01*
G01Y385667D02*
X510633Y385750D01*
Y385917D01*
X510800Y386000D01*
X510967Y385917D01*
Y385750D01*
X510800Y385667D01*
G01X515900Y381000D02*
Y385250D01*
X516067Y385667D01*
X516400Y385917D01*
X516900Y386000D01*
X517400Y385833D01*
X517650Y385417D01*
G01X516650Y384000D02*
X514983D01*
G01X522000Y384333D02*
Y381000D01*
G01Y385667D02*
X521833Y385750D01*
Y385917D01*
X522000Y386000D01*
X522167Y385917D01*
Y385750D01*
X522000Y385667D01*
G01X526350Y383250D02*
X529017D01*
X528767Y383833D01*
X528350Y384167D01*
X527767Y384333D01*
X527183Y384250D01*
X526683Y384000D01*
X526350Y383417D01*
X526183Y382917D01*
Y382417D01*
X526350Y381917D01*
X526767Y381417D01*
X527267Y381083D01*
X527850Y381000D01*
X528433Y381167D01*
X529017Y381667D01*
G01X534700Y386000D02*
Y381000D01*
G01Y381750D02*
X534367Y381333D01*
X533867Y381083D01*
X533283Y381000D01*
X532617Y381167D01*
X532117Y381583D01*
X531783Y382083D01*
X531700Y382667D01*
X531783Y383250D01*
X532117Y383750D01*
X532617Y384167D01*
X533283Y384333D01*
X533867Y384250D01*
X534283Y384083D01*
X534700Y383750D01*
G01X544400Y381000D02*
X543900Y381083D01*
X543400Y381417D01*
X543067Y382000D01*
X542900Y382667D01*
X543067Y383333D01*
X543400Y383917D01*
X543900Y384250D01*
X544400Y384333D01*
X544900Y384250D01*
X545400Y383917D01*
X545733Y383333D01*
X545817Y382667D01*
X545733Y382000D01*
X545400Y381417D01*
X544900Y381083D01*
X544400Y381000D01*
G01X548583D02*
Y384333D01*
G01Y383500D02*
X548917Y383917D01*
X549417Y384250D01*
X550083Y384333D01*
X550667Y384250D01*
X551167Y383917D01*
X551417Y383333D01*
Y381000D01*
G01X561200Y386000D02*
Y381000D01*
G01X560033Y384333D02*
X562367D01*
G01X565383Y381000D02*
Y386000D01*
G01Y383583D02*
X565800Y384000D01*
X566217Y384250D01*
X566883Y384333D01*
X567383Y384250D01*
X567967Y383917D01*
X568217Y383417D01*
Y381000D01*
G01X571150Y383250D02*
X573817D01*
X573567Y383833D01*
X573150Y384167D01*
X572567Y384333D01*
X571983Y384250D01*
X571483Y384000D01*
X571150Y383417D01*
X570983Y382917D01*
Y382417D01*
X571150Y381917D01*
X571567Y381417D01*
X572067Y381083D01*
X572650Y381000D01*
X573233Y381167D01*
X573817Y381667D01*
G01X262500Y290500D02*
X694500D01*
G01X268250Y391500D02*
Y396500D01*
G01X271750D02*
Y391500D01*
G01Y394000D02*
X268250D01*
G01X275600Y391500D02*
X275100Y391583D01*
X274600Y391917D01*
X274267Y392500D01*
X274100Y393167D01*
X274267Y393833D01*
X274600Y394417D01*
X275100Y394750D01*
X275600Y394833D01*
X276100Y394750D01*
X276600Y394417D01*
X276933Y393833D01*
X277017Y393167D01*
X276933Y392500D01*
X276600Y391917D01*
X276100Y391583D01*
X275600Y391500D01*
G01X279117Y394833D02*
X280117Y391500D01*
X281200Y394833D01*
X282283Y391500D01*
X283283Y394833D01*
G01X285550Y393750D02*
X288217D01*
X287967Y394333D01*
X287550Y394667D01*
X286967Y394833D01*
X286383Y394750D01*
X285883Y394500D01*
X285550Y393917D01*
X285383Y393417D01*
Y392917D01*
X285550Y392417D01*
X285967Y391917D01*
X286467Y391583D01*
X287050Y391500D01*
X287633Y391667D01*
X288217Y392167D01*
G01X290900Y394833D02*
X292400Y391500D01*
X293900Y394833D01*
G01X296750Y393750D02*
X299417D01*
X299167Y394333D01*
X298750Y394667D01*
X298167Y394833D01*
X297583Y394750D01*
X297083Y394500D01*
X296750Y393917D01*
X296583Y393417D01*
Y392917D01*
X296750Y392417D01*
X297167Y391917D01*
X297667Y391583D01*
X298250Y391500D01*
X298833Y391667D01*
X299417Y392167D01*
G01X302433Y391500D02*
Y394833D01*
G01Y394167D02*
X302850Y394500D01*
X303267Y394750D01*
X303850Y394833D01*
X304267Y394750D01*
X304767Y394500D01*
G01X309033Y390583D02*
X309367Y391667D01*
G01X314800Y396500D02*
Y391500D01*
G01X313633Y394833D02*
X315967D01*
G01X318983Y391500D02*
Y396500D01*
G01Y394083D02*
X319400Y394500D01*
X319817Y394750D01*
X320483Y394833D01*
X320983Y394750D01*
X321567Y394417D01*
X321817Y393917D01*
Y391500D01*
G01X324750Y393750D02*
X327417D01*
X327167Y394333D01*
X326750Y394667D01*
X326167Y394833D01*
X325583Y394750D01*
X325083Y394500D01*
X324750Y393917D01*
X324583Y393417D01*
Y392917D01*
X324750Y392417D01*
X325167Y391917D01*
X325667Y391583D01*
X326250Y391500D01*
X326833Y391667D01*
X327417Y392167D01*
G01X337200Y396500D02*
Y391500D01*
G01X336033Y394833D02*
X338367D01*
G01X344300Y391500D02*
Y394833D01*
G01Y394250D02*
X343967Y394583D01*
X343467Y394750D01*
X342883Y394833D01*
X342300Y394667D01*
X341800Y394333D01*
X341467Y393833D01*
X341300Y393167D01*
X341467Y392500D01*
X341800Y392000D01*
X342300Y391667D01*
X342883Y391500D01*
X343467Y391583D01*
X343967Y391833D01*
X344300Y392167D01*
G01X346983Y391500D02*
Y394833D01*
G01Y394000D02*
X347317Y394417D01*
X347817Y394750D01*
X348483Y394833D01*
X349067Y394750D01*
X349567Y394417D01*
X349817Y393833D01*
Y391500D01*
G01X352833Y390250D02*
X353417Y389917D01*
X354083Y389833D01*
X354667Y389917D01*
X355167Y390333D01*
X355500Y390917D01*
Y394833D01*
G01Y394167D02*
X355167Y394500D01*
X354667Y394750D01*
X354083Y394833D01*
X353417Y394667D01*
X353000Y394333D01*
X352667Y393750D01*
X352500Y393167D01*
X352583Y392667D01*
X352917Y392083D01*
X353417Y391667D01*
X354083Y391500D01*
X354583Y391583D01*
X355167Y391917D01*
X355500Y392250D01*
G01X358350Y393750D02*
X361017D01*
X360767Y394333D01*
X360350Y394667D01*
X359767Y394833D01*
X359183Y394750D01*
X358683Y394500D01*
X358350Y393917D01*
X358183Y393417D01*
Y392917D01*
X358350Y392417D01*
X358767Y391917D01*
X359267Y391583D01*
X359850Y391500D01*
X360433Y391667D01*
X361017Y392167D01*
G01X363783Y391500D02*
Y394833D01*
G01Y394000D02*
X364117Y394417D01*
X364617Y394750D01*
X365283Y394833D01*
X365867Y394750D01*
X366367Y394417D01*
X366617Y393833D01*
Y391500D01*
G01X372133Y394417D02*
X371550Y394750D01*
X371050Y394833D01*
X370383Y394667D01*
X369883Y394333D01*
X369550Y393750D01*
X369467Y393167D01*
X369550Y392583D01*
X369883Y392083D01*
X370383Y391667D01*
X371050Y391500D01*
X371633Y391667D01*
X372133Y392000D01*
G01X374650Y390000D02*
X375150Y389833D01*
X375817Y390000D01*
X376233Y390333D01*
X376567Y390750D01*
X377067Y392083D01*
X378150Y394833D01*
G01X375483D02*
X377067Y392083D01*
G01X386350D02*
X386767Y391750D01*
X387350Y391500D01*
X387850D01*
X388350Y391667D01*
X388683Y391917D01*
X388850Y392250D01*
X388767Y392750D01*
X388433Y393000D01*
X386933Y393500D01*
X386600Y394083D01*
X386767Y394500D01*
X387100Y394750D01*
X387600Y394833D01*
X388100Y394750D01*
X388600Y394500D01*
G01X391783Y391500D02*
Y396500D01*
G01Y394083D02*
X392200Y394500D01*
X392617Y394750D01*
X393283Y394833D01*
X393783Y394750D01*
X394367Y394417D01*
X394617Y393917D01*
Y391500D01*
G01X398800D02*
X398300Y391583D01*
X397800Y391917D01*
X397467Y392500D01*
X397300Y393167D01*
X397467Y393833D01*
X397800Y394417D01*
X398300Y394750D01*
X398800Y394833D01*
X399300Y394750D01*
X399800Y394417D01*
X400133Y393833D01*
X400217Y393167D01*
X400133Y392500D01*
X399800Y391917D01*
X399300Y391583D01*
X398800Y391500D01*
G01X402983Y394833D02*
Y392500D01*
X403317Y391917D01*
X403817Y391583D01*
X404400Y391500D01*
X404983Y391583D01*
X405483Y391917D01*
X405817Y392500D01*
G01Y391500D02*
Y394833D01*
G01X410000Y391500D02*
Y396500D01*
G01X417100D02*
Y391500D01*
G01Y392250D02*
X416767Y391833D01*
X416267Y391583D01*
X415683Y391500D01*
X415017Y391667D01*
X414517Y392083D01*
X414183Y392583D01*
X414100Y393167D01*
X414183Y393750D01*
X414517Y394250D01*
X415017Y394667D01*
X415683Y394833D01*
X416267Y394750D01*
X416683Y394583D01*
X417100Y394250D01*
G01X425383Y391500D02*
Y394833D01*
G01Y394000D02*
X425717Y394417D01*
X426217Y394750D01*
X426883Y394833D01*
X427467Y394750D01*
X427967Y394417D01*
X428217Y393833D01*
Y391500D01*
G01X432400D02*
X431900Y391583D01*
X431400Y391917D01*
X431067Y392500D01*
X430900Y393167D01*
X431067Y393833D01*
X431400Y394417D01*
X431900Y394750D01*
X432400Y394833D01*
X432900Y394750D01*
X433400Y394417D01*
X433733Y393833D01*
X433817Y393167D01*
X433733Y392500D01*
X433400Y391917D01*
X432900Y391583D01*
X432400Y391500D01*
G01X438000Y396500D02*
Y391500D01*
G01X436833Y394833D02*
X439167D01*
G01X448033Y391500D02*
Y394833D01*
G01Y394167D02*
X448450Y394500D01*
X448867Y394750D01*
X449450Y394833D01*
X449867Y394750D01*
X450367Y394500D01*
G01X453550Y393750D02*
X456217D01*
X455967Y394333D01*
X455550Y394667D01*
X454967Y394833D01*
X454383Y394750D01*
X453883Y394500D01*
X453550Y393917D01*
X453383Y393417D01*
Y392917D01*
X453550Y392417D01*
X453967Y391917D01*
X454467Y391583D01*
X455050Y391500D01*
X455633Y391667D01*
X456217Y392167D01*
G01X461900Y396500D02*
Y391500D01*
G01Y392250D02*
X461567Y391833D01*
X461067Y391583D01*
X460483Y391500D01*
X459817Y391667D01*
X459317Y392083D01*
X458983Y392583D01*
X458900Y393167D01*
X458983Y393750D01*
X459317Y394250D01*
X459817Y394667D01*
X460483Y394833D01*
X461067Y394750D01*
X461483Y394583D01*
X461900Y394250D01*
G01X464583Y394833D02*
Y392500D01*
X464917Y391917D01*
X465417Y391583D01*
X466000Y391500D01*
X466583Y391583D01*
X467083Y391917D01*
X467417Y392500D01*
G01Y391500D02*
Y394833D01*
G01X472933Y394417D02*
X472350Y394750D01*
X471850Y394833D01*
X471183Y394667D01*
X470683Y394333D01*
X470350Y393750D01*
X470267Y393167D01*
X470350Y392583D01*
X470683Y392083D01*
X471183Y391667D01*
X471850Y391500D01*
X472433Y391667D01*
X472933Y392000D01*
G01X475950Y393750D02*
X478617D01*
X478367Y394333D01*
X477950Y394667D01*
X477367Y394833D01*
X476783Y394750D01*
X476283Y394500D01*
X475950Y393917D01*
X475783Y393417D01*
Y392917D01*
X475950Y392417D01*
X476367Y391917D01*
X476867Y391583D01*
X477450Y391500D01*
X478033Y391667D01*
X478617Y392167D01*
G01X488400Y396500D02*
Y391500D01*
G01X487233Y394833D02*
X489567D01*
G01X492583Y391500D02*
Y396500D01*
G01Y394083D02*
X493000Y394500D01*
X493417Y394750D01*
X494083Y394833D01*
X494583Y394750D01*
X495167Y394417D01*
X495417Y393917D01*
Y391500D01*
G01X498350Y393750D02*
X501017D01*
X500767Y394333D01*
X500350Y394667D01*
X499767Y394833D01*
X499183Y394750D01*
X498683Y394500D01*
X498350Y393917D01*
X498183Y393417D01*
Y392917D01*
X498350Y392417D01*
X498767Y391917D01*
X499267Y391583D01*
X499850Y391500D01*
X500433Y391667D01*
X501017Y392167D01*
G01X510800Y391500D02*
Y396500D01*
G01X517900Y391500D02*
Y394833D01*
G01Y394250D02*
X517567Y394583D01*
X517067Y394750D01*
X516483Y394833D01*
X515900Y394667D01*
X515400Y394333D01*
X515067Y393833D01*
X514900Y393167D01*
X515067Y392500D01*
X515400Y392000D01*
X515900Y391667D01*
X516483Y391500D01*
X517067Y391583D01*
X517567Y391833D01*
X517900Y392167D01*
G01X520583Y391500D02*
Y394833D01*
G01Y394000D02*
X520917Y394417D01*
X521417Y394750D01*
X522083Y394833D01*
X522667Y394750D01*
X523167Y394417D01*
X523417Y393833D01*
Y391500D01*
G01X529100Y396500D02*
Y391500D01*
G01Y392250D02*
X528767Y391833D01*
X528267Y391583D01*
X527683Y391500D01*
X527017Y391667D01*
X526517Y392083D01*
X526183Y392583D01*
X526100Y393167D01*
X526183Y393750D01*
X526517Y394250D01*
X527017Y394667D01*
X527683Y394833D01*
X528267Y394750D01*
X528683Y394583D01*
X529100Y394250D01*
G01X531700Y391333D02*
X534700Y396500D01*
G01X540133Y394417D02*
X539550Y394750D01*
X539050Y394833D01*
X538383Y394667D01*
X537883Y394333D01*
X537550Y393750D01*
X537467Y393167D01*
X537550Y392583D01*
X537883Y392083D01*
X538383Y391667D01*
X539050Y391500D01*
X539633Y391667D01*
X540133Y392000D01*
G01X544400Y391500D02*
X543900Y391583D01*
X543400Y391917D01*
X543067Y392500D01*
X542900Y393167D01*
X543067Y393833D01*
X543400Y394417D01*
X543900Y394750D01*
X544400Y394833D01*
X544900Y394750D01*
X545400Y394417D01*
X545733Y393833D01*
X545817Y393167D01*
X545733Y392500D01*
X545400Y391917D01*
X544900Y391583D01*
X544400Y391500D01*
G01X548583D02*
Y394833D01*
G01Y394000D02*
X548917Y394417D01*
X549417Y394750D01*
X550083Y394833D01*
X550667Y394750D01*
X551167Y394417D01*
X551417Y393833D01*
Y391500D01*
G01X557100Y396500D02*
Y391500D01*
G01Y392250D02*
X556767Y391833D01*
X556267Y391583D01*
X555683Y391500D01*
X555017Y391667D01*
X554517Y392083D01*
X554183Y392583D01*
X554100Y393167D01*
X554183Y393750D01*
X554517Y394250D01*
X555017Y394667D01*
X555683Y394833D01*
X556267Y394750D01*
X556683Y394583D01*
X557100Y394250D01*
G01X559783Y394833D02*
Y392500D01*
X560117Y391917D01*
X560617Y391583D01*
X561200Y391500D01*
X561783Y391583D01*
X562283Y391917D01*
X562617Y392500D01*
G01Y391500D02*
Y394833D01*
G01X568133Y394417D02*
X567550Y394750D01*
X567050Y394833D01*
X566383Y394667D01*
X565883Y394333D01*
X565550Y393750D01*
X565467Y393167D01*
X565550Y392583D01*
X565883Y392083D01*
X566383Y391667D01*
X567050Y391500D01*
X567633Y391667D01*
X568133Y392000D01*
G01X572400Y396500D02*
Y391500D01*
G01X571233Y394833D02*
X573567D01*
G01X578000Y391500D02*
X577500Y391583D01*
X577000Y391917D01*
X576667Y392500D01*
X576500Y393167D01*
X576667Y393833D01*
X577000Y394417D01*
X577500Y394750D01*
X578000Y394833D01*
X578500Y394750D01*
X579000Y394417D01*
X579333Y393833D01*
X579417Y393167D01*
X579333Y392500D01*
X579000Y391917D01*
X578500Y391583D01*
X578000Y391500D01*
G01X582433D02*
Y394833D01*
G01Y394167D02*
X582850Y394500D01*
X583267Y394750D01*
X583850Y394833D01*
X584267Y394750D01*
X584767Y394500D01*
G01X271500Y402000D02*
Y405333D01*
G01Y404750D02*
X271167Y405083D01*
X270667Y405250D01*
X270083Y405333D01*
X269500Y405167D01*
X269000Y404833D01*
X268667Y404333D01*
X268500Y403667D01*
X268667Y403000D01*
X269000Y402500D01*
X269500Y402167D01*
X270083Y402000D01*
X270667Y402083D01*
X271167Y402333D01*
X271500Y402667D01*
G01X276933Y404917D02*
X276350Y405250D01*
X275850Y405333D01*
X275183Y405167D01*
X274683Y404833D01*
X274350Y404250D01*
X274267Y403667D01*
X274350Y403083D01*
X274683Y402583D01*
X275183Y402167D01*
X275850Y402000D01*
X276433Y402167D01*
X276933Y402500D01*
G01X282533Y404917D02*
X281950Y405250D01*
X281450Y405333D01*
X280783Y405167D01*
X280283Y404833D01*
X279950Y404250D01*
X279867Y403667D01*
X279950Y403083D01*
X280283Y402583D01*
X280783Y402167D01*
X281450Y402000D01*
X282033Y402167D01*
X282533Y402500D01*
G01X285550Y404250D02*
X288217D01*
X287967Y404833D01*
X287550Y405167D01*
X286967Y405333D01*
X286383Y405250D01*
X285883Y405000D01*
X285550Y404417D01*
X285383Y403917D01*
Y403417D01*
X285550Y402917D01*
X285967Y402417D01*
X286467Y402083D01*
X287050Y402000D01*
X287633Y402167D01*
X288217Y402667D01*
G01X290900Y400333D02*
Y405333D01*
G01Y404583D02*
X291317Y405000D01*
X291733Y405250D01*
X292400Y405333D01*
X292983Y405250D01*
X293567Y404833D01*
X293817Y404250D01*
X293900Y403667D01*
X293817Y403083D01*
X293567Y402500D01*
X293067Y402167D01*
X292400Y402000D01*
X291817Y402083D01*
X291233Y402333D01*
X290900Y402667D01*
G01X298000Y407000D02*
Y402000D01*
G01X296833Y405333D02*
X299167D01*
G01X305100Y402000D02*
Y405333D01*
G01Y404750D02*
X304767Y405083D01*
X304267Y405250D01*
X303683Y405333D01*
X303100Y405167D01*
X302600Y404833D01*
X302267Y404333D01*
X302100Y403667D01*
X302267Y403000D01*
X302600Y402500D01*
X303100Y402167D01*
X303683Y402000D01*
X304267Y402083D01*
X304767Y402333D01*
X305100Y402667D01*
G01X307700Y402000D02*
Y407000D01*
G01Y404500D02*
X308117Y405000D01*
X308617Y405250D01*
X309117Y405333D01*
X309867Y405167D01*
X310367Y404833D01*
X310700Y404250D01*
Y403583D01*
X310533Y402917D01*
X310200Y402417D01*
X309617Y402083D01*
X309117Y402000D01*
X308617Y402083D01*
X308117Y402333D01*
X307700Y402750D01*
G01X314800Y402000D02*
Y407000D01*
G01X319150Y404250D02*
X321817D01*
X321567Y404833D01*
X321150Y405167D01*
X320567Y405333D01*
X319983Y405250D01*
X319483Y405000D01*
X319150Y404417D01*
X318983Y403917D01*
Y403417D01*
X319150Y402917D01*
X319567Y402417D01*
X320067Y402083D01*
X320650Y402000D01*
X321233Y402167D01*
X321817Y402667D01*
G01X326000Y401833D02*
X325833Y401917D01*
Y402083D01*
X326000Y402167D01*
X326167Y402083D01*
Y401917D01*
X326000Y401833D01*
G01X270000Y417500D02*
Y412500D01*
G01X268083Y417500D02*
X271917D01*
G01X274183Y412500D02*
Y417500D01*
G01Y415083D02*
X274600Y415500D01*
X275017Y415750D01*
X275683Y415833D01*
X276183Y415750D01*
X276767Y415417D01*
X277017Y414917D01*
Y412500D01*
G01X279950Y414750D02*
X282617D01*
X282367Y415333D01*
X281950Y415667D01*
X281367Y415833D01*
X280783Y415750D01*
X280283Y415500D01*
X279950Y414917D01*
X279783Y414417D01*
Y413917D01*
X279950Y413417D01*
X280367Y412917D01*
X280867Y412583D01*
X281450Y412500D01*
X282033Y412667D01*
X282617Y413167D01*
G01X290900Y412500D02*
Y417500D01*
G01Y415000D02*
X291317Y415500D01*
X291817Y415750D01*
X292317Y415833D01*
X293067Y415667D01*
X293567Y415333D01*
X293900Y414750D01*
Y414083D01*
X293733Y413417D01*
X293400Y412917D01*
X292817Y412583D01*
X292317Y412500D01*
X291817Y412583D01*
X291317Y412833D01*
X290900Y413250D01*
G01X296833Y412500D02*
Y415833D01*
G01Y415167D02*
X297250Y415500D01*
X297667Y415750D01*
X298250Y415833D01*
X298667Y415750D01*
X299167Y415500D01*
G01X302350Y414750D02*
X305017D01*
X304767Y415333D01*
X304350Y415667D01*
X303767Y415833D01*
X303183Y415750D01*
X302683Y415500D01*
X302350Y414917D01*
X302183Y414417D01*
Y413917D01*
X302350Y413417D01*
X302767Y412917D01*
X303267Y412583D01*
X303850Y412500D01*
X304433Y412667D01*
X305017Y413167D01*
G01X310700Y412500D02*
Y415833D01*
G01Y415250D02*
X310367Y415583D01*
X309867Y415750D01*
X309283Y415833D01*
X308700Y415667D01*
X308200Y415333D01*
X307867Y414833D01*
X307700Y414167D01*
X307867Y413500D01*
X308200Y413000D01*
X308700Y412667D01*
X309283Y412500D01*
X309867Y412583D01*
X310367Y412833D01*
X310700Y413167D01*
G01X313383Y412500D02*
Y417500D01*
G01X316050Y415833D02*
X313383Y413917D01*
G01X314467Y414667D02*
X316217Y412500D01*
G01X320400D02*
X319900Y412583D01*
X319400Y412917D01*
X319067Y413500D01*
X318900Y414167D01*
X319067Y414833D01*
X319400Y415417D01*
X319900Y415750D01*
X320400Y415833D01*
X320900Y415750D01*
X321400Y415417D01*
X321733Y414833D01*
X321817Y414167D01*
X321733Y413500D01*
X321400Y412917D01*
X320900Y412583D01*
X320400Y412500D01*
G01X324583Y415833D02*
Y413500D01*
X324917Y412917D01*
X325417Y412583D01*
X326000Y412500D01*
X326583Y412583D01*
X327083Y412917D01*
X327417Y413500D01*
G01Y412500D02*
Y415833D01*
G01X331600Y417500D02*
Y412500D01*
G01X330433Y415833D02*
X332767D01*
G01X342800D02*
Y412500D01*
G01Y417167D02*
X342633Y417250D01*
Y417417D01*
X342800Y417500D01*
X342967Y417417D01*
Y417250D01*
X342800Y417167D01*
G01X347150Y413083D02*
X347567Y412750D01*
X348150Y412500D01*
X348650D01*
X349150Y412667D01*
X349483Y412917D01*
X349650Y413250D01*
X349567Y413750D01*
X349233Y414000D01*
X347733Y414500D01*
X347400Y415083D01*
X347567Y415500D01*
X347900Y415750D01*
X348400Y415833D01*
X348900Y415750D01*
X349400Y415500D01*
G01X358183Y412500D02*
Y415833D01*
G01Y415000D02*
X358517Y415417D01*
X359017Y415750D01*
X359683Y415833D01*
X360267Y415750D01*
X360767Y415417D01*
X361017Y414833D01*
Y412500D01*
G01X365200D02*
X364700Y412583D01*
X364200Y412917D01*
X363867Y413500D01*
X363700Y414167D01*
X363867Y414833D01*
X364200Y415417D01*
X364700Y415750D01*
X365200Y415833D01*
X365700Y415750D01*
X366200Y415417D01*
X366533Y414833D01*
X366617Y414167D01*
X366533Y413500D01*
X366200Y412917D01*
X365700Y412583D01*
X365200Y412500D01*
G01X370800Y417500D02*
Y412500D01*
G01X369633Y415833D02*
X371967D01*
G01X383500Y412500D02*
Y415833D01*
G01Y415250D02*
X383167Y415583D01*
X382667Y415750D01*
X382083Y415833D01*
X381500Y415667D01*
X381000Y415333D01*
X380667Y414833D01*
X380500Y414167D01*
X380667Y413500D01*
X381000Y413000D01*
X381500Y412667D01*
X382083Y412500D01*
X382667Y412583D01*
X383167Y412833D01*
X383500Y413167D01*
G01X387600Y412500D02*
Y417500D01*
G01X393200Y412500D02*
Y417500D01*
G01X398800Y412500D02*
X398300Y412583D01*
X397800Y412917D01*
X397467Y413500D01*
X397300Y414167D01*
X397467Y414833D01*
X397800Y415417D01*
X398300Y415750D01*
X398800Y415833D01*
X399300Y415750D01*
X399800Y415417D01*
X400133Y414833D01*
X400217Y414167D01*
X400133Y413500D01*
X399800Y412917D01*
X399300Y412583D01*
X398800Y412500D01*
G01X402317Y415833D02*
X403317Y412500D01*
X404400Y415833D01*
X405483Y412500D01*
X406483Y415833D01*
G01X408750Y414750D02*
X411417D01*
X411167Y415333D01*
X410750Y415667D01*
X410167Y415833D01*
X409583Y415750D01*
X409083Y415500D01*
X408750Y414917D01*
X408583Y414417D01*
Y413917D01*
X408750Y413417D01*
X409167Y412917D01*
X409667Y412583D01*
X410250Y412500D01*
X410833Y412667D01*
X411417Y413167D01*
G01X417100Y417500D02*
Y412500D01*
G01Y413250D02*
X416767Y412833D01*
X416267Y412583D01*
X415683Y412500D01*
X415017Y412667D01*
X414517Y413083D01*
X414183Y413583D01*
X414100Y414167D01*
X414183Y414750D01*
X414517Y415250D01*
X415017Y415667D01*
X415683Y415833D01*
X416267Y415750D01*
X416683Y415583D01*
X417100Y415250D01*
G01X421033Y411583D02*
X421367Y412667D01*
G01X436500Y412500D02*
Y417500D01*
G01Y415000D02*
X436917Y415500D01*
X437417Y415750D01*
X437917Y415833D01*
X438667Y415667D01*
X439167Y415333D01*
X439500Y414750D01*
Y414083D01*
X439333Y413417D01*
X439000Y412917D01*
X438417Y412583D01*
X437917Y412500D01*
X437417Y412583D01*
X436917Y412833D01*
X436500Y413250D01*
G01X442183Y415833D02*
Y413500D01*
X442517Y412917D01*
X443017Y412583D01*
X443600Y412500D01*
X444183Y412583D01*
X444683Y412917D01*
X445017Y413500D01*
G01Y412500D02*
Y415833D01*
G01X449200Y417500D02*
Y412500D01*
G01X448033Y415833D02*
X450367D01*
G01X461900Y412500D02*
Y415833D01*
G01Y415250D02*
X461567Y415583D01*
X461067Y415750D01*
X460483Y415833D01*
X459900Y415667D01*
X459400Y415333D01*
X459067Y414833D01*
X458900Y414167D01*
X459067Y413500D01*
X459400Y413000D01*
X459900Y412667D01*
X460483Y412500D01*
X461067Y412583D01*
X461567Y412833D01*
X461900Y413167D01*
G01X464583Y412500D02*
Y415833D01*
G01Y415000D02*
X464917Y415417D01*
X465417Y415750D01*
X466083Y415833D01*
X466667Y415750D01*
X467167Y415417D01*
X467417Y414833D01*
Y412500D01*
G01X470183D02*
Y415833D01*
G01Y415000D02*
X470517Y415417D01*
X471017Y415750D01*
X471683Y415833D01*
X472267Y415750D01*
X472767Y415417D01*
X473017Y414833D01*
Y412500D01*
G01X475783Y415833D02*
Y413500D01*
X476117Y412917D01*
X476617Y412583D01*
X477200Y412500D01*
X477783Y412583D01*
X478283Y412917D01*
X478617Y413500D01*
G01Y412500D02*
Y415833D01*
G01X484300Y412500D02*
Y415833D01*
G01Y415250D02*
X483967Y415583D01*
X483467Y415750D01*
X482883Y415833D01*
X482300Y415667D01*
X481800Y415333D01*
X481467Y414833D01*
X481300Y414167D01*
X481467Y413500D01*
X481800Y413000D01*
X482300Y412667D01*
X482883Y412500D01*
X483467Y412583D01*
X483967Y412833D01*
X484300Y413167D01*
G01X488400Y412500D02*
Y417500D01*
G01X498433Y412500D02*
Y415833D01*
G01Y415167D02*
X498850Y415500D01*
X499267Y415750D01*
X499850Y415833D01*
X500267Y415750D01*
X500767Y415500D01*
G01X505200Y415833D02*
Y412500D01*
G01Y417167D02*
X505033Y417250D01*
Y417417D01*
X505200Y417500D01*
X505367Y417417D01*
Y417250D01*
X505200Y417167D01*
G01X509383Y412500D02*
Y415833D01*
G01Y415000D02*
X509717Y415417D01*
X510217Y415750D01*
X510883Y415833D01*
X511467Y415750D01*
X511967Y415417D01*
X512217Y414833D01*
Y412500D01*
G01X515233Y411250D02*
X515817Y410917D01*
X516483Y410833D01*
X517067Y410917D01*
X517567Y411333D01*
X517900Y411917D01*
Y415833D01*
G01Y415167D02*
X517567Y415500D01*
X517067Y415750D01*
X516483Y415833D01*
X515817Y415667D01*
X515400Y415333D01*
X515067Y414750D01*
X514900Y414167D01*
X514983Y413667D01*
X515317Y413083D01*
X515817Y412667D01*
X516483Y412500D01*
X516983Y412583D01*
X517567Y412917D01*
X517900Y413250D01*
G01X527600Y417500D02*
Y412500D01*
G01X526433Y415833D02*
X528767D01*
G01X534700Y412500D02*
Y415833D01*
G01Y415250D02*
X534367Y415583D01*
X533867Y415750D01*
X533283Y415833D01*
X532700Y415667D01*
X532200Y415333D01*
X531867Y414833D01*
X531700Y414167D01*
X531867Y413500D01*
X532200Y413000D01*
X532700Y412667D01*
X533283Y412500D01*
X533867Y412583D01*
X534367Y412833D01*
X534700Y413167D01*
G01X537383Y412500D02*
Y415833D01*
G01Y415000D02*
X537717Y415417D01*
X538217Y415750D01*
X538883Y415833D01*
X539467Y415750D01*
X539967Y415417D01*
X540217Y414833D01*
Y412500D01*
G01X543233Y411250D02*
X543817Y410917D01*
X544483Y410833D01*
X545067Y410917D01*
X545567Y411333D01*
X545900Y411917D01*
Y415833D01*
G01Y415167D02*
X545567Y415500D01*
X545067Y415750D01*
X544483Y415833D01*
X543817Y415667D01*
X543400Y415333D01*
X543067Y414750D01*
X542900Y414167D01*
X542983Y413667D01*
X543317Y413083D01*
X543817Y412667D01*
X544483Y412500D01*
X544983Y412583D01*
X545567Y412917D01*
X545900Y413250D01*
G01X548750Y414750D02*
X551417D01*
X551167Y415333D01*
X550750Y415667D01*
X550167Y415833D01*
X549583Y415750D01*
X549083Y415500D01*
X548750Y414917D01*
X548583Y414417D01*
Y413917D01*
X548750Y413417D01*
X549167Y412917D01*
X549667Y412583D01*
X550250Y412500D01*
X550833Y412667D01*
X551417Y413167D01*
G01X554183Y412500D02*
Y415833D01*
G01Y415000D02*
X554517Y415417D01*
X555017Y415750D01*
X555683Y415833D01*
X556267Y415750D01*
X556767Y415417D01*
X557017Y414833D01*
Y412500D01*
G01X562533Y415417D02*
X561950Y415750D01*
X561450Y415833D01*
X560783Y415667D01*
X560283Y415333D01*
X559950Y414750D01*
X559867Y414167D01*
X559950Y413583D01*
X560283Y413083D01*
X560783Y412667D01*
X561450Y412500D01*
X562033Y412667D01*
X562533Y413000D01*
G01X565050Y411000D02*
X565550Y410833D01*
X566217Y411000D01*
X566633Y411333D01*
X566967Y411750D01*
X567467Y413083D01*
X568550Y415833D01*
G01X565883D02*
X567467Y413083D01*
G01X578000Y415833D02*
Y412500D01*
G01Y417167D02*
X577833Y417250D01*
Y417417D01*
X578000Y417500D01*
X578167Y417417D01*
Y417250D01*
X578000Y417167D01*
G01X582350Y413083D02*
X582767Y412750D01*
X583350Y412500D01*
X583850D01*
X584350Y412667D01*
X584683Y412917D01*
X584850Y413250D01*
X584767Y413750D01*
X584433Y414000D01*
X582933Y414500D01*
X582600Y415083D01*
X582767Y415500D01*
X583100Y415750D01*
X583600Y415833D01*
X584100Y415750D01*
X584600Y415500D01*
G01X273000Y437500D02*
Y432500D01*
G01Y433250D02*
X272667Y432833D01*
X272167Y432583D01*
X271583Y432500D01*
X270917Y432667D01*
X270417Y433083D01*
X270083Y433583D01*
X270000Y434167D01*
X270083Y434750D01*
X270417Y435250D01*
X270917Y435667D01*
X271583Y435833D01*
X272167Y435750D01*
X272583Y435583D01*
X273000Y435250D01*
G01X275850Y434750D02*
X278517D01*
X278267Y435333D01*
X277850Y435667D01*
X277267Y435833D01*
X276683Y435750D01*
X276183Y435500D01*
X275850Y434917D01*
X275683Y434417D01*
Y433917D01*
X275850Y433417D01*
X276267Y432917D01*
X276767Y432583D01*
X277350Y432500D01*
X277933Y432667D01*
X278517Y433167D01*
G01X281200Y430833D02*
Y435833D01*
G01Y435083D02*
X281617Y435500D01*
X282033Y435750D01*
X282700Y435833D01*
X283283Y435750D01*
X283867Y435333D01*
X284117Y434750D01*
X284200Y434167D01*
X284117Y433583D01*
X283867Y433000D01*
X283367Y432667D01*
X282700Y432500D01*
X282117Y432583D01*
X281533Y432833D01*
X281200Y433167D01*
G01X288300Y437500D02*
Y432500D01*
G01X287133Y435833D02*
X289467D01*
G01X292483Y432500D02*
Y437500D01*
G01Y435083D02*
X292900Y435500D01*
X293317Y435750D01*
X293983Y435833D01*
X294483Y435750D01*
X295067Y435417D01*
X295317Y434917D01*
Y432500D01*
G01X305100Y437500D02*
Y432500D01*
G01X303933Y435833D02*
X306267D01*
G01X310700Y432500D02*
X310200Y432583D01*
X309700Y432917D01*
X309367Y433500D01*
X309200Y434167D01*
X309367Y434833D01*
X309700Y435417D01*
X310200Y435750D01*
X310700Y435833D01*
X311200Y435750D01*
X311700Y435417D01*
X312033Y434833D01*
X312117Y434167D01*
X312033Y433500D01*
X311700Y432917D01*
X311200Y432583D01*
X310700Y432500D01*
G01X316300D02*
Y437500D01*
G01X320650Y434750D02*
X323317D01*
X323067Y435333D01*
X322650Y435667D01*
X322067Y435833D01*
X321483Y435750D01*
X320983Y435500D01*
X320650Y434917D01*
X320483Y434417D01*
Y433917D01*
X320650Y433417D01*
X321067Y432917D01*
X321567Y432583D01*
X322150Y432500D01*
X322733Y432667D01*
X323317Y433167D01*
G01X326333Y432500D02*
Y435833D01*
G01Y435167D02*
X326750Y435500D01*
X327167Y435750D01*
X327750Y435833D01*
X328167Y435750D01*
X328667Y435500D01*
G01X334600Y432500D02*
Y435833D01*
G01Y435250D02*
X334267Y435583D01*
X333767Y435750D01*
X333183Y435833D01*
X332600Y435667D01*
X332100Y435333D01*
X331767Y434833D01*
X331600Y434167D01*
X331767Y433500D01*
X332100Y433000D01*
X332600Y432667D01*
X333183Y432500D01*
X333767Y432583D01*
X334267Y432833D01*
X334600Y433167D01*
G01X337283Y432500D02*
Y435833D01*
G01Y435000D02*
X337617Y435417D01*
X338117Y435750D01*
X338783Y435833D01*
X339367Y435750D01*
X339867Y435417D01*
X340117Y434833D01*
Y432500D01*
G01X345633Y435417D02*
X345050Y435750D01*
X344550Y435833D01*
X343883Y435667D01*
X343383Y435333D01*
X343050Y434750D01*
X342967Y434167D01*
X343050Y433583D01*
X343383Y433083D01*
X343883Y432667D01*
X344550Y432500D01*
X345133Y432667D01*
X345633Y433000D01*
G01X348650Y434750D02*
X351317D01*
X351067Y435333D01*
X350650Y435667D01*
X350067Y435833D01*
X349483Y435750D01*
X348983Y435500D01*
X348650Y434917D01*
X348483Y434417D01*
Y433917D01*
X348650Y433417D01*
X349067Y432917D01*
X349567Y432583D01*
X350150Y432500D01*
X350733Y432667D01*
X351317Y433167D01*
G01X270750Y453500D02*
Y458500D01*
G01X274250D02*
Y453500D01*
G01Y456000D02*
X270750D01*
G01X278100Y453500D02*
X277600Y453583D01*
X277100Y453917D01*
X276767Y454500D01*
X276600Y455167D01*
X276767Y455833D01*
X277100Y456417D01*
X277600Y456750D01*
X278100Y456833D01*
X278600Y456750D01*
X279100Y456417D01*
X279433Y455833D01*
X279517Y455167D01*
X279433Y454500D01*
X279100Y453917D01*
X278600Y453583D01*
X278100Y453500D01*
G01X283700D02*
Y458500D01*
G01X288050Y455750D02*
X290717D01*
X290467Y456333D01*
X290050Y456667D01*
X289467Y456833D01*
X288883Y456750D01*
X288383Y456500D01*
X288050Y455917D01*
X287883Y455417D01*
Y454917D01*
X288050Y454417D01*
X288467Y453917D01*
X288967Y453583D01*
X289550Y453500D01*
X290133Y453667D01*
X290717Y454167D01*
G01X298000Y458500D02*
X299167Y453500D01*
X300500Y458500D01*
X301833Y453500D01*
X303000Y458500D01*
G01X307600Y453500D02*
Y456833D01*
G01Y456250D02*
X307267Y456583D01*
X306767Y456750D01*
X306183Y456833D01*
X305600Y456667D01*
X305100Y456333D01*
X304767Y455833D01*
X304600Y455167D01*
X304767Y454500D01*
X305100Y454000D01*
X305600Y453667D01*
X306183Y453500D01*
X306767Y453583D01*
X307267Y453833D01*
X307600Y454167D01*
G01X311700Y453500D02*
Y458500D01*
G01X317300Y453500D02*
Y458500D01*
G01X326833Y453500D02*
Y458500D01*
X328917D01*
X329583Y458250D01*
X330000Y457917D01*
X330167Y457250D01*
X330000Y456583D01*
X329500Y456167D01*
X328917Y455917D01*
X326833D01*
G01X328917D02*
X330167Y453500D01*
G01X334100D02*
X333600Y453583D01*
X333100Y453917D01*
X332767Y454500D01*
X332600Y455167D01*
X332767Y455833D01*
X333100Y456417D01*
X333600Y456750D01*
X334100Y456833D01*
X334600Y456750D01*
X335100Y456417D01*
X335433Y455833D01*
X335517Y455167D01*
X335433Y454500D01*
X335100Y453917D01*
X334600Y453583D01*
X334100Y453500D01*
G01X338283Y456833D02*
Y454500D01*
X338617Y453917D01*
X339117Y453583D01*
X339700Y453500D01*
X340283Y453583D01*
X340783Y453917D01*
X341117Y454500D01*
G01Y453500D02*
Y456833D01*
G01X344133Y452250D02*
X344717Y451917D01*
X345383Y451833D01*
X345967Y451917D01*
X346467Y452333D01*
X346800Y452917D01*
Y456833D01*
G01Y456167D02*
X346467Y456500D01*
X345967Y456750D01*
X345383Y456833D01*
X344717Y456667D01*
X344300Y456333D01*
X343967Y455750D01*
X343800Y455167D01*
X343883Y454667D01*
X344217Y454083D01*
X344717Y453667D01*
X345383Y453500D01*
X345883Y453583D01*
X346467Y453917D01*
X346800Y454250D01*
G01X349483Y453500D02*
Y458500D01*
G01Y456083D02*
X349900Y456500D01*
X350317Y456750D01*
X350983Y456833D01*
X351483Y456750D01*
X352067Y456417D01*
X352317Y455917D01*
Y453500D01*
G01X355083D02*
Y456833D01*
G01Y456000D02*
X355417Y456417D01*
X355917Y456750D01*
X356583Y456833D01*
X357167Y456750D01*
X357667Y456417D01*
X357917Y455833D01*
Y453500D01*
G01X360850Y455750D02*
X363517D01*
X363267Y456333D01*
X362850Y456667D01*
X362267Y456833D01*
X361683Y456750D01*
X361183Y456500D01*
X360850Y455917D01*
X360683Y455417D01*
Y454917D01*
X360850Y454417D01*
X361267Y453917D01*
X361767Y453583D01*
X362350Y453500D01*
X362933Y453667D01*
X363517Y454167D01*
G01X366450Y454083D02*
X366867Y453750D01*
X367450Y453500D01*
X367950D01*
X368450Y453667D01*
X368783Y453917D01*
X368950Y454250D01*
X368867Y454750D01*
X368533Y455000D01*
X367033Y455500D01*
X366700Y456083D01*
X366867Y456500D01*
X367200Y456750D01*
X367700Y456833D01*
X368200Y456750D01*
X368700Y456500D01*
G01X372050Y454083D02*
X372467Y453750D01*
X373050Y453500D01*
X373550D01*
X374050Y453667D01*
X374383Y453917D01*
X374550Y454250D01*
X374467Y454750D01*
X374133Y455000D01*
X372633Y455500D01*
X372300Y456083D01*
X372467Y456500D01*
X372800Y456750D01*
X373300Y456833D01*
X373800Y456750D01*
X374300Y456500D01*
G01X272500Y470000D02*
X271833Y470083D01*
X271250Y470417D01*
X270750Y470917D01*
X270417Y471500D01*
X270250Y472167D01*
Y472833D01*
X270417Y473500D01*
X270750Y474083D01*
X271250Y474583D01*
X271833Y474917D01*
X272500Y475000D01*
X273167Y474917D01*
X273750Y474583D01*
X274250Y474083D01*
X274583Y473500D01*
X274750Y472833D01*
Y472167D01*
X274583Y471500D01*
X274250Y470917D01*
X273750Y470417D01*
X273167Y470083D01*
X272500Y470000D01*
G01X278100Y475000D02*
Y470000D01*
G01X276933Y473333D02*
X279267D01*
G01X282283Y470000D02*
Y475000D01*
G01Y472583D02*
X282700Y473000D01*
X283117Y473250D01*
X283783Y473333D01*
X284283Y473250D01*
X284867Y472917D01*
X285117Y472417D01*
Y470000D01*
G01X288050Y472250D02*
X290717D01*
X290467Y472833D01*
X290050Y473167D01*
X289467Y473333D01*
X288883Y473250D01*
X288383Y473000D01*
X288050Y472417D01*
X287883Y471917D01*
Y471417D01*
X288050Y470917D01*
X288467Y470417D01*
X288967Y470083D01*
X289550Y470000D01*
X290133Y470167D01*
X290717Y470667D01*
G01X293733Y470000D02*
Y473333D01*
G01Y472667D02*
X294150Y473000D01*
X294567Y473250D01*
X295150Y473333D01*
X295567Y473250D01*
X296067Y473000D01*
G01X299250Y470583D02*
X299667Y470250D01*
X300250Y470000D01*
X300750D01*
X301250Y470167D01*
X301583Y470417D01*
X301750Y470750D01*
X301667Y471250D01*
X301333Y471500D01*
X299833Y472000D01*
X299500Y472583D01*
X299667Y473000D01*
X300000Y473250D01*
X300500Y473333D01*
X301000Y473250D01*
X301500Y473000D01*
G01X311283Y468333D02*
X310450Y469167D01*
X310033Y470000D01*
Y473333D01*
X310450Y474167D01*
X311283Y475000D01*
G01X317300Y470000D02*
Y475000D01*
G01X322900Y473333D02*
Y470000D01*
G01Y474667D02*
X322733Y474750D01*
Y474917D01*
X322900Y475000D01*
X323067Y474917D01*
Y474750D01*
X322900Y474667D01*
G01X327083Y470000D02*
Y475000D01*
G01X329750Y473333D02*
X327083Y471417D01*
G01X328167Y472167D02*
X329917Y470000D01*
G01X332850Y472250D02*
X335517D01*
X335267Y472833D01*
X334850Y473167D01*
X334267Y473333D01*
X333683Y473250D01*
X333183Y473000D01*
X332850Y472417D01*
X332683Y471917D01*
Y471417D01*
X332850Y470917D01*
X333267Y470417D01*
X333767Y470083D01*
X334350Y470000D01*
X334933Y470167D01*
X335517Y470667D01*
G01X344050Y472250D02*
X346717D01*
X346467Y472833D01*
X346050Y473167D01*
X345467Y473333D01*
X344883Y473250D01*
X344383Y473000D01*
X344050Y472417D01*
X343883Y471917D01*
Y471417D01*
X344050Y470917D01*
X344467Y470417D01*
X344967Y470083D01*
X345550Y470000D01*
X346133Y470167D01*
X346717Y470667D01*
G01X350900Y470000D02*
Y475000D01*
G01X356500Y470000D02*
Y475000D01*
G01X362100Y473333D02*
Y470000D01*
G01Y474667D02*
X361933Y474750D01*
Y474917D01*
X362100Y475000D01*
X362267Y474917D01*
Y474750D01*
X362100Y474667D01*
G01X366200Y468333D02*
Y473333D01*
G01Y472583D02*
X366617Y473000D01*
X367033Y473250D01*
X367700Y473333D01*
X368283Y473250D01*
X368867Y472833D01*
X369117Y472250D01*
X369200Y471667D01*
X369117Y471083D01*
X368867Y470500D01*
X368367Y470167D01*
X367700Y470000D01*
X367117Y470083D01*
X366533Y470333D01*
X366200Y470667D01*
G01X372050Y470583D02*
X372467Y470250D01*
X373050Y470000D01*
X373550D01*
X374050Y470167D01*
X374383Y470417D01*
X374550Y470750D01*
X374467Y471250D01*
X374133Y471500D01*
X372633Y472000D01*
X372300Y472583D01*
X372467Y473000D01*
X372800Y473250D01*
X373300Y473333D01*
X373800Y473250D01*
X374300Y473000D01*
G01X377650Y472250D02*
X380317D01*
X380067Y472833D01*
X379650Y473167D01*
X379067Y473333D01*
X378483Y473250D01*
X377983Y473000D01*
X377650Y472417D01*
X377483Y471917D01*
Y471417D01*
X377650Y470917D01*
X378067Y470417D01*
X378567Y470083D01*
X379150Y470000D01*
X379733Y470167D01*
X380317Y470667D01*
G01X391600Y470000D02*
Y473333D01*
G01Y472750D02*
X391267Y473083D01*
X390767Y473250D01*
X390183Y473333D01*
X389600Y473167D01*
X389100Y472833D01*
X388767Y472333D01*
X388600Y471667D01*
X388767Y471000D01*
X389100Y470500D01*
X389600Y470167D01*
X390183Y470000D01*
X390767Y470083D01*
X391267Y470333D01*
X391600Y470667D01*
G01X394283Y470000D02*
Y473333D01*
G01Y472500D02*
X394617Y472917D01*
X395117Y473250D01*
X395783Y473333D01*
X396367Y473250D01*
X396867Y472917D01*
X397117Y472333D01*
Y470000D01*
G01X402800Y475000D02*
Y470000D01*
G01Y470750D02*
X402467Y470333D01*
X401967Y470083D01*
X401383Y470000D01*
X400717Y470167D01*
X400217Y470583D01*
X399883Y471083D01*
X399800Y471667D01*
X399883Y472250D01*
X400217Y472750D01*
X400717Y473167D01*
X401383Y473333D01*
X401967Y473250D01*
X402383Y473083D01*
X402800Y472750D01*
G01X412500Y470000D02*
X412000Y470083D01*
X411500Y470417D01*
X411167Y471000D01*
X411000Y471667D01*
X411167Y472333D01*
X411500Y472917D01*
X412000Y473250D01*
X412500Y473333D01*
X413000Y473250D01*
X413500Y472917D01*
X413833Y472333D01*
X413917Y471667D01*
X413833Y471000D01*
X413500Y470417D01*
X413000Y470083D01*
X412500Y470000D01*
G01X418100Y475000D02*
Y470000D01*
G01X416933Y473333D02*
X419267D01*
G01X422283Y470000D02*
Y475000D01*
G01Y472583D02*
X422700Y473000D01*
X423117Y473250D01*
X423783Y473333D01*
X424283Y473250D01*
X424867Y472917D01*
X425117Y472417D01*
Y470000D01*
G01X428050Y472250D02*
X430717D01*
X430467Y472833D01*
X430050Y473167D01*
X429467Y473333D01*
X428883Y473250D01*
X428383Y473000D01*
X428050Y472417D01*
X427883Y471917D01*
Y471417D01*
X428050Y470917D01*
X428467Y470417D01*
X428967Y470083D01*
X429550Y470000D01*
X430133Y470167D01*
X430717Y470667D01*
G01X433733Y470000D02*
Y473333D01*
G01Y472667D02*
X434150Y473000D01*
X434567Y473250D01*
X435150Y473333D01*
X435567Y473250D01*
X436067Y473000D01*
G01X439250Y470583D02*
X439667Y470250D01*
X440250Y470000D01*
X440750D01*
X441250Y470167D01*
X441583Y470417D01*
X441750Y470750D01*
X441667Y471250D01*
X441333Y471500D01*
X439833Y472000D01*
X439500Y472583D01*
X439667Y473000D01*
X440000Y473250D01*
X440500Y473333D01*
X441000Y473250D01*
X441500Y473000D01*
G01X446517Y468333D02*
X447350Y469167D01*
X447767Y470000D01*
Y473333D01*
X447350Y474167D01*
X446517Y475000D01*
G01X262500Y397000D02*
Y679000D01*
G01X270833Y485000D02*
Y490000D01*
X272833D01*
X273500Y489750D01*
X274000Y489167D01*
X274167Y488500D01*
X274000Y487833D01*
X273583Y487333D01*
X272833Y487083D01*
X270833D01*
G01X278100Y490000D02*
Y485000D01*
G01X276183Y490000D02*
X280017D01*
G01X281950Y485000D02*
Y490000D01*
G01X285450D02*
Y485000D01*
G01Y487500D02*
X281950D01*
G01X287800Y484833D02*
X290800Y490000D01*
G01X292983Y485000D02*
Y490000D01*
X296817Y485000D01*
Y490000D01*
G01X298833Y485000D02*
Y490000D01*
X300833D01*
X301500Y489750D01*
X302000Y489167D01*
X302167Y488500D01*
X302000Y487833D01*
X301583Y487333D01*
X300833Y487083D01*
X298833D01*
G01X306100Y490000D02*
Y485000D01*
G01X304183Y490000D02*
X308017D01*
G01X309950Y485000D02*
Y490000D01*
G01X313450D02*
Y485000D01*
G01Y487500D02*
X309950D01*
G01X321233Y485000D02*
X324567Y486667D01*
X321233Y488333D01*
G01X327417Y485917D02*
X329583D01*
G01Y487417D02*
X327417D01*
G01X332267Y485750D02*
X332767Y485333D01*
X333350Y485083D01*
X334100Y485000D01*
X334850Y485167D01*
X335433Y485500D01*
X335850Y486083D01*
X335933Y486750D01*
X335767Y487417D01*
X335350Y487833D01*
X334767Y488167D01*
X334183Y488250D01*
X333600Y488167D01*
X332850Y487833D01*
X333100Y490000D01*
X335350D01*
G01X342800Y485000D02*
Y488333D01*
G01Y487417D02*
X343050Y487833D01*
X343467Y488167D01*
X344050Y488333D01*
X344633Y488167D01*
X345050Y487833D01*
X345300Y487417D01*
Y485000D01*
G01Y487417D02*
X345550Y487833D01*
X345967Y488167D01*
X346550Y488333D01*
X347133Y488167D01*
X347550Y487833D01*
X347800Y487333D01*
Y485000D01*
G01X348400D02*
Y488333D01*
G01Y487417D02*
X348650Y487833D01*
X349067Y488167D01*
X349650Y488333D01*
X350233Y488167D01*
X350650Y487833D01*
X350900Y487417D01*
Y485000D01*
G01Y487417D02*
X351150Y487833D01*
X351567Y488167D01*
X352150Y488333D01*
X352733Y488167D01*
X353150Y487833D01*
X353400Y487333D01*
Y485000D01*
G01X270583Y498500D02*
Y503500D01*
X274417Y498500D01*
Y503500D01*
G01X276433Y498500D02*
Y503500D01*
X278433D01*
X279100Y503250D01*
X279600Y502667D01*
X279767Y502000D01*
X279600Y501333D01*
X279183Y500833D01*
X278433Y500583D01*
X276433D01*
G01X283700Y503500D02*
Y498500D01*
G01X281783Y503500D02*
X285617D01*
G01X287550Y498500D02*
Y503500D01*
G01X291050D02*
Y498500D01*
G01Y501000D02*
X287550D01*
G01X298750Y499167D02*
X299417Y498750D01*
X300167Y498500D01*
X300833D01*
X301500Y498750D01*
X302000Y499167D01*
X302250Y499750D01*
X302083Y500333D01*
X301667Y500833D01*
X300917Y501167D01*
X299917Y501333D01*
X299333Y501667D01*
X299083Y502250D01*
X299250Y502833D01*
X299667Y503250D01*
X300250Y503500D01*
X300833D01*
X301417Y503333D01*
X301917Y502917D01*
G01X306100Y501833D02*
Y498500D01*
G01Y503167D02*
X305933Y503250D01*
Y503417D01*
X306100Y503500D01*
X306267Y503417D01*
Y503250D01*
X306100Y503167D01*
G01X310450Y501833D02*
X312950D01*
X310450Y498500D01*
X312950D01*
G01X316050Y500750D02*
X318717D01*
X318467Y501333D01*
X318050Y501667D01*
X317467Y501833D01*
X316883Y501750D01*
X316383Y501500D01*
X316050Y500917D01*
X315883Y500417D01*
Y499917D01*
X316050Y499417D01*
X316467Y498917D01*
X316967Y498583D01*
X317550Y498500D01*
X318133Y498667D01*
X318717Y499167D01*
G01X326667Y499500D02*
X327167Y498917D01*
X327833Y498583D01*
X328583Y498500D01*
X329250Y498583D01*
X329917Y499000D01*
X330333Y499500D01*
X330417Y500000D01*
X330250Y500583D01*
X329667Y501000D01*
X329083Y501167D01*
X328333D01*
G01X329083D02*
X329583Y501417D01*
X330000Y501833D01*
X330167Y502333D01*
X330000Y502833D01*
X329583Y503250D01*
X328833Y503500D01*
X328083Y503417D01*
X327333Y503083D01*
G01X334100Y498333D02*
X333933Y498417D01*
Y498583D01*
X334100Y498667D01*
X334267Y498583D01*
Y498417D01*
X334100Y498333D01*
G01X337867Y499250D02*
X338367Y498833D01*
X338950Y498583D01*
X339700Y498500D01*
X340450Y498667D01*
X341033Y499000D01*
X341450Y499583D01*
X341533Y500250D01*
X341367Y500917D01*
X340950Y501333D01*
X340367Y501667D01*
X339783Y501750D01*
X339200Y501667D01*
X338450Y501333D01*
X338700Y503500D01*
X340950D01*
G01X343467Y499250D02*
X343967Y498833D01*
X344550Y498583D01*
X345300Y498500D01*
X346050Y498667D01*
X346633Y499000D01*
X347050Y499583D01*
X347133Y500250D01*
X346967Y500917D01*
X346550Y501333D01*
X345967Y501667D01*
X345383Y501750D01*
X344800Y501667D01*
X344050Y501333D01*
X344300Y503500D01*
X346550D01*
G01X348400Y498500D02*
Y501833D01*
G01Y500917D02*
X348650Y501333D01*
X349067Y501667D01*
X349650Y501833D01*
X350233Y501667D01*
X350650Y501333D01*
X350900Y500917D01*
Y498500D01*
G01Y500917D02*
X351150Y501333D01*
X351567Y501667D01*
X352150Y501833D01*
X352733Y501667D01*
X353150Y501333D01*
X353400Y500833D01*
Y498500D01*
G01X354000D02*
Y501833D01*
G01Y500917D02*
X354250Y501333D01*
X354667Y501667D01*
X355250Y501833D01*
X355833Y501667D01*
X356250Y501333D01*
X356500Y500917D01*
Y498500D01*
G01Y500917D02*
X356750Y501333D01*
X357167Y501667D01*
X357750Y501833D01*
X358333Y501667D01*
X358750Y501333D01*
X359000Y500833D01*
Y498500D01*
G01X270583Y513500D02*
Y518500D01*
X274417Y513500D01*
Y518500D01*
G01X276433Y513500D02*
Y518500D01*
X278433D01*
X279100Y518250D01*
X279600Y517667D01*
X279767Y517000D01*
X279600Y516333D01*
X279183Y515833D01*
X278433Y515583D01*
X276433D01*
G01X283700Y518500D02*
Y513500D01*
G01X281783Y518500D02*
X285617D01*
G01X287550Y513500D02*
Y518500D01*
G01X291050D02*
Y513500D01*
G01Y516000D02*
X287550D01*
G01X298750Y514167D02*
X299417Y513750D01*
X300167Y513500D01*
X300833D01*
X301500Y513750D01*
X302000Y514167D01*
X302250Y514750D01*
X302083Y515333D01*
X301667Y515833D01*
X300917Y516167D01*
X299917Y516333D01*
X299333Y516667D01*
X299083Y517250D01*
X299250Y517833D01*
X299667Y518250D01*
X300250Y518500D01*
X300833D01*
X301417Y518333D01*
X301917Y517917D01*
G01X306100Y516833D02*
Y513500D01*
G01Y518167D02*
X305933Y518250D01*
Y518417D01*
X306100Y518500D01*
X306267Y518417D01*
Y518250D01*
X306100Y518167D01*
G01X310450Y516833D02*
X312950D01*
X310450Y513500D01*
X312950D01*
G01X316050Y515750D02*
X318717D01*
X318467Y516333D01*
X318050Y516667D01*
X317467Y516833D01*
X316883Y516750D01*
X316383Y516500D01*
X316050Y515917D01*
X315883Y515417D01*
Y514917D01*
X316050Y514417D01*
X316467Y513917D01*
X316967Y513583D01*
X317550Y513500D01*
X318133Y513667D01*
X318717Y514167D01*
G01X324567Y513500D02*
X321233Y515167D01*
X324567Y516833D01*
G01X332267Y514250D02*
X332767Y513833D01*
X333350Y513583D01*
X334100Y513500D01*
X334850Y513667D01*
X335433Y514000D01*
X335850Y514583D01*
X335933Y515250D01*
X335767Y515917D01*
X335350Y516333D01*
X334767Y516667D01*
X334183Y516750D01*
X333600Y516667D01*
X332850Y516333D01*
X333100Y518500D01*
X335350D01*
G01X337200Y513500D02*
Y516833D01*
G01Y515917D02*
X337450Y516333D01*
X337867Y516667D01*
X338450Y516833D01*
X339033Y516667D01*
X339450Y516333D01*
X339700Y515917D01*
Y513500D01*
G01Y515917D02*
X339950Y516333D01*
X340367Y516667D01*
X340950Y516833D01*
X341533Y516667D01*
X341950Y516333D01*
X342200Y515833D01*
Y513500D01*
G01X342800D02*
Y516833D01*
G01Y515917D02*
X343050Y516333D01*
X343467Y516667D01*
X344050Y516833D01*
X344633Y516667D01*
X345050Y516333D01*
X345300Y515917D01*
Y513500D01*
G01Y515917D02*
X345550Y516333D01*
X345967Y516667D01*
X346550Y516833D01*
X347133Y516667D01*
X347550Y516333D01*
X347800Y515833D01*
Y513500D01*
G01X270667Y535000D02*
Y531417D01*
X271000Y530667D01*
X271667Y530167D01*
X272500Y530000D01*
X273333Y530167D01*
X274000Y530667D01*
X274333Y531417D01*
Y535000D01*
G01X276683Y530000D02*
Y533333D01*
G01Y532500D02*
X277017Y532917D01*
X277517Y533250D01*
X278183Y533333D01*
X278767Y533250D01*
X279267Y532917D01*
X279517Y532333D01*
Y530000D01*
G01X282617Y531667D02*
X284783D01*
G01X287800Y528333D02*
Y533333D01*
G01Y532583D02*
X288217Y533000D01*
X288633Y533250D01*
X289300Y533333D01*
X289883Y533250D01*
X290467Y532833D01*
X290717Y532250D01*
X290800Y531667D01*
X290717Y531083D01*
X290467Y530500D01*
X289967Y530167D01*
X289300Y530000D01*
X288717Y530083D01*
X288133Y530333D01*
X287800Y530667D01*
G01X294900Y530000D02*
Y535000D01*
G01X299083Y533333D02*
Y531000D01*
X299417Y530417D01*
X299917Y530083D01*
X300500Y530000D01*
X301083Y530083D01*
X301583Y530417D01*
X301917Y531000D01*
G01Y530000D02*
Y533333D01*
G01X304933Y528750D02*
X305517Y528417D01*
X306183Y528333D01*
X306767Y528417D01*
X307267Y528833D01*
X307600Y529417D01*
Y533333D01*
G01Y532667D02*
X307267Y533000D01*
X306767Y533250D01*
X306183Y533333D01*
X305517Y533167D01*
X305100Y532833D01*
X304767Y532250D01*
X304600Y531667D01*
X304683Y531167D01*
X305017Y530583D01*
X305517Y530167D01*
X306183Y530000D01*
X306683Y530083D01*
X307267Y530417D01*
X307600Y530750D01*
G01X310533Y528750D02*
X311117Y528417D01*
X311783Y528333D01*
X312367Y528417D01*
X312867Y528833D01*
X313200Y529417D01*
Y533333D01*
G01Y532667D02*
X312867Y533000D01*
X312367Y533250D01*
X311783Y533333D01*
X311117Y533167D01*
X310700Y532833D01*
X310367Y532250D01*
X310200Y531667D01*
X310283Y531167D01*
X310617Y530583D01*
X311117Y530167D01*
X311783Y530000D01*
X312283Y530083D01*
X312867Y530417D01*
X313200Y530750D01*
G01X316050Y532250D02*
X318717D01*
X318467Y532833D01*
X318050Y533167D01*
X317467Y533333D01*
X316883Y533250D01*
X316383Y533000D01*
X316050Y532417D01*
X315883Y531917D01*
Y531417D01*
X316050Y530917D01*
X316467Y530417D01*
X316967Y530083D01*
X317550Y530000D01*
X318133Y530167D01*
X318717Y530667D01*
G01X324400Y535000D02*
Y530000D01*
G01Y530750D02*
X324067Y530333D01*
X323567Y530083D01*
X322983Y530000D01*
X322317Y530167D01*
X321817Y530583D01*
X321483Y531083D01*
X321400Y531667D01*
X321483Y532250D01*
X321817Y532750D01*
X322317Y533167D01*
X322983Y533333D01*
X323567Y533250D01*
X323983Y533083D01*
X324400Y532750D01*
G01X332433Y530000D02*
Y535000D01*
X334433D01*
X335100Y534750D01*
X335600Y534167D01*
X335767Y533500D01*
X335600Y532833D01*
X335183Y532333D01*
X334433Y532083D01*
X332433D01*
G01X339700Y535000D02*
Y530000D01*
G01X337783Y535000D02*
X341617D01*
G01X343550Y530000D02*
Y535000D01*
G01X347050D02*
Y530000D01*
G01Y532500D02*
X343550D01*
G01X356083Y528333D02*
X355250Y529167D01*
X354833Y530000D01*
Y533333D01*
X355250Y534167D01*
X356083Y535000D01*
G01X360350Y530000D02*
Y535000D01*
G01X363850D02*
Y530000D01*
G01Y532500D02*
X360350D01*
G01X367700Y530000D02*
X367200Y530083D01*
X366700Y530417D01*
X366367Y531000D01*
X366200Y531667D01*
X366367Y532333D01*
X366700Y532917D01*
X367200Y533250D01*
X367700Y533333D01*
X368200Y533250D01*
X368700Y532917D01*
X369033Y532333D01*
X369117Y531667D01*
X369033Y531000D01*
X368700Y530417D01*
X368200Y530083D01*
X367700Y530000D01*
G01X373300D02*
Y535000D01*
G01X377650Y532250D02*
X380317D01*
X380067Y532833D01*
X379650Y533167D01*
X379067Y533333D01*
X378483Y533250D01*
X377983Y533000D01*
X377650Y532417D01*
X377483Y531917D01*
Y531417D01*
X377650Y530917D01*
X378067Y530417D01*
X378567Y530083D01*
X379150Y530000D01*
X379733Y530167D01*
X380317Y530667D01*
G01X388350D02*
X389017Y530250D01*
X389767Y530000D01*
X390433D01*
X391100Y530250D01*
X391600Y530667D01*
X391850Y531250D01*
X391683Y531833D01*
X391267Y532333D01*
X390517Y532667D01*
X389517Y532833D01*
X388933Y533167D01*
X388683Y533750D01*
X388850Y534333D01*
X389267Y534750D01*
X389850Y535000D01*
X390433D01*
X391017Y534833D01*
X391517Y534417D01*
G01X395700Y533333D02*
Y530000D01*
G01Y534667D02*
X395533Y534750D01*
Y534917D01*
X395700Y535000D01*
X395867Y534917D01*
Y534750D01*
X395700Y534667D01*
G01X400050Y533333D02*
X402550D01*
X400050Y530000D01*
X402550D01*
G01X405650Y532250D02*
X408317D01*
X408067Y532833D01*
X407650Y533167D01*
X407067Y533333D01*
X406483Y533250D01*
X405983Y533000D01*
X405650Y532417D01*
X405483Y531917D01*
Y531417D01*
X405650Y530917D01*
X406067Y530417D01*
X406567Y530083D01*
X407150Y530000D01*
X407733Y530167D01*
X408317Y530667D01*
G01X414167Y530000D02*
X410833Y531667D01*
X414167Y533333D01*
G01X418100Y530000D02*
Y535000D01*
X417100Y534000D01*
G01Y530000D02*
X419100D01*
G01X422283Y530583D02*
X422867Y530167D01*
X423533Y530000D01*
X424200Y530167D01*
X424783Y530667D01*
X425200Y531417D01*
X425367Y532167D01*
Y533083D01*
X425200Y533833D01*
X424783Y534500D01*
X424283Y534833D01*
X423700Y535000D01*
X423033Y534833D01*
X422533Y534500D01*
X422200Y534000D01*
X422033Y533333D01*
X422200Y532750D01*
X422617Y532167D01*
X423117Y531833D01*
X423700Y531750D01*
X424367Y531917D01*
X424867Y532333D01*
X425367Y533083D01*
G01X429133Y530000D02*
X429300Y531083D01*
X429550Y532000D01*
X429883Y532833D01*
X430300Y533750D01*
X430967Y535000D01*
X427633D01*
G01X432400Y530000D02*
Y533333D01*
G01Y532417D02*
X432650Y532833D01*
X433067Y533167D01*
X433650Y533333D01*
X434233Y533167D01*
X434650Y532833D01*
X434900Y532417D01*
Y530000D01*
G01Y532417D02*
X435150Y532833D01*
X435567Y533167D01*
X436150Y533333D01*
X436733Y533167D01*
X437150Y532833D01*
X437400Y532333D01*
Y530000D01*
G01X440500Y533333D02*
Y530000D01*
G01Y534667D02*
X440333Y534750D01*
Y534917D01*
X440500Y535000D01*
X440667Y534917D01*
Y534750D01*
X440500Y534667D01*
G01X446100Y530000D02*
Y535000D01*
G01X455217Y533333D02*
X456217Y530000D01*
X457300Y533333D01*
X458383Y530000D01*
X459383Y533333D01*
G01X462900D02*
Y530000D01*
G01Y534667D02*
X462733Y534750D01*
Y534917D01*
X462900Y535000D01*
X463067Y534917D01*
Y534750D01*
X462900Y534667D01*
G01X468500Y535000D02*
Y530000D01*
G01X467333Y533333D02*
X469667D01*
G01X472683Y530000D02*
Y535000D01*
G01Y532583D02*
X473100Y533000D01*
X473517Y533250D01*
X474183Y533333D01*
X474683Y533250D01*
X475267Y532917D01*
X475517Y532417D01*
Y530000D01*
G01X483550D02*
Y535000D01*
G01X487050D02*
Y530000D01*
G01Y532500D02*
X483550D01*
G01X488817Y530000D02*
X490900Y535000D01*
X492983Y530000D01*
G01X492233Y531750D02*
X489567D01*
G01X494750Y530667D02*
X495417Y530250D01*
X496167Y530000D01*
X496833D01*
X497500Y530250D01*
X498000Y530667D01*
X498250Y531250D01*
X498083Y531833D01*
X497667Y532333D01*
X496917Y532667D01*
X495917Y532833D01*
X495333Y533167D01*
X495083Y533750D01*
X495250Y534333D01*
X495667Y534750D01*
X496250Y535000D01*
X496833D01*
X497417Y534833D01*
X497917Y534417D01*
G01X500433Y535000D02*
Y530000D01*
X503767D01*
G01X511800Y528333D02*
Y533333D01*
G01Y532583D02*
X512217Y533000D01*
X512633Y533250D01*
X513300Y533333D01*
X513883Y533250D01*
X514467Y532833D01*
X514717Y532250D01*
X514800Y531667D01*
X514717Y531083D01*
X514467Y530500D01*
X513967Y530167D01*
X513300Y530000D01*
X512717Y530083D01*
X512133Y530333D01*
X511800Y530667D01*
G01X517733Y530000D02*
Y533333D01*
G01Y532667D02*
X518150Y533000D01*
X518567Y533250D01*
X519150Y533333D01*
X519567Y533250D01*
X520067Y533000D01*
G01X524500Y530000D02*
X524000Y530083D01*
X523500Y530417D01*
X523167Y531000D01*
X523000Y531667D01*
X523167Y532333D01*
X523500Y532917D01*
X524000Y533250D01*
X524500Y533333D01*
X525000Y533250D01*
X525500Y532917D01*
X525833Y532333D01*
X525917Y531667D01*
X525833Y531000D01*
X525500Y530417D01*
X525000Y530083D01*
X524500Y530000D01*
G01X531600Y535000D02*
Y530000D01*
G01Y530750D02*
X531267Y530333D01*
X530767Y530083D01*
X530183Y530000D01*
X529517Y530167D01*
X529017Y530583D01*
X528683Y531083D01*
X528600Y531667D01*
X528683Y532250D01*
X529017Y532750D01*
X529517Y533167D01*
X530183Y533333D01*
X530767Y533250D01*
X531183Y533083D01*
X531600Y532750D01*
G01X534283Y533333D02*
Y531000D01*
X534617Y530417D01*
X535117Y530083D01*
X535700Y530000D01*
X536283Y530083D01*
X536783Y530417D01*
X537117Y531000D01*
G01Y530000D02*
Y533333D01*
G01X542633Y532917D02*
X542050Y533250D01*
X541550Y533333D01*
X540883Y533167D01*
X540383Y532833D01*
X540050Y532250D01*
X539967Y531667D01*
X540050Y531083D01*
X540383Y530583D01*
X540883Y530167D01*
X541550Y530000D01*
X542133Y530167D01*
X542633Y530500D01*
G01X546900Y535000D02*
Y530000D01*
G01X545733Y533333D02*
X548067D01*
G01X551250Y530583D02*
X551667Y530250D01*
X552250Y530000D01*
X552750D01*
X553250Y530167D01*
X553583Y530417D01*
X553750Y530750D01*
X553667Y531250D01*
X553333Y531500D01*
X551833Y532000D01*
X551500Y532583D01*
X551667Y533000D01*
X552000Y533250D01*
X552500Y533333D01*
X553000Y533250D01*
X553500Y533000D01*
G01X558517Y528333D02*
X559350Y529167D01*
X559767Y530000D01*
Y533333D01*
X559350Y534167D01*
X558517Y535000D01*
G01X270667Y550000D02*
Y546417D01*
X271000Y545667D01*
X271667Y545167D01*
X272500Y545000D01*
X273333Y545167D01*
X274000Y545667D01*
X274333Y546417D01*
Y550000D01*
G01X276683Y545000D02*
Y548333D01*
G01Y547500D02*
X277017Y547917D01*
X277517Y548250D01*
X278183Y548333D01*
X278767Y548250D01*
X279267Y547917D01*
X279517Y547333D01*
Y545000D01*
G01X282617Y546667D02*
X284783D01*
G01X287800Y543333D02*
Y548333D01*
G01Y547583D02*
X288217Y548000D01*
X288633Y548250D01*
X289300Y548333D01*
X289883Y548250D01*
X290467Y547833D01*
X290717Y547250D01*
X290800Y546667D01*
X290717Y546083D01*
X290467Y545500D01*
X289967Y545167D01*
X289300Y545000D01*
X288717Y545083D01*
X288133Y545333D01*
X287800Y545667D01*
G01X294900Y545000D02*
Y550000D01*
G01X299083Y548333D02*
Y546000D01*
X299417Y545417D01*
X299917Y545083D01*
X300500Y545000D01*
X301083Y545083D01*
X301583Y545417D01*
X301917Y546000D01*
G01Y545000D02*
Y548333D01*
G01X304933Y543750D02*
X305517Y543417D01*
X306183Y543333D01*
X306767Y543417D01*
X307267Y543833D01*
X307600Y544417D01*
Y548333D01*
G01Y547667D02*
X307267Y548000D01*
X306767Y548250D01*
X306183Y548333D01*
X305517Y548167D01*
X305100Y547833D01*
X304767Y547250D01*
X304600Y546667D01*
X304683Y546167D01*
X305017Y545583D01*
X305517Y545167D01*
X306183Y545000D01*
X306683Y545083D01*
X307267Y545417D01*
X307600Y545750D01*
G01X310533Y543750D02*
X311117Y543417D01*
X311783Y543333D01*
X312367Y543417D01*
X312867Y543833D01*
X313200Y544417D01*
Y548333D01*
G01Y547667D02*
X312867Y548000D01*
X312367Y548250D01*
X311783Y548333D01*
X311117Y548167D01*
X310700Y547833D01*
X310367Y547250D01*
X310200Y546667D01*
X310283Y546167D01*
X310617Y545583D01*
X311117Y545167D01*
X311783Y545000D01*
X312283Y545083D01*
X312867Y545417D01*
X313200Y545750D01*
G01X316050Y547250D02*
X318717D01*
X318467Y547833D01*
X318050Y548167D01*
X317467Y548333D01*
X316883Y548250D01*
X316383Y548000D01*
X316050Y547417D01*
X315883Y546917D01*
Y546417D01*
X316050Y545917D01*
X316467Y545417D01*
X316967Y545083D01*
X317550Y545000D01*
X318133Y545167D01*
X318717Y545667D01*
G01X324400Y550000D02*
Y545000D01*
G01Y545750D02*
X324067Y545333D01*
X323567Y545083D01*
X322983Y545000D01*
X322317Y545167D01*
X321817Y545583D01*
X321483Y546083D01*
X321400Y546667D01*
X321483Y547250D01*
X321817Y547750D01*
X322317Y548167D01*
X322983Y548333D01*
X323567Y548250D01*
X323983Y548083D01*
X324400Y547750D01*
G01X332433Y545000D02*
Y550000D01*
X334433D01*
X335100Y549750D01*
X335600Y549167D01*
X335767Y548500D01*
X335600Y547833D01*
X335183Y547333D01*
X334433Y547083D01*
X332433D01*
G01X339700Y550000D02*
Y545000D01*
G01X337783Y550000D02*
X341617D01*
G01X343550Y545000D02*
Y550000D01*
G01X347050D02*
Y545000D01*
G01Y547500D02*
X343550D01*
G01X356083Y543333D02*
X355250Y544167D01*
X354833Y545000D01*
Y548333D01*
X355250Y549167D01*
X356083Y550000D01*
G01X360350Y545000D02*
Y550000D01*
G01X363850D02*
Y545000D01*
G01Y547500D02*
X360350D01*
G01X367700Y545000D02*
X367200Y545083D01*
X366700Y545417D01*
X366367Y546000D01*
X366200Y546667D01*
X366367Y547333D01*
X366700Y547917D01*
X367200Y548250D01*
X367700Y548333D01*
X368200Y548250D01*
X368700Y547917D01*
X369033Y547333D01*
X369117Y546667D01*
X369033Y546000D01*
X368700Y545417D01*
X368200Y545083D01*
X367700Y545000D01*
G01X373300D02*
Y550000D01*
G01X377650Y547250D02*
X380317D01*
X380067Y547833D01*
X379650Y548167D01*
X379067Y548333D01*
X378483Y548250D01*
X377983Y548000D01*
X377650Y547417D01*
X377483Y546917D01*
Y546417D01*
X377650Y545917D01*
X378067Y545417D01*
X378567Y545083D01*
X379150Y545000D01*
X379733Y545167D01*
X380317Y545667D01*
G01X388350D02*
X389017Y545250D01*
X389767Y545000D01*
X390433D01*
X391100Y545250D01*
X391600Y545667D01*
X391850Y546250D01*
X391683Y546833D01*
X391267Y547333D01*
X390517Y547667D01*
X389517Y547833D01*
X388933Y548167D01*
X388683Y548750D01*
X388850Y549333D01*
X389267Y549750D01*
X389850Y550000D01*
X390433D01*
X391017Y549833D01*
X391517Y549417D01*
G01X395700Y548333D02*
Y545000D01*
G01Y549667D02*
X395533Y549750D01*
Y549917D01*
X395700Y550000D01*
X395867Y549917D01*
Y549750D01*
X395700Y549667D01*
G01X400050Y548333D02*
X402550D01*
X400050Y545000D01*
X402550D01*
G01X405650Y547250D02*
X408317D01*
X408067Y547833D01*
X407650Y548167D01*
X407067Y548333D01*
X406483Y548250D01*
X405983Y548000D01*
X405650Y547417D01*
X405483Y546917D01*
Y546417D01*
X405650Y545917D01*
X406067Y545417D01*
X406567Y545083D01*
X407150Y545000D01*
X407733Y545167D01*
X408317Y545667D01*
G01X414167Y545000D02*
X410833Y546667D01*
X414167Y548333D01*
G01X418100Y545000D02*
Y550000D01*
X417100Y549000D01*
G01Y545000D02*
X419100D01*
G01X422283Y545583D02*
X422867Y545167D01*
X423533Y545000D01*
X424200Y545167D01*
X424783Y545667D01*
X425200Y546417D01*
X425367Y547167D01*
Y548083D01*
X425200Y548833D01*
X424783Y549500D01*
X424283Y549833D01*
X423700Y550000D01*
X423033Y549833D01*
X422533Y549500D01*
X422200Y549000D01*
X422033Y548333D01*
X422200Y547750D01*
X422617Y547167D01*
X423117Y546833D01*
X423700Y546750D01*
X424367Y546917D01*
X424867Y547333D01*
X425367Y548083D01*
G01X429133Y545000D02*
X429300Y546083D01*
X429550Y547000D01*
X429883Y547833D01*
X430300Y548750D01*
X430967Y550000D01*
X427633D01*
G01X432400Y545000D02*
Y548333D01*
G01Y547417D02*
X432650Y547833D01*
X433067Y548167D01*
X433650Y548333D01*
X434233Y548167D01*
X434650Y547833D01*
X434900Y547417D01*
Y545000D01*
G01Y547417D02*
X435150Y547833D01*
X435567Y548167D01*
X436150Y548333D01*
X436733Y548167D01*
X437150Y547833D01*
X437400Y547333D01*
Y545000D01*
G01X440500Y548333D02*
Y545000D01*
G01Y549667D02*
X440333Y549750D01*
Y549917D01*
X440500Y550000D01*
X440667Y549917D01*
Y549750D01*
X440500Y549667D01*
G01X446100Y545000D02*
Y550000D01*
G01X455217Y548333D02*
X456217Y545000D01*
X457300Y548333D01*
X458383Y545000D01*
X459383Y548333D01*
G01X462900D02*
Y545000D01*
G01Y549667D02*
X462733Y549750D01*
Y549917D01*
X462900Y550000D01*
X463067Y549917D01*
Y549750D01*
X462900Y549667D01*
G01X468500Y550000D02*
Y545000D01*
G01X467333Y548333D02*
X469667D01*
G01X472683Y545000D02*
Y550000D01*
G01Y547583D02*
X473100Y548000D01*
X473517Y548250D01*
X474183Y548333D01*
X474683Y548250D01*
X475267Y547917D01*
X475517Y547417D01*
Y545000D01*
G01X483883D02*
Y548333D01*
G01Y547500D02*
X484217Y547917D01*
X484717Y548250D01*
X485383Y548333D01*
X485967Y548250D01*
X486467Y547917D01*
X486717Y547333D01*
Y545000D01*
G01X490900D02*
X490400Y545083D01*
X489900Y545417D01*
X489567Y546000D01*
X489400Y546667D01*
X489567Y547333D01*
X489900Y547917D01*
X490400Y548250D01*
X490900Y548333D01*
X491400Y548250D01*
X491900Y547917D01*
X492233Y547333D01*
X492317Y546667D01*
X492233Y546000D01*
X491900Y545417D01*
X491400Y545083D01*
X490900Y545000D01*
G01X495083D02*
Y548333D01*
G01Y547500D02*
X495417Y547917D01*
X495917Y548250D01*
X496583Y548333D01*
X497167Y548250D01*
X497667Y547917D01*
X497917Y547333D01*
Y545000D01*
G01X501017Y546667D02*
X503183D01*
G01X505950Y545000D02*
Y550000D01*
G01X509450D02*
Y545000D01*
G01Y547500D02*
X505950D01*
G01X511217Y545000D02*
X513300Y550000D01*
X515383Y545000D01*
G01X514633Y546750D02*
X511967D01*
G01X517150Y545667D02*
X517817Y545250D01*
X518567Y545000D01*
X519233D01*
X519900Y545250D01*
X520400Y545667D01*
X520650Y546250D01*
X520483Y546833D01*
X520067Y547333D01*
X519317Y547667D01*
X518317Y547833D01*
X517733Y548167D01*
X517483Y548750D01*
X517650Y549333D01*
X518067Y549750D01*
X518650Y550000D01*
X519233D01*
X519817Y549833D01*
X520317Y549417D01*
G01X522833Y550000D02*
Y545000D01*
X526167D01*
G01X534200Y543333D02*
Y548333D01*
G01Y547583D02*
X534617Y548000D01*
X535033Y548250D01*
X535700Y548333D01*
X536283Y548250D01*
X536867Y547833D01*
X537117Y547250D01*
X537200Y546667D01*
X537117Y546083D01*
X536867Y545500D01*
X536367Y545167D01*
X535700Y545000D01*
X535117Y545083D01*
X534533Y545333D01*
X534200Y545667D01*
G01X540133Y545000D02*
Y548333D01*
G01Y547667D02*
X540550Y548000D01*
X540967Y548250D01*
X541550Y548333D01*
X541967Y548250D01*
X542467Y548000D01*
G01X546900Y545000D02*
X546400Y545083D01*
X545900Y545417D01*
X545567Y546000D01*
X545400Y546667D01*
X545567Y547333D01*
X545900Y547917D01*
X546400Y548250D01*
X546900Y548333D01*
X547400Y548250D01*
X547900Y547917D01*
X548233Y547333D01*
X548317Y546667D01*
X548233Y546000D01*
X547900Y545417D01*
X547400Y545083D01*
X546900Y545000D01*
G01X554000Y550000D02*
Y545000D01*
G01Y545750D02*
X553667Y545333D01*
X553167Y545083D01*
X552583Y545000D01*
X551917Y545167D01*
X551417Y545583D01*
X551083Y546083D01*
X551000Y546667D01*
X551083Y547250D01*
X551417Y547750D01*
X551917Y548167D01*
X552583Y548333D01*
X553167Y548250D01*
X553583Y548083D01*
X554000Y547750D01*
G01X556683Y548333D02*
Y546000D01*
X557017Y545417D01*
X557517Y545083D01*
X558100Y545000D01*
X558683Y545083D01*
X559183Y545417D01*
X559517Y546000D01*
G01Y545000D02*
Y548333D01*
G01X565033Y547917D02*
X564450Y548250D01*
X563950Y548333D01*
X563283Y548167D01*
X562783Y547833D01*
X562450Y547250D01*
X562367Y546667D01*
X562450Y546083D01*
X562783Y545583D01*
X563283Y545167D01*
X563950Y545000D01*
X564533Y545167D01*
X565033Y545500D01*
G01X569300Y550000D02*
Y545000D01*
G01X568133Y548333D02*
X570467D01*
G01X573650Y545583D02*
X574067Y545250D01*
X574650Y545000D01*
X575150D01*
X575650Y545167D01*
X575983Y545417D01*
X576150Y545750D01*
X576067Y546250D01*
X575733Y546500D01*
X574233Y547000D01*
X573900Y547583D01*
X574067Y548000D01*
X574400Y548250D01*
X574900Y548333D01*
X575400Y548250D01*
X575900Y548000D01*
G01X580917Y543333D02*
X581750Y544167D01*
X582167Y545000D01*
Y548333D01*
X581750Y549167D01*
X580917Y550000D01*
G01X270833Y560000D02*
Y565000D01*
X272833D01*
X273500Y564750D01*
X274000Y564167D01*
X274167Y563500D01*
X274000Y562833D01*
X273583Y562333D01*
X272833Y562083D01*
X270833D01*
G01X278100Y560000D02*
Y565000D01*
G01X282283Y563333D02*
Y561000D01*
X282617Y560417D01*
X283117Y560083D01*
X283700Y560000D01*
X284283Y560083D01*
X284783Y560417D01*
X285117Y561000D01*
G01Y560000D02*
Y563333D01*
G01X288133Y558750D02*
X288717Y558417D01*
X289383Y558333D01*
X289967Y558417D01*
X290467Y558833D01*
X290800Y559417D01*
Y563333D01*
G01Y562667D02*
X290467Y563000D01*
X289967Y563250D01*
X289383Y563333D01*
X288717Y563167D01*
X288300Y562833D01*
X287967Y562250D01*
X287800Y561667D01*
X287883Y561167D01*
X288217Y560583D01*
X288717Y560167D01*
X289383Y560000D01*
X289883Y560083D01*
X290467Y560417D01*
X290800Y560750D01*
G01X293733Y558750D02*
X294317Y558417D01*
X294983Y558333D01*
X295567Y558417D01*
X296067Y558833D01*
X296400Y559417D01*
Y563333D01*
G01Y562667D02*
X296067Y563000D01*
X295567Y563250D01*
X294983Y563333D01*
X294317Y563167D01*
X293900Y562833D01*
X293567Y562250D01*
X293400Y561667D01*
X293483Y561167D01*
X293817Y560583D01*
X294317Y560167D01*
X294983Y560000D01*
X295483Y560083D01*
X296067Y560417D01*
X296400Y560750D01*
G01X299250Y562250D02*
X301917D01*
X301667Y562833D01*
X301250Y563167D01*
X300667Y563333D01*
X300083Y563250D01*
X299583Y563000D01*
X299250Y562417D01*
X299083Y561917D01*
Y561417D01*
X299250Y560917D01*
X299667Y560417D01*
X300167Y560083D01*
X300750Y560000D01*
X301333Y560167D01*
X301917Y560667D01*
G01X307600Y565000D02*
Y560000D01*
G01Y560750D02*
X307267Y560333D01*
X306767Y560083D01*
X306183Y560000D01*
X305517Y560167D01*
X305017Y560583D01*
X304683Y561083D01*
X304600Y561667D01*
X304683Y562250D01*
X305017Y562750D01*
X305517Y563167D01*
X306183Y563333D01*
X306767Y563250D01*
X307183Y563083D01*
X307600Y562750D01*
G01X315633Y560000D02*
Y565000D01*
X317633D01*
X318300Y564750D01*
X318800Y564167D01*
X318967Y563500D01*
X318800Y562833D01*
X318383Y562333D01*
X317633Y562083D01*
X315633D01*
G01X322900Y565000D02*
Y560000D01*
G01X320983Y565000D02*
X324817D01*
G01X326750Y560000D02*
Y565000D01*
G01X330250D02*
Y560000D01*
G01Y562500D02*
X326750D01*
G01X333683Y558333D02*
X332850Y559167D01*
X332433Y560000D01*
Y563333D01*
X332850Y564167D01*
X333683Y565000D01*
G01X338283Y560000D02*
Y565000D01*
G01Y562583D02*
X338700Y563000D01*
X339117Y563250D01*
X339783Y563333D01*
X340283Y563250D01*
X340867Y562917D01*
X341117Y562417D01*
Y560000D01*
G01X345300D02*
X344800Y560083D01*
X344300Y560417D01*
X343967Y561000D01*
X343800Y561667D01*
X343967Y562333D01*
X344300Y562917D01*
X344800Y563250D01*
X345300Y563333D01*
X345800Y563250D01*
X346300Y562917D01*
X346633Y562333D01*
X346717Y561667D01*
X346633Y561000D01*
X346300Y560417D01*
X345800Y560083D01*
X345300Y560000D01*
G01X350900D02*
Y565000D01*
G01X355250Y562250D02*
X357917D01*
X357667Y562833D01*
X357250Y563167D01*
X356667Y563333D01*
X356083Y563250D01*
X355583Y563000D01*
X355250Y562417D01*
X355083Y561917D01*
Y561417D01*
X355250Y560917D01*
X355667Y560417D01*
X356167Y560083D01*
X356750Y560000D01*
X357333Y560167D01*
X357917Y560667D01*
G01X366450Y560583D02*
X366867Y560250D01*
X367450Y560000D01*
X367950D01*
X368450Y560167D01*
X368783Y560417D01*
X368950Y560750D01*
X368867Y561250D01*
X368533Y561500D01*
X367033Y562000D01*
X366700Y562583D01*
X366867Y563000D01*
X367200Y563250D01*
X367700Y563333D01*
X368200Y563250D01*
X368700Y563000D01*
G01X373300Y563333D02*
Y560000D01*
G01Y564667D02*
X373133Y564750D01*
Y564917D01*
X373300Y565000D01*
X373467Y564917D01*
Y564750D01*
X373300Y564667D01*
G01X377650Y563333D02*
X380150D01*
X377650Y560000D01*
X380150D01*
G01X383250Y562250D02*
X385917D01*
X385667Y562833D01*
X385250Y563167D01*
X384667Y563333D01*
X384083Y563250D01*
X383583Y563000D01*
X383250Y562417D01*
X383083Y561917D01*
Y561417D01*
X383250Y560917D01*
X383667Y560417D01*
X384167Y560083D01*
X384750Y560000D01*
X385333Y560167D01*
X385917Y560667D01*
G01X388433Y560000D02*
X391767Y561667D01*
X388433Y563333D01*
G01X394617Y560917D02*
X396783D01*
G01Y562417D02*
X394617D01*
G01X401300Y560000D02*
Y565000D01*
X400300Y564000D01*
G01Y560000D02*
X402300D01*
G01X405317Y562083D02*
X405900Y562667D01*
X406400Y563000D01*
X407067Y563167D01*
X407650Y563000D01*
X408067Y562667D01*
X408400Y562167D01*
X408483Y561583D01*
X408400Y561083D01*
X408067Y560583D01*
X407567Y560167D01*
X406983Y560000D01*
X406317Y560167D01*
X405733Y560667D01*
X405400Y561417D01*
X405317Y562250D01*
X405483Y563333D01*
X405733Y563917D01*
X406150Y564500D01*
X406733Y564917D01*
X407317Y565000D01*
X407900Y564833D01*
X408317Y564417D01*
G01X415600Y560000D02*
Y563333D01*
G01Y562417D02*
X415850Y562833D01*
X416267Y563167D01*
X416850Y563333D01*
X417433Y563167D01*
X417850Y562833D01*
X418100Y562417D01*
Y560000D01*
G01Y562417D02*
X418350Y562833D01*
X418767Y563167D01*
X419350Y563333D01*
X419933Y563167D01*
X420350Y562833D01*
X420600Y562333D01*
Y560000D01*
G01X423700Y563333D02*
Y560000D01*
G01Y564667D02*
X423533Y564750D01*
Y564917D01*
X423700Y565000D01*
X423867Y564917D01*
Y564750D01*
X423700Y564667D01*
G01X429300Y560000D02*
Y565000D01*
G01X435317Y558333D02*
X436150Y559167D01*
X436567Y560000D01*
Y563333D01*
X436150Y564167D01*
X435317Y565000D01*
G01X262500Y479000D02*
X694500D01*
G01X262500Y494000D02*
X694500D01*
G01X262500Y509000D02*
X694500D01*
G01X262500Y524000D02*
X694500D01*
G01X262500Y539000D02*
X694500D01*
G01X262500Y554000D02*
X694500D01*
G01X262500Y569000D02*
X694500D01*
G01X273000Y609000D02*
Y604000D01*
G01X271083Y609000D02*
X274917D01*
G01X277183Y604000D02*
Y609000D01*
G01Y606583D02*
X277600Y607000D01*
X278017Y607250D01*
X278683Y607333D01*
X279183Y607250D01*
X279767Y606917D01*
X280017Y606417D01*
Y604000D01*
G01X282950Y606250D02*
X285617D01*
X285367Y606833D01*
X284950Y607167D01*
X284367Y607333D01*
X283783Y607250D01*
X283283Y607000D01*
X282950Y606417D01*
X282783Y605917D01*
Y605417D01*
X282950Y604917D01*
X283367Y604417D01*
X283867Y604083D01*
X284450Y604000D01*
X285033Y604167D01*
X285617Y604667D01*
G01X288633Y604000D02*
Y607333D01*
G01Y606667D02*
X289050Y607000D01*
X289467Y607250D01*
X290050Y607333D01*
X290467Y607250D01*
X290967Y607000D01*
G01X292900Y604000D02*
Y607333D01*
G01Y606417D02*
X293150Y606833D01*
X293567Y607167D01*
X294150Y607333D01*
X294733Y607167D01*
X295150Y606833D01*
X295400Y606417D01*
Y604000D01*
G01Y606417D02*
X295650Y606833D01*
X296067Y607167D01*
X296650Y607333D01*
X297233Y607167D01*
X297650Y606833D01*
X297900Y606333D01*
Y604000D01*
G01X302500D02*
Y607333D01*
G01Y606750D02*
X302167Y607083D01*
X301667Y607250D01*
X301083Y607333D01*
X300500Y607167D01*
X300000Y606833D01*
X299667Y606333D01*
X299500Y605667D01*
X299667Y605000D01*
X300000Y604500D01*
X300500Y604167D01*
X301083Y604000D01*
X301667Y604083D01*
X302167Y604333D01*
X302500Y604667D01*
G01X306600Y604000D02*
Y609000D01*
G01X316300Y602333D02*
Y607333D01*
G01Y606583D02*
X316717Y607000D01*
X317133Y607250D01*
X317800Y607333D01*
X318383Y607250D01*
X318967Y606833D01*
X319217Y606250D01*
X319300Y605667D01*
X319217Y605083D01*
X318967Y604500D01*
X318467Y604167D01*
X317800Y604000D01*
X317217Y604083D01*
X316633Y604333D01*
X316300Y604667D01*
G01X324900Y604000D02*
Y607333D01*
G01Y606750D02*
X324567Y607083D01*
X324067Y607250D01*
X323483Y607333D01*
X322900Y607167D01*
X322400Y606833D01*
X322067Y606333D01*
X321900Y605667D01*
X322067Y605000D01*
X322400Y604500D01*
X322900Y604167D01*
X323483Y604000D01*
X324067Y604083D01*
X324567Y604333D01*
X324900Y604667D01*
G01X330500Y609000D02*
Y604000D01*
G01Y604750D02*
X330167Y604333D01*
X329667Y604083D01*
X329083Y604000D01*
X328417Y604167D01*
X327917Y604583D01*
X327583Y605083D01*
X327500Y605667D01*
X327583Y606250D01*
X327917Y606750D01*
X328417Y607167D01*
X329083Y607333D01*
X329667Y607250D01*
X330083Y607083D01*
X330500Y606750D01*
G01X341533Y606917D02*
X340950Y607250D01*
X340450Y607333D01*
X339783Y607167D01*
X339283Y606833D01*
X338950Y606250D01*
X338867Y605667D01*
X338950Y605083D01*
X339283Y604583D01*
X339783Y604167D01*
X340450Y604000D01*
X341033Y604167D01*
X341533Y604500D01*
G01X347300Y604000D02*
Y607333D01*
G01Y606750D02*
X346967Y607083D01*
X346467Y607250D01*
X345883Y607333D01*
X345300Y607167D01*
X344800Y606833D01*
X344467Y606333D01*
X344300Y605667D01*
X344467Y605000D01*
X344800Y604500D01*
X345300Y604167D01*
X345883Y604000D01*
X346467Y604083D01*
X346967Y604333D01*
X347300Y604667D01*
G01X349983Y604000D02*
Y607333D01*
G01Y606500D02*
X350317Y606917D01*
X350817Y607250D01*
X351483Y607333D01*
X352067Y607250D01*
X352567Y606917D01*
X352817Y606333D01*
Y604000D01*
G01X363933Y606917D02*
X363350Y607250D01*
X362850Y607333D01*
X362183Y607167D01*
X361683Y606833D01*
X361350Y606250D01*
X361267Y605667D01*
X361350Y605083D01*
X361683Y604583D01*
X362183Y604167D01*
X362850Y604000D01*
X363433Y604167D01*
X363933Y604500D01*
G01X366783Y604000D02*
Y609000D01*
G01Y606583D02*
X367200Y607000D01*
X367617Y607250D01*
X368283Y607333D01*
X368783Y607250D01*
X369367Y606917D01*
X369617Y606417D01*
Y604000D01*
G01X375300D02*
Y607333D01*
G01Y606750D02*
X374967Y607083D01*
X374467Y607250D01*
X373883Y607333D01*
X373300Y607167D01*
X372800Y606833D01*
X372467Y606333D01*
X372300Y605667D01*
X372467Y605000D01*
X372800Y604500D01*
X373300Y604167D01*
X373883Y604000D01*
X374467Y604083D01*
X374967Y604333D01*
X375300Y604667D01*
G01X377983Y604000D02*
Y607333D01*
G01Y606500D02*
X378317Y606917D01*
X378817Y607250D01*
X379483Y607333D01*
X380067Y607250D01*
X380567Y606917D01*
X380817Y606333D01*
Y604000D01*
G01X383833Y602750D02*
X384417Y602417D01*
X385083Y602333D01*
X385667Y602417D01*
X386167Y602833D01*
X386500Y603417D01*
Y607333D01*
G01Y606667D02*
X386167Y607000D01*
X385667Y607250D01*
X385083Y607333D01*
X384417Y607167D01*
X384000Y606833D01*
X383667Y606250D01*
X383500Y605667D01*
X383583Y605167D01*
X383917Y604583D01*
X384417Y604167D01*
X385083Y604000D01*
X385583Y604083D01*
X386167Y604417D01*
X386500Y604750D01*
G01X389350Y606250D02*
X392017D01*
X391767Y606833D01*
X391350Y607167D01*
X390767Y607333D01*
X390183Y607250D01*
X389683Y607000D01*
X389350Y606417D01*
X389183Y605917D01*
Y605417D01*
X389350Y604917D01*
X389767Y604417D01*
X390267Y604083D01*
X390850Y604000D01*
X391433Y604167D01*
X392017Y604667D01*
G01X401800Y607333D02*
Y604000D01*
G01Y608667D02*
X401633Y608750D01*
Y608917D01*
X401800Y609000D01*
X401967Y608917D01*
Y608750D01*
X401800Y608667D01*
G01X405983Y604000D02*
Y607333D01*
G01Y606500D02*
X406317Y606917D01*
X406817Y607250D01*
X407483Y607333D01*
X408067Y607250D01*
X408567Y606917D01*
X408817Y606333D01*
Y604000D01*
G01X413000Y609000D02*
Y604000D01*
G01X411833Y607333D02*
X414167D01*
G01X418600Y604000D02*
X418100Y604083D01*
X417600Y604417D01*
X417267Y605000D01*
X417100Y605667D01*
X417267Y606333D01*
X417600Y606917D01*
X418100Y607250D01*
X418600Y607333D01*
X419100Y607250D01*
X419600Y606917D01*
X419933Y606333D01*
X420017Y605667D01*
X419933Y605000D01*
X419600Y604417D01*
X419100Y604083D01*
X418600Y604000D01*
G01X429300D02*
Y608250D01*
X429467Y608667D01*
X429800Y608917D01*
X430300Y609000D01*
X430800Y608833D01*
X431050Y608417D01*
G01X430050Y607000D02*
X428383D01*
G01X433983Y607333D02*
Y605000D01*
X434317Y604417D01*
X434817Y604083D01*
X435400Y604000D01*
X435983Y604083D01*
X436483Y604417D01*
X436817Y605000D01*
G01Y604000D02*
Y607333D01*
G01X441000Y604000D02*
Y609000D01*
G01X446600Y604000D02*
Y609000D01*
G01X459133Y606917D02*
X458550Y607250D01*
X458050Y607333D01*
X457383Y607167D01*
X456883Y606833D01*
X456550Y606250D01*
X456467Y605667D01*
X456550Y605083D01*
X456883Y604583D01*
X457383Y604167D01*
X458050Y604000D01*
X458633Y604167D01*
X459133Y604500D01*
G01X463400Y604000D02*
X462900Y604083D01*
X462400Y604417D01*
X462067Y605000D01*
X461900Y605667D01*
X462067Y606333D01*
X462400Y606917D01*
X462900Y607250D01*
X463400Y607333D01*
X463900Y607250D01*
X464400Y606917D01*
X464733Y606333D01*
X464817Y605667D01*
X464733Y605000D01*
X464400Y604417D01*
X463900Y604083D01*
X463400Y604000D01*
G01X467583D02*
Y607333D01*
G01Y606500D02*
X467917Y606917D01*
X468417Y607250D01*
X469083Y607333D01*
X469667Y607250D01*
X470167Y606917D01*
X470417Y606333D01*
Y604000D01*
G01X474600Y609000D02*
Y604000D01*
G01X473433Y607333D02*
X475767D01*
G01X481700Y604000D02*
Y607333D01*
G01Y606750D02*
X481367Y607083D01*
X480867Y607250D01*
X480283Y607333D01*
X479700Y607167D01*
X479200Y606833D01*
X478867Y606333D01*
X478700Y605667D01*
X478867Y605000D01*
X479200Y604500D01*
X479700Y604167D01*
X480283Y604000D01*
X480867Y604083D01*
X481367Y604333D01*
X481700Y604667D01*
G01X487133Y606917D02*
X486550Y607250D01*
X486050Y607333D01*
X485383Y607167D01*
X484883Y606833D01*
X484550Y606250D01*
X484467Y605667D01*
X484550Y605083D01*
X484883Y604583D01*
X485383Y604167D01*
X486050Y604000D01*
X486633Y604167D01*
X487133Y604500D01*
G01X491400Y609000D02*
Y604000D01*
G01X490233Y607333D02*
X492567D01*
G01X270417Y588500D02*
X272500Y593500D01*
X274583Y588500D01*
G01X273833Y590250D02*
X271167D01*
G01X276683Y588500D02*
Y591833D01*
G01Y591000D02*
X277017Y591417D01*
X277517Y591750D01*
X278183Y591833D01*
X278767Y591750D01*
X279267Y591417D01*
X279517Y590833D01*
Y588500D01*
G01X281950Y587000D02*
X282450Y586833D01*
X283117Y587000D01*
X283533Y587333D01*
X283867Y587750D01*
X284367Y589083D01*
X285450Y591833D01*
G01X282783D02*
X284367Y589083D01*
G01X293483Y588500D02*
Y593500D01*
G01Y591083D02*
X293900Y591500D01*
X294317Y591750D01*
X294983Y591833D01*
X295483Y591750D01*
X296067Y591417D01*
X296317Y590917D01*
Y588500D01*
G01X300500D02*
X300000Y588583D01*
X299500Y588917D01*
X299167Y589500D01*
X299000Y590167D01*
X299167Y590833D01*
X299500Y591417D01*
X300000Y591750D01*
X300500Y591833D01*
X301000Y591750D01*
X301500Y591417D01*
X301833Y590833D01*
X301917Y590167D01*
X301833Y589500D01*
X301500Y588917D01*
X301000Y588583D01*
X300500Y588500D01*
G01X306100D02*
Y593500D01*
G01X310450Y590750D02*
X313117D01*
X312867Y591333D01*
X312450Y591667D01*
X311867Y591833D01*
X311283Y591750D01*
X310783Y591500D01*
X310450Y590917D01*
X310283Y590417D01*
Y589917D01*
X310450Y589417D01*
X310867Y588917D01*
X311367Y588583D01*
X311950Y588500D01*
X312533Y588667D01*
X313117Y589167D01*
G01X322900Y593500D02*
Y588500D01*
G01X321733Y591833D02*
X324067D01*
G01X328500Y588500D02*
X328000Y588583D01*
X327500Y588917D01*
X327167Y589500D01*
X327000Y590167D01*
X327167Y590833D01*
X327500Y591417D01*
X328000Y591750D01*
X328500Y591833D01*
X329000Y591750D01*
X329500Y591417D01*
X329833Y590833D01*
X329917Y590167D01*
X329833Y589500D01*
X329500Y588917D01*
X329000Y588583D01*
X328500Y588500D01*
G01X338283D02*
Y593500D01*
G01Y591083D02*
X338700Y591500D01*
X339117Y591750D01*
X339783Y591833D01*
X340283Y591750D01*
X340867Y591417D01*
X341117Y590917D01*
Y588500D01*
G01X345300D02*
X344800Y588583D01*
X344300Y588917D01*
X343967Y589500D01*
X343800Y590167D01*
X343967Y590833D01*
X344300Y591417D01*
X344800Y591750D01*
X345300Y591833D01*
X345800Y591750D01*
X346300Y591417D01*
X346633Y590833D01*
X346717Y590167D01*
X346633Y589500D01*
X346300Y588917D01*
X345800Y588583D01*
X345300Y588500D01*
G01X350900D02*
Y593500D01*
G01X355250Y590750D02*
X357917D01*
X357667Y591333D01*
X357250Y591667D01*
X356667Y591833D01*
X356083Y591750D01*
X355583Y591500D01*
X355250Y590917D01*
X355083Y590417D01*
Y589917D01*
X355250Y589417D01*
X355667Y588917D01*
X356167Y588583D01*
X356750Y588500D01*
X357333Y588667D01*
X357917Y589167D01*
G01X270917Y619000D02*
X273000Y624000D01*
X275083Y619000D01*
G01X274333Y620750D02*
X271667D01*
G01X277183Y619000D02*
Y622333D01*
G01Y621500D02*
X277517Y621917D01*
X278017Y622250D01*
X278683Y622333D01*
X279267Y622250D01*
X279767Y621917D01*
X280017Y621333D01*
Y619000D01*
G01X284200Y624000D02*
Y619000D01*
G01X283033Y622333D02*
X285367D01*
G01X289800D02*
Y619000D01*
G01Y623667D02*
X289633Y623750D01*
Y623917D01*
X289800Y624000D01*
X289967Y623917D01*
Y623750D01*
X289800Y623667D01*
G01X294317Y620667D02*
X296483D01*
G01X299500Y617333D02*
Y622333D01*
G01Y621583D02*
X299917Y622000D01*
X300333Y622250D01*
X301000Y622333D01*
X301583Y622250D01*
X302167Y621833D01*
X302417Y621250D01*
X302500Y620667D01*
X302417Y620083D01*
X302167Y619500D01*
X301667Y619167D01*
X301000Y619000D01*
X300417Y619083D01*
X299833Y619333D01*
X299500Y619667D01*
G01X308100Y619000D02*
Y622333D01*
G01Y621750D02*
X307767Y622083D01*
X307267Y622250D01*
X306683Y622333D01*
X306100Y622167D01*
X305600Y621833D01*
X305267Y621333D01*
X305100Y620667D01*
X305267Y620000D01*
X305600Y619500D01*
X306100Y619167D01*
X306683Y619000D01*
X307267Y619083D01*
X307767Y619333D01*
X308100Y619667D01*
G01X313700Y624000D02*
Y619000D01*
G01Y619750D02*
X313367Y619333D01*
X312867Y619083D01*
X312283Y619000D01*
X311617Y619167D01*
X311117Y619583D01*
X310783Y620083D01*
X310700Y620667D01*
X310783Y621250D01*
X311117Y621750D01*
X311617Y622167D01*
X312283Y622333D01*
X312867Y622250D01*
X313283Y622083D01*
X313700Y621750D01*
G01X322150Y619583D02*
X322567Y619250D01*
X323150Y619000D01*
X323650D01*
X324150Y619167D01*
X324483Y619417D01*
X324650Y619750D01*
X324567Y620250D01*
X324233Y620500D01*
X322733Y621000D01*
X322400Y621583D01*
X322567Y622000D01*
X322900Y622250D01*
X323400Y622333D01*
X323900Y622250D01*
X324400Y622000D01*
G01X329000Y622333D02*
Y619000D01*
G01Y623667D02*
X328833Y623750D01*
Y623917D01*
X329000Y624000D01*
X329167Y623917D01*
Y623750D01*
X329000Y623667D01*
G01X333350Y622333D02*
X335850D01*
X333350Y619000D01*
X335850D01*
G01X338950Y621250D02*
X341617D01*
X341367Y621833D01*
X340950Y622167D01*
X340367Y622333D01*
X339783Y622250D01*
X339283Y622000D01*
X338950Y621417D01*
X338783Y620917D01*
Y620417D01*
X338950Y619917D01*
X339367Y619417D01*
X339867Y619083D01*
X340450Y619000D01*
X341033Y619167D01*
X341617Y619667D01*
G01X269717Y637573D02*
X270717Y634240D01*
X271800Y637573D01*
X272883Y634240D01*
X273883Y637573D01*
G01X277400D02*
Y634240D01*
G01Y638907D02*
X277233Y638990D01*
Y639157D01*
X277400Y639240D01*
X277567Y639157D01*
Y638990D01*
X277400Y638907D01*
G01X283000Y639240D02*
Y634240D01*
G01X281833Y637573D02*
X284167D01*
G01X287183Y634240D02*
Y639240D01*
G01Y636823D02*
X287600Y637240D01*
X288017Y637490D01*
X288683Y637573D01*
X289183Y637490D01*
X289767Y637157D01*
X290017Y636657D01*
Y634240D01*
G01X294200D02*
X293700Y634323D01*
X293200Y634657D01*
X292867Y635240D01*
X292700Y635907D01*
X292867Y636573D01*
X293200Y637157D01*
X293700Y637490D01*
X294200Y637573D01*
X294700Y637490D01*
X295200Y637157D01*
X295533Y636573D01*
X295617Y635907D01*
X295533Y635240D01*
X295200Y634657D01*
X294700Y634323D01*
X294200Y634240D01*
G01X298383Y637573D02*
Y635240D01*
X298717Y634657D01*
X299217Y634323D01*
X299800Y634240D01*
X300383Y634323D01*
X300883Y634657D01*
X301217Y635240D01*
G01Y634240D02*
Y637573D01*
G01X305400Y639240D02*
Y634240D01*
G01X304233Y637573D02*
X306567D01*
G01X317933Y637157D02*
X317350Y637490D01*
X316850Y637573D01*
X316183Y637407D01*
X315683Y637073D01*
X315350Y636490D01*
X315267Y635907D01*
X315350Y635323D01*
X315683Y634823D01*
X316183Y634407D01*
X316850Y634240D01*
X317433Y634407D01*
X317933Y634740D01*
G01X322200Y634240D02*
X321700Y634323D01*
X321200Y634657D01*
X320867Y635240D01*
X320700Y635907D01*
X320867Y636573D01*
X321200Y637157D01*
X321700Y637490D01*
X322200Y637573D01*
X322700Y637490D01*
X323200Y637157D01*
X323533Y636573D01*
X323617Y635907D01*
X323533Y635240D01*
X323200Y634657D01*
X322700Y634323D01*
X322200Y634240D01*
G01X326383D02*
Y637573D01*
G01Y636740D02*
X326717Y637157D01*
X327217Y637490D01*
X327883Y637573D01*
X328467Y637490D01*
X328967Y637157D01*
X329217Y636573D01*
Y634240D01*
G01X331983D02*
Y637573D01*
G01Y636740D02*
X332317Y637157D01*
X332817Y637490D01*
X333483Y637573D01*
X334067Y637490D01*
X334567Y637157D01*
X334817Y636573D01*
Y634240D01*
G01X337750Y636490D02*
X340417D01*
X340167Y637073D01*
X339750Y637407D01*
X339167Y637573D01*
X338583Y637490D01*
X338083Y637240D01*
X337750Y636657D01*
X337583Y636157D01*
Y635657D01*
X337750Y635157D01*
X338167Y634657D01*
X338667Y634323D01*
X339250Y634240D01*
X339833Y634407D01*
X340417Y634907D01*
G01X345933Y637157D02*
X345350Y637490D01*
X344850Y637573D01*
X344183Y637407D01*
X343683Y637073D01*
X343350Y636490D01*
X343267Y635907D01*
X343350Y635323D01*
X343683Y634823D01*
X344183Y634407D01*
X344850Y634240D01*
X345433Y634407D01*
X345933Y634740D01*
G01X350200Y639240D02*
Y634240D01*
G01X349033Y637573D02*
X351367D01*
G01X355800D02*
Y634240D01*
G01Y638907D02*
X355633Y638990D01*
Y639157D01*
X355800Y639240D01*
X355967Y639157D01*
Y638990D01*
X355800Y638907D01*
G01X359983Y634240D02*
Y637573D01*
G01Y636740D02*
X360317Y637157D01*
X360817Y637490D01*
X361483Y637573D01*
X362067Y637490D01*
X362567Y637157D01*
X362817Y636573D01*
Y634240D01*
G01X365833Y632990D02*
X366417Y632657D01*
X367083Y632573D01*
X367667Y632657D01*
X368167Y633073D01*
X368500Y633657D01*
Y637573D01*
G01Y636907D02*
X368167Y637240D01*
X367667Y637490D01*
X367083Y637573D01*
X366417Y637407D01*
X366000Y637073D01*
X365667Y636490D01*
X365500Y635907D01*
X365583Y635407D01*
X365917Y634823D01*
X366417Y634407D01*
X367083Y634240D01*
X367583Y634323D01*
X368167Y634657D01*
X368500Y634990D01*
G01X378200Y639240D02*
Y634240D01*
G01X377033Y637573D02*
X379367D01*
G01X383800Y634240D02*
X383300Y634323D01*
X382800Y634657D01*
X382467Y635240D01*
X382300Y635907D01*
X382467Y636573D01*
X382800Y637157D01*
X383300Y637490D01*
X383800Y637573D01*
X384300Y637490D01*
X384800Y637157D01*
X385133Y636573D01*
X385217Y635907D01*
X385133Y635240D01*
X384800Y634657D01*
X384300Y634323D01*
X383800Y634240D01*
G01X395000D02*
X394500Y634323D01*
X394000Y634657D01*
X393667Y635240D01*
X393500Y635907D01*
X393667Y636573D01*
X394000Y637157D01*
X394500Y637490D01*
X395000Y637573D01*
X395500Y637490D01*
X396000Y637157D01*
X396333Y636573D01*
X396417Y635907D01*
X396333Y635240D01*
X396000Y634657D01*
X395500Y634323D01*
X395000Y634240D01*
G01X400600Y639240D02*
Y634240D01*
G01X399433Y637573D02*
X401767D01*
G01X404783Y634240D02*
Y639240D01*
G01Y636823D02*
X405200Y637240D01*
X405617Y637490D01*
X406283Y637573D01*
X406783Y637490D01*
X407367Y637157D01*
X407617Y636657D01*
Y634240D01*
G01X410550Y636490D02*
X413217D01*
X412967Y637073D01*
X412550Y637407D01*
X411967Y637573D01*
X411383Y637490D01*
X410883Y637240D01*
X410550Y636657D01*
X410383Y636157D01*
Y635657D01*
X410550Y635157D01*
X410967Y634657D01*
X411467Y634323D01*
X412050Y634240D01*
X412633Y634407D01*
X413217Y634907D01*
G01X416233Y634240D02*
Y637573D01*
G01Y636907D02*
X416650Y637240D01*
X417067Y637490D01*
X417650Y637573D01*
X418067Y637490D01*
X418567Y637240D01*
G01X428600Y634240D02*
Y639240D01*
G01X435700Y634240D02*
Y637573D01*
G01Y636990D02*
X435367Y637323D01*
X434867Y637490D01*
X434283Y637573D01*
X433700Y637407D01*
X433200Y637073D01*
X432867Y636573D01*
X432700Y635907D01*
X432867Y635240D01*
X433200Y634740D01*
X433700Y634407D01*
X434283Y634240D01*
X434867Y634323D01*
X435367Y634573D01*
X435700Y634907D01*
G01X438050Y632740D02*
X438550Y632573D01*
X439217Y632740D01*
X439633Y633073D01*
X439967Y633490D01*
X440467Y634823D01*
X441550Y637573D01*
G01X438883D02*
X440467Y634823D01*
G01X444150Y636490D02*
X446817D01*
X446567Y637073D01*
X446150Y637407D01*
X445567Y637573D01*
X444983Y637490D01*
X444483Y637240D01*
X444150Y636657D01*
X443983Y636157D01*
Y635657D01*
X444150Y635157D01*
X444567Y634657D01*
X445067Y634323D01*
X445650Y634240D01*
X446233Y634407D01*
X446817Y634907D01*
G01X449833Y634240D02*
Y637573D01*
G01Y636907D02*
X450250Y637240D01*
X450667Y637490D01*
X451250Y637573D01*
X451667Y637490D01*
X452167Y637240D01*
G01X455350Y634823D02*
X455767Y634490D01*
X456350Y634240D01*
X456850D01*
X457350Y634407D01*
X457683Y634657D01*
X457850Y634990D01*
X457767Y635490D01*
X457433Y635740D01*
X455933Y636240D01*
X455600Y636823D01*
X455767Y637240D01*
X456100Y637490D01*
X456600Y637573D01*
X457100Y637490D01*
X457600Y637240D01*
G01X462617Y632573D02*
X463450Y633407D01*
X463867Y634240D01*
Y637573D01*
X463450Y638407D01*
X462617Y639240D01*
G01X270257Y644950D02*
Y649950D01*
X271923D01*
X272590Y649700D01*
X273090Y649367D01*
X273507Y648867D01*
X273840Y648283D01*
X273923Y647450D01*
X273840Y646617D01*
X273507Y646033D01*
X273090Y645533D01*
X272590Y645200D01*
X271923Y644950D01*
X270257D01*
G01X276440Y647200D02*
X279107D01*
X278857Y647783D01*
X278440Y648117D01*
X277857Y648283D01*
X277273Y648200D01*
X276773Y647950D01*
X276440Y647367D01*
X276273Y646867D01*
Y646367D01*
X276440Y645867D01*
X276857Y645367D01*
X277357Y645033D01*
X277940Y644950D01*
X278523Y645117D01*
X279107Y645617D01*
G01X283290Y644950D02*
Y649950D01*
G01X287640Y647200D02*
X290307D01*
X290057Y647783D01*
X289640Y648117D01*
X289057Y648283D01*
X288473Y648200D01*
X287973Y647950D01*
X287640Y647367D01*
X287473Y646867D01*
Y646367D01*
X287640Y645867D01*
X288057Y645367D01*
X288557Y645033D01*
X289140Y644950D01*
X289723Y645117D01*
X290307Y645617D01*
G01X294490Y649950D02*
Y644950D01*
G01X293323Y648283D02*
X295657D01*
G01X298840Y647200D02*
X301507D01*
X301257Y647783D01*
X300840Y648117D01*
X300257Y648283D01*
X299673Y648200D01*
X299173Y647950D01*
X298840Y647367D01*
X298673Y646867D01*
Y646367D01*
X298840Y645867D01*
X299257Y645367D01*
X299757Y645033D01*
X300340Y644950D01*
X300923Y645117D01*
X301507Y645617D01*
G01X309873Y644950D02*
Y648283D01*
G01Y647450D02*
X310207Y647867D01*
X310707Y648200D01*
X311373Y648283D01*
X311957Y648200D01*
X312457Y647867D01*
X312707Y647283D01*
Y644950D01*
G01X316890D02*
X316390Y645033D01*
X315890Y645367D01*
X315557Y645950D01*
X315390Y646617D01*
X315557Y647283D01*
X315890Y647867D01*
X316390Y648200D01*
X316890Y648283D01*
X317390Y648200D01*
X317890Y647867D01*
X318223Y647283D01*
X318307Y646617D01*
X318223Y645950D01*
X317890Y645367D01*
X317390Y645033D01*
X316890Y644950D01*
G01X321073D02*
Y648283D01*
G01Y647450D02*
X321407Y647867D01*
X321907Y648200D01*
X322573Y648283D01*
X323157Y648200D01*
X323657Y647867D01*
X323907Y647283D01*
Y644950D01*
G01X327007Y646617D02*
X329173D01*
G01X333190Y644950D02*
Y649200D01*
X333357Y649617D01*
X333690Y649867D01*
X334190Y649950D01*
X334690Y649783D01*
X334940Y649367D01*
G01X333940Y647950D02*
X332273D01*
G01X337873Y648283D02*
Y645950D01*
X338207Y645367D01*
X338707Y645033D01*
X339290Y644950D01*
X339873Y645033D01*
X340373Y645367D01*
X340707Y645950D01*
G01Y644950D02*
Y648283D01*
G01X343473Y644950D02*
Y648283D01*
G01Y647450D02*
X343807Y647867D01*
X344307Y648200D01*
X344973Y648283D01*
X345557Y648200D01*
X346057Y647867D01*
X346307Y647283D01*
Y644950D01*
G01X351823Y647867D02*
X351240Y648200D01*
X350740Y648283D01*
X350073Y648117D01*
X349573Y647783D01*
X349240Y647200D01*
X349157Y646617D01*
X349240Y646033D01*
X349573Y645533D01*
X350073Y645117D01*
X350740Y644950D01*
X351323Y645117D01*
X351823Y645450D01*
G01X356090Y649950D02*
Y644950D01*
G01X354923Y648283D02*
X357257D01*
G01X361690D02*
Y644950D01*
G01Y649617D02*
X361523Y649700D01*
Y649867D01*
X361690Y649950D01*
X361857Y649867D01*
Y649700D01*
X361690Y649617D01*
G01X367290Y644950D02*
X366790Y645033D01*
X366290Y645367D01*
X365957Y645950D01*
X365790Y646617D01*
X365957Y647283D01*
X366290Y647867D01*
X366790Y648200D01*
X367290Y648283D01*
X367790Y648200D01*
X368290Y647867D01*
X368623Y647283D01*
X368707Y646617D01*
X368623Y645950D01*
X368290Y645367D01*
X367790Y645033D01*
X367290Y644950D01*
G01X371473D02*
Y648283D01*
G01Y647450D02*
X371807Y647867D01*
X372307Y648200D01*
X372973Y648283D01*
X373557Y648200D01*
X374057Y647867D01*
X374307Y647283D01*
Y644950D01*
G01X379990D02*
Y648283D01*
G01Y647700D02*
X379657Y648033D01*
X379157Y648200D01*
X378573Y648283D01*
X377990Y648117D01*
X377490Y647783D01*
X377157Y647283D01*
X376990Y646617D01*
X377157Y645950D01*
X377490Y645450D01*
X377990Y645117D01*
X378573Y644950D01*
X379157Y645033D01*
X379657Y645283D01*
X379990Y645617D01*
G01X384090Y644950D02*
Y649950D01*
G01X393790Y643283D02*
Y648283D01*
G01Y647533D02*
X394207Y647950D01*
X394623Y648200D01*
X395290Y648283D01*
X395873Y648200D01*
X396457Y647783D01*
X396707Y647200D01*
X396790Y646617D01*
X396707Y646033D01*
X396457Y645450D01*
X395957Y645117D01*
X395290Y644950D01*
X394707Y645033D01*
X394123Y645283D01*
X393790Y645617D01*
G01X402390Y644950D02*
Y648283D01*
G01Y647700D02*
X402057Y648033D01*
X401557Y648200D01*
X400973Y648283D01*
X400390Y648117D01*
X399890Y647783D01*
X399557Y647283D01*
X399390Y646617D01*
X399557Y645950D01*
X399890Y645450D01*
X400390Y645117D01*
X400973Y644950D01*
X401557Y645033D01*
X402057Y645283D01*
X402390Y645617D01*
G01X407990Y649950D02*
Y644950D01*
G01Y645700D02*
X407657Y645283D01*
X407157Y645033D01*
X406573Y644950D01*
X405907Y645117D01*
X405407Y645533D01*
X405073Y646033D01*
X404990Y646617D01*
X405073Y647200D01*
X405407Y647700D01*
X405907Y648117D01*
X406573Y648283D01*
X407157Y648200D01*
X407573Y648033D01*
X407990Y647700D01*
G01X417690Y648283D02*
Y644950D01*
G01Y649617D02*
X417523Y649700D01*
Y649867D01*
X417690Y649950D01*
X417857Y649867D01*
Y649700D01*
X417690Y649617D01*
G01X421873Y644950D02*
Y648283D01*
G01Y647450D02*
X422207Y647867D01*
X422707Y648200D01*
X423373Y648283D01*
X423957Y648200D01*
X424457Y647867D01*
X424707Y647283D01*
Y644950D01*
G01X435990D02*
Y648283D01*
G01Y647700D02*
X435657Y648033D01*
X435157Y648200D01*
X434573Y648283D01*
X433990Y648117D01*
X433490Y647783D01*
X433157Y647283D01*
X432990Y646617D01*
X433157Y645950D01*
X433490Y645450D01*
X433990Y645117D01*
X434573Y644950D01*
X435157Y645033D01*
X435657Y645283D01*
X435990Y645617D01*
G01X440090Y644950D02*
Y649950D01*
G01X445690Y644950D02*
Y649950D01*
G01X455390Y643283D02*
Y648283D01*
G01Y647533D02*
X455807Y647950D01*
X456223Y648200D01*
X456890Y648283D01*
X457473Y648200D01*
X458057Y647783D01*
X458307Y647200D01*
X458390Y646617D01*
X458307Y646033D01*
X458057Y645450D01*
X457557Y645117D01*
X456890Y644950D01*
X456307Y645033D01*
X455723Y645283D01*
X455390Y645617D01*
G01X461323Y644950D02*
Y648283D01*
G01Y647617D02*
X461740Y647950D01*
X462157Y648200D01*
X462740Y648283D01*
X463157Y648200D01*
X463657Y647950D01*
G01X468090Y644950D02*
X467590Y645033D01*
X467090Y645367D01*
X466757Y645950D01*
X466590Y646617D01*
X466757Y647283D01*
X467090Y647867D01*
X467590Y648200D01*
X468090Y648283D01*
X468590Y648200D01*
X469090Y647867D01*
X469423Y647283D01*
X469507Y646617D01*
X469423Y645950D01*
X469090Y645367D01*
X468590Y645033D01*
X468090Y644950D01*
G01X475190Y649950D02*
Y644950D01*
G01Y645700D02*
X474857Y645283D01*
X474357Y645033D01*
X473773Y644950D01*
X473107Y645117D01*
X472607Y645533D01*
X472273Y646033D01*
X472190Y646617D01*
X472273Y647200D01*
X472607Y647700D01*
X473107Y648117D01*
X473773Y648283D01*
X474357Y648200D01*
X474773Y648033D01*
X475190Y647700D01*
G01X477873Y648283D02*
Y645950D01*
X478207Y645367D01*
X478707Y645033D01*
X479290Y644950D01*
X479873Y645033D01*
X480373Y645367D01*
X480707Y645950D01*
G01Y644950D02*
Y648283D01*
G01X486223Y647867D02*
X485640Y648200D01*
X485140Y648283D01*
X484473Y648117D01*
X483973Y647783D01*
X483640Y647200D01*
X483557Y646617D01*
X483640Y646033D01*
X483973Y645533D01*
X484473Y645117D01*
X485140Y644950D01*
X485723Y645117D01*
X486223Y645450D01*
G01X490490Y649950D02*
Y644950D01*
G01X489323Y648283D02*
X491657D01*
G01X494840Y645533D02*
X495257Y645200D01*
X495840Y644950D01*
X496340D01*
X496840Y645117D01*
X497173Y645367D01*
X497340Y645700D01*
X497257Y646200D01*
X496923Y646450D01*
X495423Y646950D01*
X495090Y647533D01*
X495257Y647950D01*
X495590Y648200D01*
X496090Y648283D01*
X496590Y648200D01*
X497090Y647950D01*
G01X501690Y644783D02*
X501523Y644867D01*
Y645033D01*
X501690Y645117D01*
X501857Y645033D01*
Y644867D01*
X501690Y644783D01*
G01X506873Y643283D02*
X506040Y644117D01*
X505623Y644950D01*
Y648283D01*
X506040Y649117D01*
X506873Y649950D01*
G01X511890D02*
X513890D01*
G01X512890D02*
Y644950D01*
G01X511890D02*
X513890D01*
G01X517240Y645533D02*
X517657Y645200D01*
X518240Y644950D01*
X518740D01*
X519240Y645117D01*
X519573Y645367D01*
X519740Y645700D01*
X519657Y646200D01*
X519323Y646450D01*
X517823Y646950D01*
X517490Y647533D01*
X517657Y647950D01*
X517990Y648200D01*
X518490Y648283D01*
X518990Y648200D01*
X519490Y647950D01*
G01X524090Y644950D02*
X523590Y645033D01*
X523090Y645367D01*
X522757Y645950D01*
X522590Y646617D01*
X522757Y647283D01*
X523090Y647867D01*
X523590Y648200D01*
X524090Y648283D01*
X524590Y648200D01*
X525090Y647867D01*
X525423Y647283D01*
X525507Y646617D01*
X525423Y645950D01*
X525090Y645367D01*
X524590Y645033D01*
X524090Y644950D01*
G01X529690D02*
Y649950D01*
G01X536790Y644950D02*
Y648283D01*
G01Y647700D02*
X536457Y648033D01*
X535957Y648200D01*
X535373Y648283D01*
X534790Y648117D01*
X534290Y647783D01*
X533957Y647283D01*
X533790Y646617D01*
X533957Y645950D01*
X534290Y645450D01*
X534790Y645117D01*
X535373Y644950D01*
X535957Y645033D01*
X536457Y645283D01*
X536790Y645617D01*
G01X540890Y649950D02*
Y644950D01*
G01X539723Y648283D02*
X542057D01*
G01X545240Y647200D02*
X547907D01*
X547657Y647783D01*
X547240Y648117D01*
X546657Y648283D01*
X546073Y648200D01*
X545573Y647950D01*
X545240Y647367D01*
X545073Y646867D01*
Y646367D01*
X545240Y645867D01*
X545657Y645367D01*
X546157Y645033D01*
X546740Y644950D01*
X547323Y645117D01*
X547907Y645617D01*
G01X556190Y643283D02*
Y648283D01*
G01Y647533D02*
X556607Y647950D01*
X557023Y648200D01*
X557690Y648283D01*
X558273Y648200D01*
X558857Y647783D01*
X559107Y647200D01*
X559190Y646617D01*
X559107Y646033D01*
X558857Y645450D01*
X558357Y645117D01*
X557690Y644950D01*
X557107Y645033D01*
X556523Y645283D01*
X556190Y645617D01*
G01X564790Y644950D02*
Y648283D01*
G01Y647700D02*
X564457Y648033D01*
X563957Y648200D01*
X563373Y648283D01*
X562790Y648117D01*
X562290Y647783D01*
X561957Y647283D01*
X561790Y646617D01*
X561957Y645950D01*
X562290Y645450D01*
X562790Y645117D01*
X563373Y644950D01*
X563957Y645033D01*
X564457Y645283D01*
X564790Y645617D01*
G01X570390Y649950D02*
Y644950D01*
G01Y645700D02*
X570057Y645283D01*
X569557Y645033D01*
X568973Y644950D01*
X568307Y645117D01*
X567807Y645533D01*
X567473Y646033D01*
X567390Y646617D01*
X567473Y647200D01*
X567807Y647700D01*
X568307Y648117D01*
X568973Y648283D01*
X569557Y648200D01*
X569973Y648033D01*
X570390Y647700D01*
G01X270833Y575000D02*
Y580000D01*
X272833D01*
X273500Y579750D01*
X274000Y579167D01*
X274167Y578500D01*
X274000Y577833D01*
X273583Y577333D01*
X272833Y577083D01*
X270833D01*
G01X278100Y575000D02*
Y580000D01*
G01X282283Y578333D02*
Y576000D01*
X282617Y575417D01*
X283117Y575083D01*
X283700Y575000D01*
X284283Y575083D01*
X284783Y575417D01*
X285117Y576000D01*
G01Y575000D02*
Y578333D01*
G01X288133Y573750D02*
X288717Y573417D01*
X289383Y573333D01*
X289967Y573417D01*
X290467Y573833D01*
X290800Y574417D01*
Y578333D01*
G01Y577667D02*
X290467Y578000D01*
X289967Y578250D01*
X289383Y578333D01*
X288717Y578167D01*
X288300Y577833D01*
X287967Y577250D01*
X287800Y576667D01*
X287883Y576167D01*
X288217Y575583D01*
X288717Y575167D01*
X289383Y575000D01*
X289883Y575083D01*
X290467Y575417D01*
X290800Y575750D01*
G01X293733Y573750D02*
X294317Y573417D01*
X294983Y573333D01*
X295567Y573417D01*
X296067Y573833D01*
X296400Y574417D01*
Y578333D01*
G01Y577667D02*
X296067Y578000D01*
X295567Y578250D01*
X294983Y578333D01*
X294317Y578167D01*
X293900Y577833D01*
X293567Y577250D01*
X293400Y576667D01*
X293483Y576167D01*
X293817Y575583D01*
X294317Y575167D01*
X294983Y575000D01*
X295483Y575083D01*
X296067Y575417D01*
X296400Y575750D01*
G01X299250Y577250D02*
X301917D01*
X301667Y577833D01*
X301250Y578167D01*
X300667Y578333D01*
X300083Y578250D01*
X299583Y578000D01*
X299250Y577417D01*
X299083Y576917D01*
Y576417D01*
X299250Y575917D01*
X299667Y575417D01*
X300167Y575083D01*
X300750Y575000D01*
X301333Y575167D01*
X301917Y575667D01*
G01X307600Y580000D02*
Y575000D01*
G01Y575750D02*
X307267Y575333D01*
X306767Y575083D01*
X306183Y575000D01*
X305517Y575167D01*
X305017Y575583D01*
X304683Y576083D01*
X304600Y576667D01*
X304683Y577250D01*
X305017Y577750D01*
X305517Y578167D01*
X306183Y578333D01*
X306767Y578250D01*
X307183Y578083D01*
X307600Y577750D01*
G01X315217Y580000D02*
X317300Y575000D01*
X319383Y580000D01*
G01X322900Y578333D02*
Y575000D01*
G01Y579667D02*
X322733Y579750D01*
Y579917D01*
X322900Y580000D01*
X323067Y579917D01*
Y579750D01*
X322900Y579667D01*
G01X330000Y575000D02*
Y578333D01*
G01Y577750D02*
X329667Y578083D01*
X329167Y578250D01*
X328583Y578333D01*
X328000Y578167D01*
X327500Y577833D01*
X327167Y577333D01*
X327000Y576667D01*
X327167Y576000D01*
X327500Y575500D01*
X328000Y575167D01*
X328583Y575000D01*
X329167Y575083D01*
X329667Y575333D01*
X330000Y575667D01*
G01X333683Y573333D02*
X332850Y574167D01*
X332433Y575000D01*
Y578333D01*
X332850Y579167D01*
X333683Y580000D01*
G01X338283Y575000D02*
Y580000D01*
G01Y577583D02*
X338700Y578000D01*
X339117Y578250D01*
X339783Y578333D01*
X340283Y578250D01*
X340867Y577917D01*
X341117Y577417D01*
Y575000D01*
G01X345300D02*
X344800Y575083D01*
X344300Y575417D01*
X343967Y576000D01*
X343800Y576667D01*
X343967Y577333D01*
X344300Y577917D01*
X344800Y578250D01*
X345300Y578333D01*
X345800Y578250D01*
X346300Y577917D01*
X346633Y577333D01*
X346717Y576667D01*
X346633Y576000D01*
X346300Y575417D01*
X345800Y575083D01*
X345300Y575000D01*
G01X350900D02*
Y580000D01*
G01X355250Y577250D02*
X357917D01*
X357667Y577833D01*
X357250Y578167D01*
X356667Y578333D01*
X356083Y578250D01*
X355583Y578000D01*
X355250Y577417D01*
X355083Y576917D01*
Y576417D01*
X355250Y575917D01*
X355667Y575417D01*
X356167Y575083D01*
X356750Y575000D01*
X357333Y575167D01*
X357917Y575667D01*
G01X366450Y575583D02*
X366867Y575250D01*
X367450Y575000D01*
X367950D01*
X368450Y575167D01*
X368783Y575417D01*
X368950Y575750D01*
X368867Y576250D01*
X368533Y576500D01*
X367033Y577000D01*
X366700Y577583D01*
X366867Y578000D01*
X367200Y578250D01*
X367700Y578333D01*
X368200Y578250D01*
X368700Y578000D01*
G01X373300Y578333D02*
Y575000D01*
G01Y579667D02*
X373133Y579750D01*
Y579917D01*
X373300Y580000D01*
X373467Y579917D01*
Y579750D01*
X373300Y579667D01*
G01X377650Y578333D02*
X380150D01*
X377650Y575000D01*
X380150D01*
G01X383250Y577250D02*
X385917D01*
X385667Y577833D01*
X385250Y578167D01*
X384667Y578333D01*
X384083Y578250D01*
X383583Y578000D01*
X383250Y577417D01*
X383083Y576917D01*
Y576417D01*
X383250Y575917D01*
X383667Y575417D01*
X384167Y575083D01*
X384750Y575000D01*
X385333Y575167D01*
X385917Y575667D01*
G01X391767Y575000D02*
X388433Y576667D01*
X391767Y578333D01*
G01X395700Y575000D02*
Y580000D01*
X394700Y579000D01*
G01Y575000D02*
X396700D01*
G01X399717Y577083D02*
X400300Y577667D01*
X400800Y578000D01*
X401467Y578167D01*
X402050Y578000D01*
X402467Y577667D01*
X402800Y577167D01*
X402883Y576583D01*
X402800Y576083D01*
X402467Y575583D01*
X401967Y575167D01*
X401383Y575000D01*
X400717Y575167D01*
X400133Y575667D01*
X399800Y576417D01*
X399717Y577250D01*
X399883Y578333D01*
X400133Y578917D01*
X400550Y579500D01*
X401133Y579917D01*
X401717Y580000D01*
X402300Y579833D01*
X402717Y579417D01*
G01X410000Y575000D02*
Y578333D01*
G01Y577417D02*
X410250Y577833D01*
X410667Y578167D01*
X411250Y578333D01*
X411833Y578167D01*
X412250Y577833D01*
X412500Y577417D01*
Y575000D01*
G01Y577417D02*
X412750Y577833D01*
X413167Y578167D01*
X413750Y578333D01*
X414333Y578167D01*
X414750Y577833D01*
X415000Y577333D01*
Y575000D01*
G01X418100Y578333D02*
Y575000D01*
G01Y579667D02*
X417933Y579750D01*
Y579917D01*
X418100Y580000D01*
X418267Y579917D01*
Y579750D01*
X418100Y579667D01*
G01X423700Y575000D02*
Y580000D01*
G01X429717Y573333D02*
X430550Y574167D01*
X430967Y575000D01*
Y578333D01*
X430550Y579167D01*
X429717Y580000D01*
G01X322623Y303963D02*
X322890Y304163D01*
X323090Y304497D01*
X323223Y304963D01*
X323090Y305363D01*
X322823Y305630D01*
X322357Y305830D01*
X320557D01*
Y301830D01*
X322757D01*
X323223Y302097D01*
X323490Y302497D01*
X323623Y302963D01*
X323490Y303430D01*
X323090Y303830D01*
X322623Y303963D01*
X320557D01*
G01X320423Y351330D02*
X322090Y355330D01*
X323757Y351330D01*
G01X323157Y352730D02*
X321023D01*
G01X361117Y328537D02*
X360717Y328737D01*
X360250Y328870D01*
X359717D01*
X359117Y328670D01*
X358650Y328337D01*
X358317Y327937D01*
X358050Y327270D01*
X357983Y326670D01*
X358117Y326070D01*
X358317Y325670D01*
X358717Y325270D01*
X359183Y325003D01*
X359650Y324870D01*
X360117D01*
X360583Y325003D01*
X360983Y325203D01*
X361317Y325470D01*
G01X395000Y364500D02*
Y175500D01*
G01X402977Y229887D02*
X403310Y230137D01*
X403560Y230553D01*
X403727Y231137D01*
X403560Y231637D01*
X403227Y231970D01*
X402643Y232220D01*
X400393D01*
Y227220D01*
X403143D01*
X403727Y227553D01*
X404060Y228053D01*
X404227Y228637D01*
X404060Y229220D01*
X403560Y229720D01*
X402977Y229887D01*
X400393D01*
G01X406493Y230553D02*
Y228220D01*
X406827Y227637D01*
X407327Y227303D01*
X407910Y227220D01*
X408493Y227303D01*
X408993Y227637D01*
X409327Y228220D01*
G01Y227220D02*
Y230553D01*
G01X411010Y227220D02*
Y230553D01*
G01Y229637D02*
X411260Y230053D01*
X411677Y230387D01*
X412260Y230553D01*
X412843Y230387D01*
X413260Y230053D01*
X413510Y229637D01*
Y227220D01*
G01Y229637D02*
X413760Y230053D01*
X414177Y230387D01*
X414760Y230553D01*
X415343Y230387D01*
X415760Y230053D01*
X416010Y229553D01*
Y227220D01*
G01X417610Y225553D02*
Y230553D01*
G01Y229803D02*
X418027Y230220D01*
X418443Y230470D01*
X419110Y230553D01*
X419693Y230470D01*
X420277Y230053D01*
X420527Y229470D01*
X420610Y228887D01*
X420527Y228303D01*
X420277Y227720D01*
X419777Y227387D01*
X419110Y227220D01*
X418527Y227303D01*
X417943Y227553D01*
X417610Y227887D01*
G01X401520Y268213D02*
X403020Y264880D01*
X404520Y268213D01*
G01X408620D02*
Y264880D01*
G01Y269547D02*
X408453Y269630D01*
Y269797D01*
X408620Y269880D01*
X408787Y269797D01*
Y269630D01*
X408620Y269547D01*
G01X415720Y264880D02*
Y268213D01*
G01Y267630D02*
X415387Y267963D01*
X414887Y268130D01*
X414303Y268213D01*
X413720Y268047D01*
X413220Y267713D01*
X412887Y267213D01*
X412720Y266547D01*
X412887Y265880D01*
X413220Y265380D01*
X413720Y265047D01*
X414303Y264880D01*
X414887Y264963D01*
X415387Y265213D01*
X415720Y265547D01*
G01X401067Y277360D02*
Y282360D01*
X402733D01*
X403400Y282110D01*
X403900Y281777D01*
X404317Y281277D01*
X404650Y280693D01*
X404733Y279860D01*
X404650Y279027D01*
X404317Y278443D01*
X403900Y277943D01*
X403400Y277610D01*
X402733Y277360D01*
X401067D01*
G01X408500Y280693D02*
Y277360D01*
G01Y282027D02*
X408333Y282110D01*
Y282277D01*
X408500Y282360D01*
X408667Y282277D01*
Y282110D01*
X408500Y282027D01*
G01X411600Y277360D02*
Y280693D01*
G01Y279777D02*
X411850Y280193D01*
X412267Y280527D01*
X412850Y280693D01*
X413433Y280527D01*
X413850Y280193D01*
X414100Y279777D01*
Y277360D01*
G01Y279777D02*
X414350Y280193D01*
X414767Y280527D01*
X415350Y280693D01*
X415933Y280527D01*
X416350Y280193D01*
X416600Y279693D01*
Y277360D01*
G01X418200Y275693D02*
Y280693D01*
G01Y279943D02*
X418617Y280360D01*
X419033Y280610D01*
X419700Y280693D01*
X420283Y280610D01*
X420867Y280193D01*
X421117Y279610D01*
X421200Y279027D01*
X421117Y278443D01*
X420867Y277860D01*
X420367Y277527D01*
X419700Y277360D01*
X419117Y277443D01*
X418533Y277693D01*
X418200Y278027D01*
G01X425300Y277360D02*
Y282360D01*
G01X429650Y279610D02*
X432317D01*
X432067Y280193D01*
X431650Y280527D01*
X431067Y280693D01*
X430483Y280610D01*
X429983Y280360D01*
X429650Y279777D01*
X429483Y279277D01*
Y278777D01*
X429650Y278277D01*
X430067Y277777D01*
X430567Y277443D01*
X431150Y277360D01*
X431733Y277527D01*
X432317Y278027D01*
G01X441600Y277360D02*
Y281610D01*
X441767Y282027D01*
X442100Y282277D01*
X442600Y282360D01*
X443100Y282193D01*
X443350Y281777D01*
G01X442350Y280360D02*
X440683D01*
G01X447700Y277360D02*
X447200Y277443D01*
X446700Y277777D01*
X446367Y278360D01*
X446200Y279027D01*
X446367Y279693D01*
X446700Y280277D01*
X447200Y280610D01*
X447700Y280693D01*
X448200Y280610D01*
X448700Y280277D01*
X449033Y279693D01*
X449117Y279027D01*
X449033Y278360D01*
X448700Y277777D01*
X448200Y277443D01*
X447700Y277360D01*
G01X452133D02*
Y280693D01*
G01Y280027D02*
X452550Y280360D01*
X452967Y280610D01*
X453550Y280693D01*
X453967Y280610D01*
X454467Y280360D01*
G01X464500Y277360D02*
X464000Y277443D01*
X463500Y277777D01*
X463167Y278360D01*
X463000Y279027D01*
X463167Y279693D01*
X463500Y280277D01*
X464000Y280610D01*
X464500Y280693D01*
X465000Y280610D01*
X465500Y280277D01*
X465833Y279693D01*
X465917Y279027D01*
X465833Y278360D01*
X465500Y277777D01*
X465000Y277443D01*
X464500Y277360D01*
G01X468683Y280693D02*
Y278360D01*
X469017Y277777D01*
X469517Y277443D01*
X470100Y277360D01*
X470683Y277443D01*
X471183Y277777D01*
X471517Y278360D01*
G01Y277360D02*
Y280693D01*
G01X475700Y282360D02*
Y277360D01*
G01X474533Y280693D02*
X476867D01*
G01X480050Y279610D02*
X482717D01*
X482467Y280193D01*
X482050Y280527D01*
X481467Y280693D01*
X480883Y280610D01*
X480383Y280360D01*
X480050Y279777D01*
X479883Y279277D01*
Y278777D01*
X480050Y278277D01*
X480467Y277777D01*
X480967Y277443D01*
X481550Y277360D01*
X482133Y277527D01*
X482717Y278027D01*
G01X485733Y277360D02*
Y280693D01*
G01Y280027D02*
X486150Y280360D01*
X486567Y280610D01*
X487150Y280693D01*
X487567Y280610D01*
X488067Y280360D01*
G01X499600Y277360D02*
Y280693D01*
G01Y280110D02*
X499267Y280443D01*
X498767Y280610D01*
X498183Y280693D01*
X497600Y280527D01*
X497100Y280193D01*
X496767Y279693D01*
X496600Y279027D01*
X496767Y278360D01*
X497100Y277860D01*
X497600Y277527D01*
X498183Y277360D01*
X498767Y277443D01*
X499267Y277693D01*
X499600Y278027D01*
G01X502283Y277360D02*
Y280693D01*
G01Y279860D02*
X502617Y280277D01*
X503117Y280610D01*
X503783Y280693D01*
X504367Y280610D01*
X504867Y280277D01*
X505117Y279693D01*
Y277360D01*
G01X510800Y282360D02*
Y277360D01*
G01Y278110D02*
X510467Y277693D01*
X509967Y277443D01*
X509383Y277360D01*
X508717Y277527D01*
X508217Y277943D01*
X507883Y278443D01*
X507800Y279027D01*
X507883Y279610D01*
X508217Y280110D01*
X508717Y280527D01*
X509383Y280693D01*
X509967Y280610D01*
X510383Y280443D01*
X510800Y280110D01*
G01X520500Y280693D02*
Y277360D01*
G01Y282027D02*
X520333Y282110D01*
Y282277D01*
X520500Y282360D01*
X520667Y282277D01*
Y282110D01*
X520500Y282027D01*
G01X524683Y277360D02*
Y280693D01*
G01Y279860D02*
X525017Y280277D01*
X525517Y280610D01*
X526183Y280693D01*
X526767Y280610D01*
X527267Y280277D01*
X527517Y279693D01*
Y277360D01*
G01X530283D02*
Y280693D01*
G01Y279860D02*
X530617Y280277D01*
X531117Y280610D01*
X531783Y280693D01*
X532367Y280610D01*
X532867Y280277D01*
X533117Y279693D01*
Y277360D01*
G01X536050Y279610D02*
X538717D01*
X538467Y280193D01*
X538050Y280527D01*
X537467Y280693D01*
X536883Y280610D01*
X536383Y280360D01*
X536050Y279777D01*
X535883Y279277D01*
Y278777D01*
X536050Y278277D01*
X536467Y277777D01*
X536967Y277443D01*
X537550Y277360D01*
X538133Y277527D01*
X538717Y278027D01*
G01X541733Y277360D02*
Y280693D01*
G01Y280027D02*
X542150Y280360D01*
X542567Y280610D01*
X543150Y280693D01*
X543567Y280610D01*
X544067Y280360D01*
G01X554100Y277360D02*
Y282360D01*
G01X561200Y277360D02*
Y280693D01*
G01Y280110D02*
X560867Y280443D01*
X560367Y280610D01*
X559783Y280693D01*
X559200Y280527D01*
X558700Y280193D01*
X558367Y279693D01*
X558200Y279027D01*
X558367Y278360D01*
X558700Y277860D01*
X559200Y277527D01*
X559783Y277360D01*
X560367Y277443D01*
X560867Y277693D01*
X561200Y278027D01*
G01X564050Y277943D02*
X564467Y277610D01*
X565050Y277360D01*
X565550D01*
X566050Y277527D01*
X566383Y277777D01*
X566550Y278110D01*
X566467Y278610D01*
X566133Y278860D01*
X564633Y279360D01*
X564300Y279943D01*
X564467Y280360D01*
X564800Y280610D01*
X565300Y280693D01*
X565800Y280610D01*
X566300Y280360D01*
G01X569650Y279610D02*
X572317D01*
X572067Y280193D01*
X571650Y280527D01*
X571067Y280693D01*
X570483Y280610D01*
X569983Y280360D01*
X569650Y279777D01*
X569483Y279277D01*
Y278777D01*
X569650Y278277D01*
X570067Y277777D01*
X570567Y277443D01*
X571150Y277360D01*
X571733Y277527D01*
X572317Y278027D01*
G01X575333Y277360D02*
Y280693D01*
G01Y280027D02*
X575750Y280360D01*
X576167Y280610D01*
X576750Y280693D01*
X577167Y280610D01*
X577667Y280360D01*
G01X444197Y299927D02*
X443797Y300127D01*
X443330Y300260D01*
X442797D01*
X442197Y300060D01*
X441730Y299727D01*
X441397Y299327D01*
X441130Y298660D01*
X441063Y298060D01*
X441197Y297460D01*
X441397Y297060D01*
X441797Y296660D01*
X442263Y296393D01*
X442730Y296260D01*
X443197D01*
X443663Y296393D01*
X444063Y296593D01*
X444397Y296860D01*
G01X401827Y295540D02*
X403910Y300540D01*
X405993Y295540D01*
G01X405243Y297290D02*
X402577D01*
G01X408093Y295540D02*
Y298873D01*
G01Y298040D02*
X408427Y298457D01*
X408927Y298790D01*
X409593Y298873D01*
X410177Y298790D01*
X410677Y298457D01*
X410927Y297873D01*
Y295540D01*
G01X413943Y294290D02*
X414527Y293957D01*
X415193Y293873D01*
X415777Y293957D01*
X416277Y294373D01*
X416610Y294957D01*
Y298873D01*
G01Y298207D02*
X416277Y298540D01*
X415777Y298790D01*
X415193Y298873D01*
X414527Y298707D01*
X414110Y298373D01*
X413777Y297790D01*
X413610Y297207D01*
X413693Y296707D01*
X414027Y296123D01*
X414527Y295707D01*
X415193Y295540D01*
X415693Y295623D01*
X416277Y295957D01*
X416610Y296290D01*
G01X420710Y295540D02*
Y300540D01*
G01X425060Y297790D02*
X427727D01*
X427477Y298373D01*
X427060Y298707D01*
X426477Y298873D01*
X425893Y298790D01*
X425393Y298540D01*
X425060Y297957D01*
X424893Y297457D01*
Y296957D01*
X425060Y296457D01*
X425477Y295957D01*
X425977Y295623D01*
X426560Y295540D01*
X427143Y295707D01*
X427727Y296207D01*
G01X431493Y293873D02*
X430660Y294707D01*
X430243Y295540D01*
Y298873D01*
X430660Y299707D01*
X431493Y300540D01*
G01X449127Y293873D02*
X449960Y294707D01*
X450377Y295540D01*
Y298873D01*
X449960Y299707D01*
X449127Y300540D01*
G01X401777Y331927D02*
X402110Y332177D01*
X402360Y332593D01*
X402527Y333177D01*
X402360Y333677D01*
X402027Y334010D01*
X401443Y334260D01*
X399193D01*
Y329260D01*
X401943D01*
X402527Y329593D01*
X402860Y330093D01*
X403027Y330677D01*
X402860Y331260D01*
X402360Y331760D01*
X401777Y331927D01*
X399193D01*
G01X405210Y329093D02*
X408210Y334260D01*
G01X410227Y329260D02*
X412310Y334260D01*
X414393Y329260D01*
G01X413643Y331010D02*
X410977D01*
G01X400633Y358960D02*
Y353960D01*
X403967D01*
G01X409400D02*
Y357293D01*
G01Y356710D02*
X409067Y357043D01*
X408567Y357210D01*
X407983Y357293D01*
X407400Y357127D01*
X406900Y356793D01*
X406567Y356293D01*
X406400Y355627D01*
X406567Y354960D01*
X406900Y354460D01*
X407400Y354127D01*
X407983Y353960D01*
X408567Y354043D01*
X409067Y354293D01*
X409400Y354627D01*
G01X412250Y354543D02*
X412667Y354210D01*
X413250Y353960D01*
X413750D01*
X414250Y354127D01*
X414583Y354377D01*
X414750Y354710D01*
X414667Y355210D01*
X414333Y355460D01*
X412833Y355960D01*
X412500Y356543D01*
X412667Y356960D01*
X413000Y357210D01*
X413500Y357293D01*
X414000Y357210D01*
X414500Y356960D01*
G01X417850Y356210D02*
X420517D01*
X420267Y356793D01*
X419850Y357127D01*
X419267Y357293D01*
X418683Y357210D01*
X418183Y356960D01*
X417850Y356377D01*
X417683Y355877D01*
Y355377D01*
X417850Y354877D01*
X418267Y354377D01*
X418767Y354043D01*
X419350Y353960D01*
X419933Y354127D01*
X420517Y354627D01*
G01X423533Y353960D02*
Y357293D01*
G01Y356627D02*
X423950Y356960D01*
X424367Y357210D01*
X424950Y357293D01*
X425367Y357210D01*
X425867Y356960D01*
G01X434400Y357293D02*
X435900Y353960D01*
X437400Y357293D01*
G01X441500D02*
Y353960D01*
G01Y358627D02*
X441333Y358710D01*
Y358877D01*
X441500Y358960D01*
X441667Y358877D01*
Y358710D01*
X441500Y358627D01*
G01X448600Y353960D02*
Y357293D01*
G01Y356710D02*
X448267Y357043D01*
X447767Y357210D01*
X447183Y357293D01*
X446600Y357127D01*
X446100Y356793D01*
X445767Y356293D01*
X445600Y355627D01*
X445767Y354960D01*
X446100Y354460D01*
X446600Y354127D01*
X447183Y353960D01*
X447767Y354043D01*
X448267Y354293D01*
X448600Y354627D01*
G01X457050Y354543D02*
X457467Y354210D01*
X458050Y353960D01*
X458550D01*
X459050Y354127D01*
X459383Y354377D01*
X459550Y354710D01*
X459467Y355210D01*
X459133Y355460D01*
X457633Y355960D01*
X457300Y356543D01*
X457467Y356960D01*
X457800Y357210D01*
X458300Y357293D01*
X458800Y357210D01*
X459300Y356960D01*
G01X463900Y357293D02*
Y353960D01*
G01Y358627D02*
X463733Y358710D01*
Y358877D01*
X463900Y358960D01*
X464067Y358877D01*
Y358710D01*
X463900Y358627D01*
G01X468250Y357293D02*
X470750D01*
X468250Y353960D01*
X470750D01*
G01X473850Y356210D02*
X476517D01*
X476267Y356793D01*
X475850Y357127D01*
X475267Y357293D01*
X474683Y357210D01*
X474183Y356960D01*
X473850Y356377D01*
X473683Y355877D01*
Y355377D01*
X473850Y354877D01*
X474267Y354377D01*
X474767Y354043D01*
X475350Y353960D01*
X475933Y354127D01*
X476517Y354627D01*
G01X484217Y357293D02*
X485217Y353960D01*
X486300Y357293D01*
X487383Y353960D01*
X488383Y357293D01*
G01X491900D02*
Y353960D01*
G01Y358627D02*
X491733Y358710D01*
Y358877D01*
X491900Y358960D01*
X492067Y358877D01*
Y358710D01*
X491900Y358627D01*
G01X497500Y358960D02*
Y353960D01*
G01X496333Y357293D02*
X498667D01*
G01X501683Y353960D02*
Y358960D01*
G01Y356543D02*
X502100Y356960D01*
X502517Y357210D01*
X503183Y357293D01*
X503683Y357210D01*
X504267Y356877D01*
X504517Y356377D01*
Y353960D01*
G01X508700D02*
X508200Y354043D01*
X507700Y354377D01*
X507367Y354960D01*
X507200Y355627D01*
X507367Y356293D01*
X507700Y356877D01*
X508200Y357210D01*
X508700Y357293D01*
X509200Y357210D01*
X509700Y356877D01*
X510033Y356293D01*
X510117Y355627D01*
X510033Y354960D01*
X509700Y354377D01*
X509200Y354043D01*
X508700Y353960D01*
G01X512883Y357293D02*
Y354960D01*
X513217Y354377D01*
X513717Y354043D01*
X514300Y353960D01*
X514883Y354043D01*
X515383Y354377D01*
X515717Y354960D01*
G01Y353960D02*
Y357293D01*
G01X519900Y358960D02*
Y353960D01*
G01X518733Y357293D02*
X521067D01*
G01X529600Y352293D02*
Y357293D01*
G01Y356543D02*
X530017Y356960D01*
X530433Y357210D01*
X531100Y357293D01*
X531683Y357210D01*
X532267Y356793D01*
X532517Y356210D01*
X532600Y355627D01*
X532517Y355043D01*
X532267Y354460D01*
X531767Y354127D01*
X531100Y353960D01*
X530517Y354043D01*
X529933Y354293D01*
X529600Y354627D01*
G01X536700Y353960D02*
Y358960D01*
G01X543800Y353960D02*
Y357293D01*
G01Y356710D02*
X543467Y357043D01*
X542967Y357210D01*
X542383Y357293D01*
X541800Y357127D01*
X541300Y356793D01*
X540967Y356293D01*
X540800Y355627D01*
X540967Y354960D01*
X541300Y354460D01*
X541800Y354127D01*
X542383Y353960D01*
X542967Y354043D01*
X543467Y354293D01*
X543800Y354627D01*
G01X547900Y358960D02*
Y353960D01*
G01X546733Y357293D02*
X549067D01*
G01X553500D02*
Y353960D01*
G01Y358627D02*
X553333Y358710D01*
Y358877D01*
X553500Y358960D01*
X553667Y358877D01*
Y358710D01*
X553500Y358627D01*
G01X557683Y353960D02*
Y357293D01*
G01Y356460D02*
X558017Y356877D01*
X558517Y357210D01*
X559183Y357293D01*
X559767Y357210D01*
X560267Y356877D01*
X560517Y356293D01*
Y353960D01*
G01X563533Y352710D02*
X564117Y352377D01*
X564783Y352293D01*
X565367Y352377D01*
X565867Y352793D01*
X566200Y353377D01*
Y357293D01*
G01Y356627D02*
X565867Y356960D01*
X565367Y357210D01*
X564783Y357293D01*
X564117Y357127D01*
X563700Y356793D01*
X563367Y356210D01*
X563200Y355627D01*
X563283Y355127D01*
X563617Y354543D01*
X564117Y354127D01*
X564783Y353960D01*
X565283Y354043D01*
X565867Y354377D01*
X566200Y354710D01*
G01X575483Y352293D02*
X574650Y353127D01*
X574233Y353960D01*
Y357293D01*
X574650Y358127D01*
X575483Y358960D01*
G01X582167Y356627D02*
X582500Y356877D01*
X582750Y357293D01*
X582917Y357877D01*
X582750Y358377D01*
X582417Y358710D01*
X581833Y358960D01*
X579583D01*
Y353960D01*
X582333D01*
X582917Y354293D01*
X583250Y354793D01*
X583417Y355377D01*
X583250Y355960D01*
X582750Y356460D01*
X582167Y356627D01*
X579583D01*
G01X587517Y352293D02*
X588350Y353127D01*
X588767Y353960D01*
Y357293D01*
X588350Y358127D01*
X587517Y358960D01*
G01X395000Y305500D02*
X694500D01*
G01X395000Y337500D02*
X694500D01*
G01X404500Y666833D02*
Y663500D01*
G01Y668167D02*
X404333Y668250D01*
Y668417D01*
X404500Y668500D01*
X404667Y668417D01*
Y668250D01*
X404500Y668167D01*
G01X410100Y668500D02*
Y663500D01*
G01X408933Y666833D02*
X411267D01*
G01X414450Y665750D02*
X417117D01*
X416867Y666333D01*
X416450Y666667D01*
X415867Y666833D01*
X415283Y666750D01*
X414783Y666500D01*
X414450Y665917D01*
X414283Y665417D01*
Y664917D01*
X414450Y664417D01*
X414867Y663917D01*
X415367Y663583D01*
X415950Y663500D01*
X416533Y663667D01*
X417117Y664167D01*
G01X418800Y663500D02*
Y666833D01*
G01Y665917D02*
X419050Y666333D01*
X419467Y666667D01*
X420050Y666833D01*
X420633Y666667D01*
X421050Y666333D01*
X421300Y665917D01*
Y663500D01*
G01Y665917D02*
X421550Y666333D01*
X421967Y666667D01*
X422550Y666833D01*
X423133Y666667D01*
X423550Y666333D01*
X423800Y665833D01*
Y663500D01*
G01X606583Y-1833D02*
X608583D01*
G01X607500Y-750D02*
Y-2917D01*
G01X611600Y-3667D02*
X614600Y1500D01*
G01X617617Y-1833D02*
X619783D01*
G01X624300Y-3500D02*
Y1500D01*
X623300Y500D01*
G01Y-3500D02*
X625300D01*
G01X627400D02*
Y-167D01*
G01Y-1083D02*
X627650Y-667D01*
X628067Y-333D01*
X628650Y-167D01*
X629233Y-333D01*
X629650Y-667D01*
X629900Y-1083D01*
Y-3500D01*
G01Y-1083D02*
X630150Y-667D01*
X630567Y-333D01*
X631150Y-167D01*
X631733Y-333D01*
X632150Y-667D01*
X632400Y-1167D01*
Y-3500D01*
G01X635500Y-167D02*
Y-3500D01*
G01Y1167D02*
X635333Y1250D01*
Y1417D01*
X635500Y1500D01*
X635667Y1417D01*
Y1250D01*
X635500Y1167D01*
G01X641100Y-3500D02*
Y1500D01*
G01X607500Y-15000D02*
X606833Y-15167D01*
X606333Y-15583D01*
X606000Y-16083D01*
X605750Y-16750D01*
X605667Y-17500D01*
X605750Y-18250D01*
X606000Y-18917D01*
X606333Y-19417D01*
X606833Y-19833D01*
X607500Y-20000D01*
X608167Y-19833D01*
X608667Y-19417D01*
X609000Y-18917D01*
X609250Y-18250D01*
X609333Y-17500D01*
X609250Y-16750D01*
X609000Y-16083D01*
X608667Y-15583D01*
X608167Y-15167D01*
X607500Y-15000D01*
G01X613100Y-20167D02*
X612933Y-20083D01*
Y-19917D01*
X613100Y-19833D01*
X613267Y-19917D01*
Y-20083D01*
X613100Y-20167D01*
G01X616867Y-19000D02*
X617367Y-19583D01*
X618033Y-19917D01*
X618783Y-20000D01*
X619450Y-19917D01*
X620117Y-19500D01*
X620533Y-19000D01*
X620617Y-18500D01*
X620450Y-17917D01*
X619867Y-17500D01*
X619283Y-17333D01*
X618533D01*
G01X619283D02*
X619783Y-17083D01*
X620200Y-16667D01*
X620367Y-16167D01*
X620200Y-15667D01*
X619783Y-15250D01*
X619033Y-15000D01*
X618283Y-15083D01*
X617533Y-15417D01*
G01X621800Y-18333D02*
X622633Y-16667D01*
X623467D01*
X625133Y-20000D01*
X625967D01*
X626800Y-18333D01*
G01X629900Y-15000D02*
X629233Y-15167D01*
X628733Y-15583D01*
X628400Y-16083D01*
X628150Y-16750D01*
X628067Y-17500D01*
X628150Y-18250D01*
X628400Y-18917D01*
X628733Y-19417D01*
X629233Y-19833D01*
X629900Y-20000D01*
X630567Y-19833D01*
X631067Y-19417D01*
X631400Y-18917D01*
X631650Y-18250D01*
X631733Y-17500D01*
X631650Y-16750D01*
X631400Y-16083D01*
X631067Y-15583D01*
X630567Y-15167D01*
X629900Y-15000D01*
G01X635500Y-20167D02*
X635333Y-20083D01*
Y-19917D01*
X635500Y-19833D01*
X635667Y-19917D01*
Y-20083D01*
X635500Y-20167D01*
G01X640933Y-20000D02*
X641100Y-18917D01*
X641350Y-18000D01*
X641683Y-17167D01*
X642100Y-16250D01*
X642767Y-15000D01*
X639433D01*
G01X644200Y-20000D02*
Y-16667D01*
G01Y-17583D02*
X644450Y-17167D01*
X644867Y-16833D01*
X645450Y-16667D01*
X646033Y-16833D01*
X646450Y-17167D01*
X646700Y-17583D01*
Y-20000D01*
G01Y-17583D02*
X646950Y-17167D01*
X647367Y-16833D01*
X647950Y-16667D01*
X648533Y-16833D01*
X648950Y-17167D01*
X649200Y-17667D01*
Y-20000D01*
G01X652300Y-16667D02*
Y-20000D01*
G01Y-15333D02*
X652133Y-15250D01*
Y-15083D01*
X652300Y-15000D01*
X652467Y-15083D01*
Y-15250D01*
X652300Y-15333D01*
G01X657900Y-20000D02*
Y-15000D01*
G01X607500Y-28500D02*
X606833Y-28667D01*
X606333Y-29083D01*
X606000Y-29583D01*
X605750Y-30250D01*
X605667Y-31000D01*
X605750Y-31750D01*
X606000Y-32417D01*
X606333Y-32917D01*
X606833Y-33333D01*
X607500Y-33500D01*
X608167Y-33333D01*
X608667Y-32917D01*
X609000Y-32417D01*
X609250Y-31750D01*
X609333Y-31000D01*
X609250Y-30250D01*
X609000Y-29583D01*
X608667Y-29083D01*
X608167Y-28667D01*
X607500Y-28500D01*
G01X613100Y-33667D02*
X612933Y-33583D01*
Y-33417D01*
X613100Y-33333D01*
X613267Y-33417D01*
Y-33583D01*
X613100Y-33667D01*
G01X616867Y-32500D02*
X617367Y-33083D01*
X618033Y-33417D01*
X618783Y-33500D01*
X619450Y-33417D01*
X620117Y-33000D01*
X620533Y-32500D01*
X620617Y-32000D01*
X620450Y-31417D01*
X619867Y-31000D01*
X619283Y-30833D01*
X618533D01*
G01X619283D02*
X619783Y-30583D01*
X620200Y-30167D01*
X620367Y-29667D01*
X620200Y-29167D01*
X619783Y-28750D01*
X619033Y-28500D01*
X618283Y-28583D01*
X617533Y-28917D01*
G01X621800Y-31833D02*
X622633Y-30167D01*
X623467D01*
X625133Y-33500D01*
X625967D01*
X626800Y-31833D01*
G01X629900Y-28500D02*
X629233Y-28667D01*
X628733Y-29083D01*
X628400Y-29583D01*
X628150Y-30250D01*
X628067Y-31000D01*
X628150Y-31750D01*
X628400Y-32417D01*
X628733Y-32917D01*
X629233Y-33333D01*
X629900Y-33500D01*
X630567Y-33333D01*
X631067Y-32917D01*
X631400Y-32417D01*
X631650Y-31750D01*
X631733Y-31000D01*
X631650Y-30250D01*
X631400Y-29583D01*
X631067Y-29083D01*
X630567Y-28667D01*
X629900Y-28500D01*
G01X635500Y-33667D02*
X635333Y-33583D01*
Y-33417D01*
X635500Y-33333D01*
X635667Y-33417D01*
Y-33583D01*
X635500Y-33667D01*
G01X640933Y-33500D02*
X641100Y-32417D01*
X641350Y-31500D01*
X641683Y-30667D01*
X642100Y-29750D01*
X642767Y-28500D01*
X639433D01*
G01X644200Y-33500D02*
Y-30167D01*
G01Y-31083D02*
X644450Y-30667D01*
X644867Y-30333D01*
X645450Y-30167D01*
X646033Y-30333D01*
X646450Y-30667D01*
X646700Y-31083D01*
Y-33500D01*
G01Y-31083D02*
X646950Y-30667D01*
X647367Y-30333D01*
X647950Y-30167D01*
X648533Y-30333D01*
X648950Y-30667D01*
X649200Y-31167D01*
Y-33500D01*
G01X652300Y-30167D02*
Y-33500D01*
G01Y-28833D02*
X652133Y-28750D01*
Y-28583D01*
X652300Y-28500D01*
X652467Y-28583D01*
Y-28750D01*
X652300Y-28833D01*
G01X657900Y-33500D02*
Y-28500D01*
G01X609167Y-48500D02*
X605833Y-46833D01*
X609167Y-45167D01*
G01X612017Y-47583D02*
X614183D01*
G01Y-46083D02*
X612017D01*
G01X618700Y-48500D02*
Y-43500D01*
X617700Y-44500D01*
G01Y-48500D02*
X619700D01*
G01X624300Y-48667D02*
X624133Y-48583D01*
Y-48417D01*
X624300Y-48333D01*
X624467Y-48417D01*
Y-48583D01*
X624300Y-48667D01*
G01X630900Y-48500D02*
Y-43500D01*
X627817Y-47083D01*
X631983D01*
G01X633000Y-48500D02*
Y-45167D01*
G01Y-46083D02*
X633250Y-45667D01*
X633667Y-45333D01*
X634250Y-45167D01*
X634833Y-45333D01*
X635250Y-45667D01*
X635500Y-46083D01*
Y-48500D01*
G01Y-46083D02*
X635750Y-45667D01*
X636167Y-45333D01*
X636750Y-45167D01*
X637333Y-45333D01*
X637750Y-45667D01*
X638000Y-46167D01*
Y-48500D01*
G01X641100Y-45167D02*
Y-48500D01*
G01Y-43833D02*
X640933Y-43750D01*
Y-43583D01*
X641100Y-43500D01*
X641267Y-43583D01*
Y-43750D01*
X641100Y-43833D01*
G01X646700Y-48500D02*
Y-43500D01*
G01X605333Y-65000D02*
Y-60000D01*
X607500Y-64167D01*
X609667Y-60000D01*
Y-65000D01*
G01X611683Y-61667D02*
Y-64000D01*
X612017Y-64583D01*
X612517Y-64917D01*
X613100Y-65000D01*
X613683Y-64917D01*
X614183Y-64583D01*
X614517Y-64000D01*
G01Y-65000D02*
Y-61667D01*
G01X617450Y-64417D02*
X617867Y-64750D01*
X618450Y-65000D01*
X618950D01*
X619450Y-64833D01*
X619783Y-64583D01*
X619950Y-64250D01*
X619867Y-63750D01*
X619533Y-63500D01*
X618033Y-63000D01*
X617700Y-62417D01*
X617867Y-62000D01*
X618200Y-61750D01*
X618700Y-61667D01*
X619200Y-61750D01*
X619700Y-62000D01*
G01X624300Y-60000D02*
Y-65000D01*
G01X623133Y-61667D02*
X625467D01*
G01X635000Y-65000D02*
Y-60750D01*
X635167Y-60333D01*
X635500Y-60083D01*
X636000Y-60000D01*
X636500Y-60167D01*
X636750Y-60583D01*
G01X635750Y-62000D02*
X634083D01*
G01X641100Y-65000D02*
X640600Y-64917D01*
X640100Y-64583D01*
X639767Y-64000D01*
X639600Y-63333D01*
X639767Y-62667D01*
X640100Y-62083D01*
X640600Y-61750D01*
X641100Y-61667D01*
X641600Y-61750D01*
X642100Y-62083D01*
X642433Y-62667D01*
X642517Y-63333D01*
X642433Y-64000D01*
X642100Y-64583D01*
X641600Y-64917D01*
X641100Y-65000D01*
G01X646700D02*
Y-60000D01*
G01X652300Y-65000D02*
Y-60000D01*
G01X657900Y-65000D02*
X657400Y-64917D01*
X656900Y-64583D01*
X656567Y-64000D01*
X656400Y-63333D01*
X656567Y-62667D01*
X656900Y-62083D01*
X657400Y-61750D01*
X657900Y-61667D01*
X658400Y-61750D01*
X658900Y-62083D01*
X659233Y-62667D01*
X659317Y-63333D01*
X659233Y-64000D01*
X658900Y-64583D01*
X658400Y-64917D01*
X657900Y-65000D01*
G01X661417Y-61667D02*
X662417Y-65000D01*
X663500Y-61667D01*
X664583Y-65000D01*
X665583Y-61667D01*
G01X595500Y-69500D02*
Y438000D01*
G01X606583Y68167D02*
X608583D01*
G01X607500Y69250D02*
Y67083D01*
G01X611600Y66333D02*
X614600Y71500D01*
G01X617617Y68167D02*
X619783D01*
G01X624300Y66500D02*
Y71500D01*
X623300Y70500D01*
G01Y66500D02*
X625300D01*
G01X628067Y67250D02*
X628567Y66833D01*
X629150Y66583D01*
X629900Y66500D01*
X630650Y66667D01*
X631233Y67000D01*
X631650Y67583D01*
X631733Y68250D01*
X631567Y68917D01*
X631150Y69333D01*
X630567Y69667D01*
X629983Y69750D01*
X629400Y69667D01*
X628650Y69333D01*
X628900Y71500D01*
X631150D01*
G01X634000Y66333D02*
X637000Y71500D01*
G01X634000D02*
X633500Y71333D01*
X633250Y71083D01*
X633083Y70583D01*
X633250Y70083D01*
X633500Y69833D01*
X634000Y69667D01*
X634500Y69833D01*
X634750Y70083D01*
X634917Y70583D01*
X634750Y71083D01*
X634500Y71333D01*
X634000Y71500D01*
G01X637000Y68167D02*
X636500Y68000D01*
X636250Y67750D01*
X636083Y67250D01*
X636250Y66750D01*
X636500Y66500D01*
X637000Y66333D01*
X637500Y66500D01*
X637750Y66750D01*
X637917Y67250D01*
X637750Y67750D01*
X637500Y68000D01*
X637000Y68167D01*
G01X606583Y83167D02*
X608583D01*
G01X607500Y84250D02*
Y82083D01*
G01X611600Y81333D02*
X614600Y86500D01*
G01X617617Y83167D02*
X619783D01*
G01X624300Y81500D02*
Y86500D01*
X623300Y85500D01*
G01Y81500D02*
X625300D01*
G01X627400D02*
Y84833D01*
G01Y83917D02*
X627650Y84333D01*
X628067Y84667D01*
X628650Y84833D01*
X629233Y84667D01*
X629650Y84333D01*
X629900Y83917D01*
Y81500D01*
G01Y83917D02*
X630150Y84333D01*
X630567Y84667D01*
X631150Y84833D01*
X631733Y84667D01*
X632150Y84333D01*
X632400Y83833D01*
Y81500D01*
G01X635500Y84833D02*
Y81500D01*
G01Y86167D02*
X635333Y86250D01*
Y86417D01*
X635500Y86500D01*
X635667Y86417D01*
Y86250D01*
X635500Y86167D01*
G01X641100Y81500D02*
Y86500D01*
G01X606583Y48667D02*
X608583D01*
G01X607500Y49750D02*
Y47583D01*
G01X611600Y46833D02*
X614600Y52000D01*
G01X617617Y48667D02*
X619783D01*
G01X622717Y51167D02*
X623217Y51667D01*
X623800Y51917D01*
X624467Y52000D01*
X625300Y51833D01*
X625883Y51417D01*
X626050Y50917D01*
X625967Y50417D01*
X625633Y50000D01*
X623967Y49167D01*
X623217Y48583D01*
X622717Y47750D01*
X622550Y47000D01*
X626050D01*
G01X627400D02*
Y50333D01*
G01Y49417D02*
X627650Y49833D01*
X628067Y50167D01*
X628650Y50333D01*
X629233Y50167D01*
X629650Y49833D01*
X629900Y49417D01*
Y47000D01*
G01Y49417D02*
X630150Y49833D01*
X630567Y50167D01*
X631150Y50333D01*
X631733Y50167D01*
X632150Y49833D01*
X632400Y49333D01*
Y47000D01*
G01X635500Y50333D02*
Y47000D01*
G01Y51667D02*
X635333Y51750D01*
Y51917D01*
X635500Y52000D01*
X635667Y51917D01*
Y51750D01*
X635500Y51667D01*
G01X641100Y47000D02*
Y52000D01*
G01X606583Y24667D02*
X608583D01*
G01X607500Y25750D02*
Y23583D01*
G01X611600Y22833D02*
X614600Y28000D01*
G01X617617Y24667D02*
X619783D01*
G01X624300Y23000D02*
Y28000D01*
X623300Y27000D01*
G01Y23000D02*
X625300D01*
G01X627400D02*
Y26333D01*
G01Y25417D02*
X627650Y25833D01*
X628067Y26167D01*
X628650Y26333D01*
X629233Y26167D01*
X629650Y25833D01*
X629900Y25417D01*
Y23000D01*
G01Y25417D02*
X630150Y25833D01*
X630567Y26167D01*
X631150Y26333D01*
X631733Y26167D01*
X632150Y25833D01*
X632400Y25333D01*
Y23000D01*
G01X635500Y26333D02*
Y23000D01*
G01Y27667D02*
X635333Y27750D01*
Y27917D01*
X635500Y28000D01*
X635667Y27917D01*
Y27750D01*
X635500Y27667D01*
G01X641100Y23000D02*
Y28000D01*
G01X606583Y13167D02*
X608583D01*
G01X607500Y14250D02*
Y12083D01*
G01X611600Y11333D02*
X614600Y16500D01*
G01X617617Y13167D02*
X619783D01*
G01X622717Y15667D02*
X623217Y16167D01*
X623800Y16417D01*
X624467Y16500D01*
X625300Y16333D01*
X625883Y15917D01*
X626050Y15417D01*
X625967Y14917D01*
X625633Y14500D01*
X623967Y13667D01*
X623217Y13083D01*
X622717Y12250D01*
X622550Y11500D01*
X626050D01*
G01X627400D02*
Y14833D01*
G01Y13917D02*
X627650Y14333D01*
X628067Y14667D01*
X628650Y14833D01*
X629233Y14667D01*
X629650Y14333D01*
X629900Y13917D01*
Y11500D01*
G01Y13917D02*
X630150Y14333D01*
X630567Y14667D01*
X631150Y14833D01*
X631733Y14667D01*
X632150Y14333D01*
X632400Y13833D01*
Y11500D01*
G01X635500Y14833D02*
Y11500D01*
G01Y16167D02*
X635333Y16250D01*
Y16417D01*
X635500Y16500D01*
X635667Y16417D01*
Y16250D01*
X635500Y16167D01*
G01X641100Y11500D02*
Y16500D01*
G01X605833Y166500D02*
X609167Y168167D01*
X605833Y169833D01*
G01X612017Y167417D02*
X614183D01*
G01Y168917D02*
X612017D01*
G01X618700Y166500D02*
Y171500D01*
X617700Y170500D01*
G01Y166500D02*
X619700D01*
G01X624300Y166333D02*
X624133Y166417D01*
Y166583D01*
X624300Y166667D01*
X624467Y166583D01*
Y166417D01*
X624300Y166333D01*
G01X628067Y167500D02*
X628567Y166917D01*
X629233Y166583D01*
X629983Y166500D01*
X630650Y166583D01*
X631317Y167000D01*
X631733Y167500D01*
X631817Y168000D01*
X631650Y168583D01*
X631067Y169000D01*
X630483Y169167D01*
X629733D01*
G01X630483D02*
X630983Y169417D01*
X631400Y169833D01*
X631567Y170333D01*
X631400Y170833D01*
X630983Y171250D01*
X630233Y171500D01*
X629483Y171417D01*
X628733Y171083D01*
G01X633000Y166500D02*
Y169833D01*
G01Y168917D02*
X633250Y169333D01*
X633667Y169667D01*
X634250Y169833D01*
X634833Y169667D01*
X635250Y169333D01*
X635500Y168917D01*
Y166500D01*
G01Y168917D02*
X635750Y169333D01*
X636167Y169667D01*
X636750Y169833D01*
X637333Y169667D01*
X637750Y169333D01*
X638000Y168833D01*
Y166500D01*
G01X641100Y169833D02*
Y166500D01*
G01Y171167D02*
X640933Y171250D01*
Y171417D01*
X641100Y171500D01*
X641267Y171417D01*
Y171250D01*
X641100Y171167D01*
G01X646700Y166500D02*
Y171500D01*
G01X605833Y144000D02*
X609167Y145667D01*
X605833Y147333D01*
G01X612017Y144917D02*
X614183D01*
G01Y146417D02*
X612017D01*
G01X618700Y144000D02*
Y149000D01*
X617700Y148000D01*
G01Y144000D02*
X619700D01*
G01X624300Y143833D02*
X624133Y143917D01*
Y144083D01*
X624300Y144167D01*
X624467Y144083D01*
Y143917D01*
X624300Y143833D01*
G01X628067Y144750D02*
X628567Y144333D01*
X629150Y144083D01*
X629900Y144000D01*
X630650Y144167D01*
X631233Y144500D01*
X631650Y145083D01*
X631733Y145750D01*
X631567Y146417D01*
X631150Y146833D01*
X630567Y147167D01*
X629983Y147250D01*
X629400Y147167D01*
X628650Y146833D01*
X628900Y149000D01*
X631150D01*
G01X633000Y144000D02*
Y147333D01*
G01Y146417D02*
X633250Y146833D01*
X633667Y147167D01*
X634250Y147333D01*
X634833Y147167D01*
X635250Y146833D01*
X635500Y146417D01*
Y144000D01*
G01Y146417D02*
X635750Y146833D01*
X636167Y147167D01*
X636750Y147333D01*
X637333Y147167D01*
X637750Y146833D01*
X638000Y146333D01*
Y144000D01*
G01X641100Y147333D02*
Y144000D01*
G01Y148667D02*
X640933Y148750D01*
Y148917D01*
X641100Y149000D01*
X641267Y148917D01*
Y148750D01*
X641100Y148667D01*
G01X646700Y144000D02*
Y149000D01*
G01X605833Y126500D02*
X609167Y128167D01*
X605833Y129833D01*
G01X612017Y127417D02*
X614183D01*
G01Y128917D02*
X612017D01*
G01X618700Y126500D02*
Y131500D01*
X617700Y130500D01*
G01Y126500D02*
X619700D01*
G01X624300Y126333D02*
X624133Y126417D01*
Y126583D01*
X624300Y126667D01*
X624467Y126583D01*
Y126417D01*
X624300Y126333D01*
G01X629900Y131500D02*
X629233Y131333D01*
X628733Y130917D01*
X628400Y130417D01*
X628150Y129750D01*
X628067Y129000D01*
X628150Y128250D01*
X628400Y127583D01*
X628733Y127083D01*
X629233Y126667D01*
X629900Y126500D01*
X630567Y126667D01*
X631067Y127083D01*
X631400Y127583D01*
X631650Y128250D01*
X631733Y129000D01*
X631650Y129750D01*
X631400Y130417D01*
X631067Y130917D01*
X630567Y131333D01*
X629900Y131500D01*
G01X633000Y126500D02*
Y129833D01*
G01Y128917D02*
X633250Y129333D01*
X633667Y129667D01*
X634250Y129833D01*
X634833Y129667D01*
X635250Y129333D01*
X635500Y128917D01*
Y126500D01*
G01Y128917D02*
X635750Y129333D01*
X636167Y129667D01*
X636750Y129833D01*
X637333Y129667D01*
X637750Y129333D01*
X638000Y128833D01*
Y126500D01*
G01X641100Y129833D02*
Y126500D01*
G01Y131167D02*
X640933Y131250D01*
Y131417D01*
X641100Y131500D01*
X641267Y131417D01*
Y131250D01*
X641100Y131167D01*
G01X646700Y126500D02*
Y131500D01*
G01X606583Y98167D02*
X608583D01*
G01X607500Y99250D02*
Y97083D01*
G01X611600Y96333D02*
X614600Y101500D01*
G01X617617Y98167D02*
X619783D01*
G01X622717Y100667D02*
X623217Y101167D01*
X623800Y101417D01*
X624467Y101500D01*
X625300Y101333D01*
X625883Y100917D01*
X626050Y100417D01*
X625967Y99917D01*
X625633Y99500D01*
X623967Y98667D01*
X623217Y98083D01*
X622717Y97250D01*
X622550Y96500D01*
X626050D01*
G01X629900Y101500D02*
X629233Y101333D01*
X628733Y100917D01*
X628400Y100417D01*
X628150Y99750D01*
X628067Y99000D01*
X628150Y98250D01*
X628400Y97583D01*
X628733Y97083D01*
X629233Y96667D01*
X629900Y96500D01*
X630567Y96667D01*
X631067Y97083D01*
X631400Y97583D01*
X631650Y98250D01*
X631733Y99000D01*
X631650Y99750D01*
X631400Y100417D01*
X631067Y100917D01*
X630567Y101333D01*
X629900Y101500D01*
G01X634000Y96333D02*
X637000Y101500D01*
G01X634000D02*
X633500Y101333D01*
X633250Y101083D01*
X633083Y100583D01*
X633250Y100083D01*
X633500Y99833D01*
X634000Y99667D01*
X634500Y99833D01*
X634750Y100083D01*
X634917Y100583D01*
X634750Y101083D01*
X634500Y101333D01*
X634000Y101500D01*
G01X637000Y98167D02*
X636500Y98000D01*
X636250Y97750D01*
X636083Y97250D01*
X636250Y96750D01*
X636500Y96500D01*
X637000Y96333D01*
X637500Y96500D01*
X637750Y96750D01*
X637917Y97250D01*
X637750Y97750D01*
X637500Y98000D01*
X637000Y98167D01*
G01X606583Y113167D02*
X608583D01*
G01X607500Y114250D02*
Y112083D01*
G01X611600Y111333D02*
X614600Y116500D01*
G01X617617Y113167D02*
X619783D01*
G01X622467Y112500D02*
X622967Y111917D01*
X623633Y111583D01*
X624383Y111500D01*
X625050Y111583D01*
X625717Y112000D01*
X626133Y112500D01*
X626217Y113000D01*
X626050Y113583D01*
X625467Y114000D01*
X624883Y114167D01*
X624133D01*
G01X624883D02*
X625383Y114417D01*
X625800Y114833D01*
X625967Y115333D01*
X625800Y115833D01*
X625383Y116250D01*
X624633Y116500D01*
X623883Y116417D01*
X623133Y116083D01*
G01X627400Y111500D02*
Y114833D01*
G01Y113917D02*
X627650Y114333D01*
X628067Y114667D01*
X628650Y114833D01*
X629233Y114667D01*
X629650Y114333D01*
X629900Y113917D01*
Y111500D01*
G01Y113917D02*
X630150Y114333D01*
X630567Y114667D01*
X631150Y114833D01*
X631733Y114667D01*
X632150Y114333D01*
X632400Y113833D01*
Y111500D01*
G01X635500Y114833D02*
Y111500D01*
G01Y116167D02*
X635333Y116250D01*
Y116417D01*
X635500Y116500D01*
X635667Y116417D01*
Y116250D01*
X635500Y116167D01*
G01X641100Y111500D02*
Y116500D01*
G01X612977Y200490D02*
X609643Y202157D01*
X612977Y203823D01*
G01X616910Y205490D02*
X616243Y205323D01*
X615743Y204907D01*
X615410Y204407D01*
X615160Y203740D01*
X615077Y202990D01*
X615160Y202240D01*
X615410Y201573D01*
X615743Y201073D01*
X616243Y200657D01*
X616910Y200490D01*
X617577Y200657D01*
X618077Y201073D01*
X618410Y201573D01*
X618660Y202240D01*
X618743Y202990D01*
X618660Y203740D01*
X618410Y204407D01*
X618077Y204907D01*
X617577Y205323D01*
X616910Y205490D01*
G01X622510Y200323D02*
X622343Y200407D01*
Y200573D01*
X622510Y200657D01*
X622677Y200573D01*
Y200407D01*
X622510Y200323D01*
G01X626277Y201490D02*
X626777Y200907D01*
X627443Y200573D01*
X628193Y200490D01*
X628860Y200573D01*
X629527Y200990D01*
X629943Y201490D01*
X630027Y201990D01*
X629860Y202573D01*
X629277Y202990D01*
X628693Y203157D01*
X627943D01*
G01X628693D02*
X629193Y203407D01*
X629610Y203823D01*
X629777Y204323D01*
X629610Y204823D01*
X629193Y205240D01*
X628443Y205490D01*
X627693Y205407D01*
X626943Y205073D01*
G01X631210Y200490D02*
Y203823D01*
G01Y202907D02*
X631460Y203323D01*
X631877Y203657D01*
X632460Y203823D01*
X633043Y203657D01*
X633460Y203323D01*
X633710Y202907D01*
Y200490D01*
G01Y202907D02*
X633960Y203323D01*
X634377Y203657D01*
X634960Y203823D01*
X635543Y203657D01*
X635960Y203323D01*
X636210Y202823D01*
Y200490D01*
G01X639310Y203823D02*
Y200490D01*
G01Y205157D02*
X639143Y205240D01*
Y205407D01*
X639310Y205490D01*
X639477Y205407D01*
Y205240D01*
X639310Y205157D01*
G01X644910Y200490D02*
Y205490D01*
G01X612377Y255680D02*
X609043Y257347D01*
X612377Y259013D01*
G01X616310Y255680D02*
Y260680D01*
X615310Y259680D01*
G01Y255680D02*
X617310D01*
G01X619410D02*
Y259013D01*
G01Y258097D02*
X619660Y258513D01*
X620077Y258847D01*
X620660Y259013D01*
X621243Y258847D01*
X621660Y258513D01*
X621910Y258097D01*
Y255680D01*
G01Y258097D02*
X622160Y258513D01*
X622577Y258847D01*
X623160Y259013D01*
X623743Y258847D01*
X624160Y258513D01*
X624410Y258013D01*
Y255680D01*
G01X627510Y259013D02*
Y255680D01*
G01Y260347D02*
X627343Y260430D01*
Y260597D01*
X627510Y260680D01*
X627677Y260597D01*
Y260430D01*
X627510Y260347D01*
G01X633110Y255680D02*
Y260680D01*
G01X602120Y310470D02*
Y313803D01*
G01Y312887D02*
X602370Y313303D01*
X602787Y313637D01*
X603370Y313803D01*
X603953Y313637D01*
X604370Y313303D01*
X604620Y312887D01*
Y310470D01*
G01Y312887D02*
X604870Y313303D01*
X605287Y313637D01*
X605870Y313803D01*
X606453Y313637D01*
X606870Y313303D01*
X607120Y312803D01*
Y310470D01*
G01X608803Y313803D02*
Y311470D01*
X609137Y310887D01*
X609637Y310553D01*
X610220Y310470D01*
X610803Y310553D01*
X611303Y310887D01*
X611637Y311470D01*
G01Y310470D02*
Y313803D01*
G01X614570Y311053D02*
X614987Y310720D01*
X615570Y310470D01*
X616070D01*
X616570Y310637D01*
X616903Y310887D01*
X617070Y311220D01*
X616987Y311720D01*
X616653Y311970D01*
X615153Y312470D01*
X614820Y313053D01*
X614987Y313470D01*
X615320Y313720D01*
X615820Y313803D01*
X616320Y313720D01*
X616820Y313470D01*
G01X621420Y315470D02*
Y310470D01*
G01X620253Y313803D02*
X622587D01*
G01X628687Y310470D02*
X625353Y312137D01*
X628687Y313803D01*
G01X630537Y310470D02*
X632620Y315470D01*
X634703Y310470D01*
G01X633953Y312220D02*
X631287D01*
G01X645320Y315470D02*
Y310470D01*
G01Y311220D02*
X644987Y310803D01*
X644487Y310553D01*
X643903Y310470D01*
X643237Y310637D01*
X642737Y311053D01*
X642403Y311553D01*
X642320Y312137D01*
X642403Y312720D01*
X642737Y313220D01*
X643237Y313637D01*
X643903Y313803D01*
X644487Y313720D01*
X644903Y313553D01*
X645320Y313220D01*
G01X649420Y313803D02*
Y310470D01*
G01Y315137D02*
X649253Y315220D01*
Y315387D01*
X649420Y315470D01*
X649587Y315387D01*
Y315220D01*
X649420Y315137D01*
G01X656520Y310470D02*
Y313803D01*
G01Y313220D02*
X656187Y313553D01*
X655687Y313720D01*
X655103Y313803D01*
X654520Y313637D01*
X654020Y313303D01*
X653687Y312803D01*
X653520Y312137D01*
X653687Y311470D01*
X654020Y310970D01*
X654520Y310637D01*
X655103Y310470D01*
X655687Y310553D01*
X656187Y310803D01*
X656520Y311137D01*
G01X658120Y310470D02*
Y313803D01*
G01Y312887D02*
X658370Y313303D01*
X658787Y313637D01*
X659370Y313803D01*
X659953Y313637D01*
X660370Y313303D01*
X660620Y312887D01*
Y310470D01*
G01Y312887D02*
X660870Y313303D01*
X661287Y313637D01*
X661870Y313803D01*
X662453Y313637D01*
X662870Y313303D01*
X663120Y312803D01*
Y310470D01*
G01X664970Y312720D02*
X667637D01*
X667387Y313303D01*
X666970Y313637D01*
X666387Y313803D01*
X665803Y313720D01*
X665303Y313470D01*
X664970Y312887D01*
X664803Y312387D01*
Y311887D01*
X664970Y311387D01*
X665387Y310887D01*
X665887Y310553D01*
X666470Y310470D01*
X667053Y310637D01*
X667637Y311137D01*
G01X671820Y315470D02*
Y310470D01*
G01X670653Y313803D02*
X672987D01*
G01X676170Y312720D02*
X678837D01*
X678587Y313303D01*
X678170Y313637D01*
X677587Y313803D01*
X677003Y313720D01*
X676503Y313470D01*
X676170Y312887D01*
X676003Y312387D01*
Y311887D01*
X676170Y311387D01*
X676587Y310887D01*
X677087Y310553D01*
X677670Y310470D01*
X678253Y310637D01*
X678837Y311137D01*
G01X681853Y310470D02*
Y313803D01*
G01Y313137D02*
X682270Y313470D01*
X682687Y313720D01*
X683270Y313803D01*
X683687Y313720D01*
X684187Y313470D01*
G01X602700Y319240D02*
Y324240D01*
G01Y321740D02*
X603117Y322240D01*
X603617Y322490D01*
X604117Y322573D01*
X604867Y322407D01*
X605367Y322073D01*
X605700Y321490D01*
Y320823D01*
X605533Y320157D01*
X605200Y319657D01*
X604617Y319323D01*
X604117Y319240D01*
X603617Y319323D01*
X603117Y319573D01*
X602700Y319990D01*
G01X608383Y322573D02*
Y320240D01*
X608717Y319657D01*
X609217Y319323D01*
X609800Y319240D01*
X610383Y319323D01*
X610883Y319657D01*
X611217Y320240D01*
G01Y319240D02*
Y322573D01*
G01X615400Y324240D02*
Y319240D01*
G01X614233Y322573D02*
X616567D01*
G01X627267Y321907D02*
X627600Y322157D01*
X627850Y322573D01*
X628017Y323157D01*
X627850Y323657D01*
X627517Y323990D01*
X626933Y324240D01*
X624683D01*
Y319240D01*
X627433D01*
X628017Y319573D01*
X628350Y320073D01*
X628517Y320657D01*
X628350Y321240D01*
X627850Y321740D01*
X627267Y321907D01*
X624683D01*
G01X639300Y324240D02*
Y319240D01*
G01Y319990D02*
X638967Y319573D01*
X638467Y319323D01*
X637883Y319240D01*
X637217Y319407D01*
X636717Y319823D01*
X636383Y320323D01*
X636300Y320907D01*
X636383Y321490D01*
X636717Y321990D01*
X637217Y322407D01*
X637883Y322573D01*
X638467Y322490D01*
X638883Y322323D01*
X639300Y321990D01*
G01X643400Y322573D02*
Y319240D01*
G01Y323907D02*
X643233Y323990D01*
Y324157D01*
X643400Y324240D01*
X643567Y324157D01*
Y323990D01*
X643400Y323907D01*
G01X650500Y319240D02*
Y322573D01*
G01Y321990D02*
X650167Y322323D01*
X649667Y322490D01*
X649083Y322573D01*
X648500Y322407D01*
X648000Y322073D01*
X647667Y321573D01*
X647500Y320907D01*
X647667Y320240D01*
X648000Y319740D01*
X648500Y319407D01*
X649083Y319240D01*
X649667Y319323D01*
X650167Y319573D01*
X650500Y319907D01*
G01X652100Y319240D02*
Y322573D01*
G01Y321657D02*
X652350Y322073D01*
X652767Y322407D01*
X653350Y322573D01*
X653933Y322407D01*
X654350Y322073D01*
X654600Y321657D01*
Y319240D01*
G01Y321657D02*
X654850Y322073D01*
X655267Y322407D01*
X655850Y322573D01*
X656433Y322407D01*
X656850Y322073D01*
X657100Y321573D01*
Y319240D01*
G01X658950Y321490D02*
X661617D01*
X661367Y322073D01*
X660950Y322407D01*
X660367Y322573D01*
X659783Y322490D01*
X659283Y322240D01*
X658950Y321657D01*
X658783Y321157D01*
Y320657D01*
X658950Y320157D01*
X659367Y319657D01*
X659867Y319323D01*
X660450Y319240D01*
X661033Y319407D01*
X661617Y319907D01*
G01X665800Y324240D02*
Y319240D01*
G01X664633Y322573D02*
X666967D01*
G01X670150Y321490D02*
X672817D01*
X672567Y322073D01*
X672150Y322407D01*
X671567Y322573D01*
X670983Y322490D01*
X670483Y322240D01*
X670150Y321657D01*
X669983Y321157D01*
Y320657D01*
X670150Y320157D01*
X670567Y319657D01*
X671067Y319323D01*
X671650Y319240D01*
X672233Y319407D01*
X672817Y319907D01*
G01X675833Y319240D02*
Y322573D01*
G01Y321907D02*
X676250Y322240D01*
X676667Y322490D01*
X677250Y322573D01*
X677667Y322490D01*
X678167Y322240D01*
G01X608397Y295230D02*
X605063Y296897D01*
X608397Y298563D01*
G01X610913Y295813D02*
X611497Y295397D01*
X612163Y295230D01*
X612830Y295397D01*
X613413Y295897D01*
X613830Y296647D01*
X613997Y297397D01*
Y298313D01*
X613830Y299063D01*
X613413Y299730D01*
X612913Y300063D01*
X612330Y300230D01*
X611663Y300063D01*
X611163Y299730D01*
X610830Y299230D01*
X610663Y298563D01*
X610830Y297980D01*
X611247Y297397D01*
X611747Y297063D01*
X612330Y296980D01*
X612997Y297147D01*
X613497Y297563D01*
X613997Y298313D01*
G01X617930Y300230D02*
X617263Y300063D01*
X616763Y299647D01*
X616430Y299147D01*
X616180Y298480D01*
X616097Y297730D01*
X616180Y296980D01*
X616430Y296313D01*
X616763Y295813D01*
X617263Y295397D01*
X617930Y295230D01*
X618597Y295397D01*
X619097Y295813D01*
X619430Y296313D01*
X619680Y296980D01*
X619763Y297730D01*
X619680Y298480D01*
X619430Y299147D01*
X619097Y299647D01*
X618597Y300063D01*
X617930Y300230D01*
G01X630630D02*
Y295230D01*
G01Y295980D02*
X630297Y295563D01*
X629797Y295313D01*
X629213Y295230D01*
X628547Y295397D01*
X628047Y295813D01*
X627713Y296313D01*
X627630Y296897D01*
X627713Y297480D01*
X628047Y297980D01*
X628547Y298397D01*
X629213Y298563D01*
X629797Y298480D01*
X630213Y298313D01*
X630630Y297980D01*
G01X633480Y297480D02*
X636147D01*
X635897Y298063D01*
X635480Y298397D01*
X634897Y298563D01*
X634313Y298480D01*
X633813Y298230D01*
X633480Y297647D01*
X633313Y297147D01*
Y296647D01*
X633480Y296147D01*
X633897Y295647D01*
X634397Y295313D01*
X634980Y295230D01*
X635563Y295397D01*
X636147Y295897D01*
G01X639163Y293980D02*
X639747Y293647D01*
X640413Y293563D01*
X640997Y293647D01*
X641497Y294063D01*
X641830Y294647D01*
Y298563D01*
G01Y297897D02*
X641497Y298230D01*
X640997Y298480D01*
X640413Y298563D01*
X639747Y298397D01*
X639330Y298063D01*
X638997Y297480D01*
X638830Y296897D01*
X638913Y296397D01*
X639247Y295813D01*
X639747Y295397D01*
X640413Y295230D01*
X640913Y295313D01*
X641497Y295647D01*
X641830Y295980D01*
G01X644763Y295230D02*
Y298563D01*
G01Y297897D02*
X645180Y298230D01*
X645597Y298480D01*
X646180Y298563D01*
X646597Y298480D01*
X647097Y298230D01*
G01X650280Y297480D02*
X652947D01*
X652697Y298063D01*
X652280Y298397D01*
X651697Y298563D01*
X651113Y298480D01*
X650613Y298230D01*
X650280Y297647D01*
X650113Y297147D01*
Y296647D01*
X650280Y296147D01*
X650697Y295647D01*
X651197Y295313D01*
X651780Y295230D01*
X652363Y295397D01*
X652947Y295897D01*
G01X655880Y297480D02*
X658547D01*
X658297Y298063D01*
X657880Y298397D01*
X657297Y298563D01*
X656713Y298480D01*
X656213Y298230D01*
X655880Y297647D01*
X655713Y297147D01*
Y296647D01*
X655880Y296147D01*
X656297Y295647D01*
X656797Y295313D01*
X657380Y295230D01*
X657963Y295397D01*
X658547Y295897D01*
G01X603783Y329260D02*
X607117Y330927D01*
X603783Y332593D01*
G01X609967Y330177D02*
X612133D01*
G01Y331677D02*
X609967D01*
G01X616483Y329260D02*
X616650Y330343D01*
X616900Y331260D01*
X617233Y332093D01*
X617650Y333010D01*
X618317Y334260D01*
X614983D01*
G01X622250D02*
X621583Y334093D01*
X621083Y333677D01*
X620750Y333177D01*
X620500Y332510D01*
X620417Y331760D01*
X620500Y331010D01*
X620750Y330343D01*
X621083Y329843D01*
X621583Y329427D01*
X622250Y329260D01*
X622917Y329427D01*
X623417Y329843D01*
X623750Y330343D01*
X624000Y331010D01*
X624083Y331760D01*
X624000Y332510D01*
X623750Y333177D01*
X623417Y333677D01*
X622917Y334093D01*
X622250Y334260D01*
G01X626350Y329093D02*
X629350Y334260D01*
G01X626350D02*
X625850Y334093D01*
X625600Y333843D01*
X625433Y333343D01*
X625600Y332843D01*
X625850Y332593D01*
X626350Y332427D01*
X626850Y332593D01*
X627100Y332843D01*
X627267Y333343D01*
X627100Y333843D01*
X626850Y334093D01*
X626350Y334260D01*
G01X629350Y330927D02*
X628850Y330760D01*
X628600Y330510D01*
X628433Y330010D01*
X628600Y329510D01*
X628850Y329260D01*
X629350Y329093D01*
X629850Y329260D01*
X630100Y329510D01*
X630267Y330010D01*
X630100Y330510D01*
X629850Y330760D01*
X629350Y330927D01*
G01X633283Y328343D02*
X633617Y329427D01*
G01X605763Y349687D02*
X607763D01*
G01X606680Y350770D02*
Y348603D01*
G01X610780Y347853D02*
X613780Y353020D01*
G01X616797Y349687D02*
X618963D01*
G01X623480Y348020D02*
Y353020D01*
X622480Y352020D01*
G01Y348020D02*
X624480D01*
G01X626580D02*
Y351353D01*
G01Y350437D02*
X626830Y350853D01*
X627247Y351187D01*
X627830Y351353D01*
X628413Y351187D01*
X628830Y350853D01*
X629080Y350437D01*
Y348020D01*
G01Y350437D02*
X629330Y350853D01*
X629747Y351187D01*
X630330Y351353D01*
X630913Y351187D01*
X631330Y350853D01*
X631580Y350353D01*
Y348020D01*
G01X634680Y351353D02*
Y348020D01*
G01Y352687D02*
X634513Y352770D01*
Y352937D01*
X634680Y353020D01*
X634847Y352937D01*
Y352770D01*
X634680Y352687D01*
G01X640280Y348020D02*
Y353020D01*
G01X608333Y393000D02*
Y398000D01*
X610500Y393833D01*
X612667Y398000D01*
Y393000D01*
G01X614683Y396333D02*
Y394000D01*
X615017Y393417D01*
X615517Y393083D01*
X616100Y393000D01*
X616683Y393083D01*
X617183Y393417D01*
X617517Y394000D01*
G01Y393000D02*
Y396333D01*
G01X620450Y393583D02*
X620867Y393250D01*
X621450Y393000D01*
X621950D01*
X622450Y393167D01*
X622783Y393417D01*
X622950Y393750D01*
X622867Y394250D01*
X622533Y394500D01*
X621033Y395000D01*
X620700Y395583D01*
X620867Y396000D01*
X621200Y396250D01*
X621700Y396333D01*
X622200Y396250D01*
X622700Y396000D01*
G01X627300Y398000D02*
Y393000D01*
G01X626133Y396333D02*
X628467D01*
G01X638000Y393000D02*
Y397250D01*
X638167Y397667D01*
X638500Y397917D01*
X639000Y398000D01*
X639500Y397833D01*
X639750Y397417D01*
G01X638750Y396000D02*
X637083D01*
G01X644100Y393000D02*
X643600Y393083D01*
X643100Y393417D01*
X642767Y394000D01*
X642600Y394667D01*
X642767Y395333D01*
X643100Y395917D01*
X643600Y396250D01*
X644100Y396333D01*
X644600Y396250D01*
X645100Y395917D01*
X645433Y395333D01*
X645517Y394667D01*
X645433Y394000D01*
X645100Y393417D01*
X644600Y393083D01*
X644100Y393000D01*
G01X649700D02*
Y398000D01*
G01X655300Y393000D02*
Y398000D01*
G01X660900Y393000D02*
X660400Y393083D01*
X659900Y393417D01*
X659567Y394000D01*
X659400Y394667D01*
X659567Y395333D01*
X659900Y395917D01*
X660400Y396250D01*
X660900Y396333D01*
X661400Y396250D01*
X661900Y395917D01*
X662233Y395333D01*
X662317Y394667D01*
X662233Y394000D01*
X661900Y393417D01*
X661400Y393083D01*
X660900Y393000D01*
G01X664417Y396333D02*
X665417Y393000D01*
X666500Y396333D01*
X667583Y393000D01*
X668583Y396333D01*
G01X605810Y429990D02*
Y434240D01*
X605977Y434657D01*
X606310Y434907D01*
X606810Y434990D01*
X607310Y434823D01*
X607560Y434407D01*
G01X606560Y432990D02*
X604893D01*
G01X611910Y429990D02*
X611410Y430073D01*
X610910Y430407D01*
X610577Y430990D01*
X610410Y431657D01*
X610577Y432323D01*
X610910Y432907D01*
X611410Y433240D01*
X611910Y433323D01*
X612410Y433240D01*
X612910Y432907D01*
X613243Y432323D01*
X613327Y431657D01*
X613243Y430990D01*
X612910Y430407D01*
X612410Y430073D01*
X611910Y429990D01*
G01X617510D02*
Y434990D01*
G01X623110Y429990D02*
Y434990D01*
G01X628710Y429990D02*
X628210Y430073D01*
X627710Y430407D01*
X627377Y430990D01*
X627210Y431657D01*
X627377Y432323D01*
X627710Y432907D01*
X628210Y433240D01*
X628710Y433323D01*
X629210Y433240D01*
X629710Y432907D01*
X630043Y432323D01*
X630127Y431657D01*
X630043Y430990D01*
X629710Y430407D01*
X629210Y430073D01*
X628710Y429990D01*
G01X632227Y433323D02*
X633227Y429990D01*
X634310Y433323D01*
X635393Y429990D01*
X636393Y433323D01*
G01X647010Y434990D02*
Y429990D01*
G01Y430740D02*
X646677Y430323D01*
X646177Y430073D01*
X645593Y429990D01*
X644927Y430157D01*
X644427Y430573D01*
X644093Y431073D01*
X644010Y431657D01*
X644093Y432240D01*
X644427Y432740D01*
X644927Y433157D01*
X645593Y433323D01*
X646177Y433240D01*
X646593Y433073D01*
X647010Y432740D01*
G01X649943Y429990D02*
Y433323D01*
G01Y432657D02*
X650360Y432990D01*
X650777Y433240D01*
X651360Y433323D01*
X651777Y433240D01*
X652277Y432990D01*
G01X658210Y429990D02*
Y433323D01*
G01Y432740D02*
X657877Y433073D01*
X657377Y433240D01*
X656793Y433323D01*
X656210Y433157D01*
X655710Y432823D01*
X655377Y432323D01*
X655210Y431657D01*
X655377Y430990D01*
X655710Y430490D01*
X656210Y430157D01*
X656793Y429990D01*
X657377Y430073D01*
X657877Y430323D01*
X658210Y430657D01*
G01X660227Y433323D02*
X661227Y429990D01*
X662310Y433323D01*
X663393Y429990D01*
X664393Y433323D01*
G01X667910D02*
Y429990D01*
G01Y434657D02*
X667743Y434740D01*
Y434907D01*
X667910Y434990D01*
X668077Y434907D01*
Y434740D01*
X667910Y434657D01*
G01X672093Y429990D02*
Y433323D01*
G01Y432490D02*
X672427Y432907D01*
X672927Y433240D01*
X673593Y433323D01*
X674177Y433240D01*
X674677Y432907D01*
X674927Y432323D01*
Y429990D01*
G01X677943Y428740D02*
X678527Y428407D01*
X679193Y428323D01*
X679777Y428407D01*
X680277Y428823D01*
X680610Y429407D01*
Y433323D01*
G01Y432657D02*
X680277Y432990D01*
X679777Y433240D01*
X679193Y433323D01*
X678527Y433157D01*
X678110Y432823D01*
X677777Y432240D01*
X677610Y431657D01*
X677693Y431157D01*
X678027Y430573D01*
X678527Y430157D01*
X679193Y429990D01*
X679693Y430073D01*
X680277Y430407D01*
X680610Y430740D01*
G01X685127Y428323D02*
X685960Y429157D01*
X686377Y429990D01*
Y433323D01*
X685960Y434157D01*
X685127Y434990D01*
G01X650853Y438153D02*
X650020Y438987D01*
X649603Y439820D01*
Y443153D01*
X650020Y443987D01*
X650853Y444820D01*
G01X656870Y439820D02*
X656370Y439903D01*
X655870Y440237D01*
X655537Y440820D01*
X655370Y441487D01*
X655537Y442153D01*
X655870Y442737D01*
X656370Y443070D01*
X656870Y443153D01*
X657370Y443070D01*
X657870Y442737D01*
X658203Y442153D01*
X658287Y441487D01*
X658203Y440820D01*
X657870Y440237D01*
X657370Y439903D01*
X656870Y439820D01*
G01X661303D02*
Y443153D01*
G01Y442487D02*
X661720Y442820D01*
X662137Y443070D01*
X662720Y443153D01*
X663137Y443070D01*
X663637Y442820D01*
G01X606903Y440587D02*
X608903D01*
G01X607820Y441670D02*
Y439503D01*
G01X611920Y438753D02*
X614920Y443920D01*
G01X617937Y440587D02*
X620103D01*
G01X622787Y439670D02*
X623287Y439253D01*
X623870Y439003D01*
X624620Y438920D01*
X625370Y439087D01*
X625953Y439420D01*
X626370Y440003D01*
X626453Y440670D01*
X626287Y441337D01*
X625870Y441753D01*
X625287Y442087D01*
X624703Y442170D01*
X624120Y442087D01*
X623370Y441753D01*
X623620Y443920D01*
X625870D01*
G01X627720Y438920D02*
Y442253D01*
G01Y441337D02*
X627970Y441753D01*
X628387Y442087D01*
X628970Y442253D01*
X629553Y442087D01*
X629970Y441753D01*
X630220Y441337D01*
Y438920D01*
G01Y441337D02*
X630470Y441753D01*
X630887Y442087D01*
X631470Y442253D01*
X632053Y442087D01*
X632470Y441753D01*
X632720Y441253D01*
Y438920D01*
G01X635820Y442253D02*
Y438920D01*
G01Y443587D02*
X635653Y443670D01*
Y443837D01*
X635820Y443920D01*
X635987Y443837D01*
Y443670D01*
X635820Y443587D01*
G01X641420Y438920D02*
Y443920D01*
G01X607500Y452000D02*
Y457000D01*
X606500Y456000D01*
G01Y452000D02*
X608500D01*
G01X613100Y451833D02*
X612933Y451917D01*
Y452083D01*
X613100Y452167D01*
X613267Y452083D01*
Y451917D01*
X613100Y451833D01*
G01X618700Y457000D02*
X618033Y456833D01*
X617533Y456417D01*
X617200Y455917D01*
X616950Y455250D01*
X616867Y454500D01*
X616950Y453750D01*
X617200Y453083D01*
X617533Y452583D01*
X618033Y452167D01*
X618700Y452000D01*
X619367Y452167D01*
X619867Y452583D01*
X620200Y453083D01*
X620450Y453750D01*
X620533Y454500D01*
X620450Y455250D01*
X620200Y455917D01*
X619867Y456417D01*
X619367Y456833D01*
X618700Y457000D01*
G01X621800Y452000D02*
Y455333D01*
G01Y454417D02*
X622050Y454833D01*
X622467Y455167D01*
X623050Y455333D01*
X623633Y455167D01*
X624050Y454833D01*
X624300Y454417D01*
Y452000D01*
G01Y454417D02*
X624550Y454833D01*
X624967Y455167D01*
X625550Y455333D01*
X626133Y455167D01*
X626550Y454833D01*
X626800Y454333D01*
Y452000D01*
G01X629900Y455333D02*
Y452000D01*
G01Y456667D02*
X629733Y456750D01*
Y456917D01*
X629900Y457000D01*
X630067Y456917D01*
Y456750D01*
X629900Y456667D01*
G01X635500Y452000D02*
Y457000D01*
G01X644200Y452000D02*
Y455333D01*
G01Y454417D02*
X644450Y454833D01*
X644867Y455167D01*
X645450Y455333D01*
X646033Y455167D01*
X646450Y454833D01*
X646700Y454417D01*
Y452000D01*
G01Y454417D02*
X646950Y454833D01*
X647367Y455167D01*
X647950Y455333D01*
X648533Y455167D01*
X648950Y454833D01*
X649200Y454333D01*
Y452000D01*
G01X653800D02*
Y455333D01*
G01Y454750D02*
X653467Y455083D01*
X652967Y455250D01*
X652383Y455333D01*
X651800Y455167D01*
X651300Y454833D01*
X650967Y454333D01*
X650800Y453667D01*
X650967Y453000D01*
X651300Y452500D01*
X651800Y452167D01*
X652383Y452000D01*
X652967Y452083D01*
X653467Y452333D01*
X653800Y452667D01*
G01X656650Y455333D02*
X659150Y452000D01*
G01Y455333D02*
X656650Y452000D01*
G01X606583Y471667D02*
X608583D01*
G01X607500Y472750D02*
Y470583D01*
G01X611600Y469833D02*
X614600Y475000D01*
G01X617617Y471667D02*
X619783D01*
G01X622467Y470750D02*
X622967Y470333D01*
X623550Y470083D01*
X624300Y470000D01*
X625050Y470167D01*
X625633Y470500D01*
X626050Y471083D01*
X626133Y471750D01*
X625967Y472417D01*
X625550Y472833D01*
X624967Y473167D01*
X624383Y473250D01*
X623800Y473167D01*
X623050Y472833D01*
X623300Y475000D01*
X625550D01*
G01X627400Y470000D02*
Y473333D01*
G01Y472417D02*
X627650Y472833D01*
X628067Y473167D01*
X628650Y473333D01*
X629233Y473167D01*
X629650Y472833D01*
X629900Y472417D01*
Y470000D01*
G01Y472417D02*
X630150Y472833D01*
X630567Y473167D01*
X631150Y473333D01*
X631733Y473167D01*
X632150Y472833D01*
X632400Y472333D01*
Y470000D01*
G01X635500Y473333D02*
Y470000D01*
G01Y474667D02*
X635333Y474750D01*
Y474917D01*
X635500Y475000D01*
X635667Y474917D01*
Y474750D01*
X635500Y474667D01*
G01X641100Y470000D02*
Y475000D01*
G01X595500Y679000D02*
Y396000D01*
G01X606583Y546667D02*
X608583D01*
G01X607500Y547750D02*
Y545583D01*
G01X611600Y544833D02*
X614600Y550000D01*
G01X617617Y546667D02*
X619783D01*
G01X622717Y549167D02*
X623217Y549667D01*
X623800Y549917D01*
X624467Y550000D01*
X625300Y549833D01*
X625883Y549417D01*
X626050Y548917D01*
X625967Y548417D01*
X625633Y548000D01*
X623967Y547167D01*
X623217Y546583D01*
X622717Y545750D01*
X622550Y545000D01*
X626050D01*
G01X627400D02*
Y548333D01*
G01Y547417D02*
X627650Y547833D01*
X628067Y548167D01*
X628650Y548333D01*
X629233Y548167D01*
X629650Y547833D01*
X629900Y547417D01*
Y545000D01*
G01Y547417D02*
X630150Y547833D01*
X630567Y548167D01*
X631150Y548333D01*
X631733Y548167D01*
X632150Y547833D01*
X632400Y547333D01*
Y545000D01*
G01X635500Y548333D02*
Y545000D01*
G01Y549667D02*
X635333Y549750D01*
Y549917D01*
X635500Y550000D01*
X635667Y549917D01*
Y549750D01*
X635500Y549667D01*
G01X641100Y545000D02*
Y550000D01*
G01X606583Y486667D02*
X608583D01*
G01X607500Y487750D02*
Y485583D01*
G01X611600Y484833D02*
X614600Y490000D01*
G01X617617Y486667D02*
X619783D01*
G01X622467Y485750D02*
X622967Y485333D01*
X623550Y485083D01*
X624300Y485000D01*
X625050Y485167D01*
X625633Y485500D01*
X626050Y486083D01*
X626133Y486750D01*
X625967Y487417D01*
X625550Y487833D01*
X624967Y488167D01*
X624383Y488250D01*
X623800Y488167D01*
X623050Y487833D01*
X623300Y490000D01*
X625550D01*
G01X627400Y485000D02*
Y488333D01*
G01Y487417D02*
X627650Y487833D01*
X628067Y488167D01*
X628650Y488333D01*
X629233Y488167D01*
X629650Y487833D01*
X629900Y487417D01*
Y485000D01*
G01Y487417D02*
X630150Y487833D01*
X630567Y488167D01*
X631150Y488333D01*
X631733Y488167D01*
X632150Y487833D01*
X632400Y487333D01*
Y485000D01*
G01X635500Y488333D02*
Y485000D01*
G01Y489667D02*
X635333Y489750D01*
Y489917D01*
X635500Y490000D01*
X635667Y489917D01*
Y489750D01*
X635500Y489667D01*
G01X641100Y485000D02*
Y490000D01*
G01X606583Y501667D02*
X608583D01*
G01X607500Y502750D02*
Y500583D01*
G01X611267Y501000D02*
X611767Y500417D01*
X612433Y500083D01*
X613183Y500000D01*
X613850Y500083D01*
X614517Y500500D01*
X614933Y501000D01*
X615017Y501500D01*
X614850Y502083D01*
X614267Y502500D01*
X613683Y502667D01*
X612933D01*
G01X613683D02*
X614183Y502917D01*
X614600Y503333D01*
X614767Y503833D01*
X614600Y504333D01*
X614183Y504750D01*
X613433Y505000D01*
X612683Y504917D01*
X611933Y504583D01*
G01X617200Y499833D02*
X620200Y505000D01*
G01X623217Y501667D02*
X625383D01*
G01X629900Y505000D02*
X629233Y504833D01*
X628733Y504417D01*
X628400Y503917D01*
X628150Y503250D01*
X628067Y502500D01*
X628150Y501750D01*
X628400Y501083D01*
X628733Y500583D01*
X629233Y500167D01*
X629900Y500000D01*
X630567Y500167D01*
X631067Y500583D01*
X631400Y501083D01*
X631650Y501750D01*
X631733Y502500D01*
X631650Y503250D01*
X631400Y503917D01*
X631067Y504417D01*
X630567Y504833D01*
X629900Y505000D01*
G01X633000Y500000D02*
Y503333D01*
G01Y502417D02*
X633250Y502833D01*
X633667Y503167D01*
X634250Y503333D01*
X634833Y503167D01*
X635250Y502833D01*
X635500Y502417D01*
Y500000D01*
G01Y502417D02*
X635750Y502833D01*
X636167Y503167D01*
X636750Y503333D01*
X637333Y503167D01*
X637750Y502833D01*
X638000Y502333D01*
Y500000D01*
G01X641100Y503333D02*
Y500000D01*
G01Y504667D02*
X640933Y504750D01*
Y504917D01*
X641100Y505000D01*
X641267Y504917D01*
Y504750D01*
X641100Y504667D01*
G01X646700Y500000D02*
Y505000D01*
G01X606583Y516667D02*
X608583D01*
G01X607500Y517750D02*
Y515583D01*
G01X611600Y514833D02*
X614600Y520000D01*
G01X617617Y516667D02*
X619783D01*
G01X622717Y519167D02*
X623217Y519667D01*
X623800Y519917D01*
X624467Y520000D01*
X625300Y519833D01*
X625883Y519417D01*
X626050Y518917D01*
X625967Y518417D01*
X625633Y518000D01*
X623967Y517167D01*
X623217Y516583D01*
X622717Y515750D01*
X622550Y515000D01*
X626050D01*
G01X627400D02*
Y518333D01*
G01Y517417D02*
X627650Y517833D01*
X628067Y518167D01*
X628650Y518333D01*
X629233Y518167D01*
X629650Y517833D01*
X629900Y517417D01*
Y515000D01*
G01Y517417D02*
X630150Y517833D01*
X630567Y518167D01*
X631150Y518333D01*
X631733Y518167D01*
X632150Y517833D01*
X632400Y517333D01*
Y515000D01*
G01X635500Y518333D02*
Y515000D01*
G01Y519667D02*
X635333Y519750D01*
Y519917D01*
X635500Y520000D01*
X635667Y519917D01*
Y519750D01*
X635500Y519667D01*
G01X641100Y515000D02*
Y520000D01*
G01X606583Y530167D02*
X608583D01*
G01X607500Y531250D02*
Y529083D01*
G01X611600Y528333D02*
X614600Y533500D01*
G01X617617Y530167D02*
X619783D01*
G01X622467Y529500D02*
X622967Y528917D01*
X623633Y528583D01*
X624383Y528500D01*
X625050Y528583D01*
X625717Y529000D01*
X626133Y529500D01*
X626217Y530000D01*
X626050Y530583D01*
X625467Y531000D01*
X624883Y531167D01*
X624133D01*
G01X624883D02*
X625383Y531417D01*
X625800Y531833D01*
X625967Y532333D01*
X625800Y532833D01*
X625383Y533250D01*
X624633Y533500D01*
X623883Y533417D01*
X623133Y533083D01*
G01X627400Y528500D02*
Y531833D01*
G01Y530917D02*
X627650Y531333D01*
X628067Y531667D01*
X628650Y531833D01*
X629233Y531667D01*
X629650Y531333D01*
X629900Y530917D01*
Y528500D01*
G01Y530917D02*
X630150Y531333D01*
X630567Y531667D01*
X631150Y531833D01*
X631733Y531667D01*
X632150Y531333D01*
X632400Y530833D01*
Y528500D01*
G01X635500Y531833D02*
Y528500D01*
G01Y533167D02*
X635333Y533250D01*
Y533417D01*
X635500Y533500D01*
X635667Y533417D01*
Y533250D01*
X635500Y533167D01*
G01X641100Y528500D02*
Y533500D01*
G01X606583Y561667D02*
X608583D01*
G01X607500Y562750D02*
Y560583D01*
G01X611600Y559833D02*
X614600Y565000D01*
G01X617617Y561667D02*
X619783D01*
G01X622717Y564167D02*
X623217Y564667D01*
X623800Y564917D01*
X624467Y565000D01*
X625300Y564833D01*
X625883Y564417D01*
X626050Y563917D01*
X625967Y563417D01*
X625633Y563000D01*
X623967Y562167D01*
X623217Y561583D01*
X622717Y560750D01*
X622550Y560000D01*
X626050D01*
G01X627400D02*
Y563333D01*
G01Y562417D02*
X627650Y562833D01*
X628067Y563167D01*
X628650Y563333D01*
X629233Y563167D01*
X629650Y562833D01*
X629900Y562417D01*
Y560000D01*
G01Y562417D02*
X630150Y562833D01*
X630567Y563167D01*
X631150Y563333D01*
X631733Y563167D01*
X632150Y562833D01*
X632400Y562333D01*
Y560000D01*
G01X635500Y563333D02*
Y560000D01*
G01Y564667D02*
X635333Y564750D01*
Y564917D01*
X635500Y565000D01*
X635667Y564917D01*
Y564750D01*
X635500Y564667D01*
G01X641100Y560000D02*
Y565000D01*
G01X606583Y620167D02*
X608583D01*
G01X607500Y621250D02*
Y619083D01*
G01X611600Y618333D02*
X614600Y623500D01*
G01X617617Y620167D02*
X619783D01*
G01X622717Y622667D02*
X623217Y623167D01*
X623800Y623417D01*
X624467Y623500D01*
X625300Y623333D01*
X625883Y622917D01*
X626050Y622417D01*
X625967Y621917D01*
X625633Y621500D01*
X623967Y620667D01*
X623217Y620083D01*
X622717Y619250D01*
X622550Y618500D01*
X626050D01*
G01X627400D02*
Y621833D01*
G01Y620917D02*
X627650Y621333D01*
X628067Y621667D01*
X628650Y621833D01*
X629233Y621667D01*
X629650Y621333D01*
X629900Y620917D01*
Y618500D01*
G01Y620917D02*
X630150Y621333D01*
X630567Y621667D01*
X631150Y621833D01*
X631733Y621667D01*
X632150Y621333D01*
X632400Y620833D01*
Y618500D01*
G01X635500Y621833D02*
Y618500D01*
G01Y623167D02*
X635333Y623250D01*
Y623417D01*
X635500Y623500D01*
X635667Y623417D01*
Y623250D01*
X635500Y623167D01*
G01X641100Y618500D02*
Y623500D01*
G01X617500Y668500D02*
Y663500D01*
G01X615583Y668500D02*
X619417D01*
G01X623100Y663500D02*
X622600Y663583D01*
X622100Y663917D01*
X621767Y664500D01*
X621600Y665167D01*
X621767Y665833D01*
X622100Y666417D01*
X622600Y666750D01*
X623100Y666833D01*
X623600Y666750D01*
X624100Y666417D01*
X624433Y665833D01*
X624517Y665167D01*
X624433Y664500D01*
X624100Y663917D01*
X623600Y663583D01*
X623100Y663500D01*
G01X628700D02*
Y668500D01*
G01X633050Y665750D02*
X635717D01*
X635467Y666333D01*
X635050Y666667D01*
X634467Y666833D01*
X633883Y666750D01*
X633383Y666500D01*
X633050Y665917D01*
X632883Y665417D01*
Y664917D01*
X633050Y664417D01*
X633467Y663917D01*
X633967Y663583D01*
X634550Y663500D01*
X635133Y663667D01*
X635717Y664167D01*
G01X638733Y663500D02*
Y666833D01*
G01Y666167D02*
X639150Y666500D01*
X639567Y666750D01*
X640150Y666833D01*
X640567Y666750D01*
X641067Y666500D01*
G01X647000Y663500D02*
Y666833D01*
G01Y666250D02*
X646667Y666583D01*
X646167Y666750D01*
X645583Y666833D01*
X645000Y666667D01*
X644500Y666333D01*
X644167Y665833D01*
X644000Y665167D01*
X644167Y664500D01*
X644500Y664000D01*
X645000Y663667D01*
X645583Y663500D01*
X646167Y663583D01*
X646667Y663833D01*
X647000Y664167D01*
G01X649683Y663500D02*
Y666833D01*
G01Y666000D02*
X650017Y666417D01*
X650517Y666750D01*
X651183Y666833D01*
X651767Y666750D01*
X652267Y666417D01*
X652517Y665833D01*
Y663500D01*
G01X658033Y666417D02*
X657450Y666750D01*
X656950Y666833D01*
X656283Y666667D01*
X655783Y666333D01*
X655450Y665750D01*
X655367Y665167D01*
X655450Y664583D01*
X655783Y664083D01*
X656283Y663667D01*
X656950Y663500D01*
X657533Y663667D01*
X658033Y664000D01*
G01X661050Y665750D02*
X663717D01*
X663467Y666333D01*
X663050Y666667D01*
X662467Y666833D01*
X661883Y666750D01*
X661383Y666500D01*
X661050Y665917D01*
X660883Y665417D01*
Y664917D01*
X661050Y664417D01*
X661467Y663917D01*
X661967Y663583D01*
X662550Y663500D01*
X663133Y663667D01*
X663717Y664167D01*
G01X606583Y591667D02*
X608583D01*
G01X607500Y592750D02*
Y590583D01*
G01X611600Y589833D02*
X614600Y595000D01*
G01X617617Y591667D02*
X619783D01*
G01X622467Y591000D02*
X622967Y590417D01*
X623633Y590083D01*
X624383Y590000D01*
X625050Y590083D01*
X625717Y590500D01*
X626133Y591000D01*
X626217Y591500D01*
X626050Y592083D01*
X625467Y592500D01*
X624883Y592667D01*
X624133D01*
G01X624883D02*
X625383Y592917D01*
X625800Y593333D01*
X625967Y593833D01*
X625800Y594333D01*
X625383Y594750D01*
X624633Y595000D01*
X623883Y594917D01*
X623133Y594583D01*
G01X627400Y590000D02*
Y593333D01*
G01Y592417D02*
X627650Y592833D01*
X628067Y593167D01*
X628650Y593333D01*
X629233Y593167D01*
X629650Y592833D01*
X629900Y592417D01*
Y590000D01*
G01Y592417D02*
X630150Y592833D01*
X630567Y593167D01*
X631150Y593333D01*
X631733Y593167D01*
X632150Y592833D01*
X632400Y592333D01*
Y590000D01*
G01X635500Y593333D02*
Y590000D01*
G01Y594667D02*
X635333Y594750D01*
Y594917D01*
X635500Y595000D01*
X635667Y594917D01*
Y594750D01*
X635500Y594667D01*
G01X641100Y590000D02*
Y595000D01*
G01X605417Y603500D02*
X607500Y608500D01*
X609583Y603500D01*
G01X608833Y605250D02*
X606167D01*
G01X613100Y603500D02*
Y608500D01*
G01X618700Y603500D02*
Y608500D01*
G01X624300Y603500D02*
X623800Y603583D01*
X623300Y603917D01*
X622967Y604500D01*
X622800Y605167D01*
X622967Y605833D01*
X623300Y606417D01*
X623800Y606750D01*
X624300Y606833D01*
X624800Y606750D01*
X625300Y606417D01*
X625633Y605833D01*
X625717Y605167D01*
X625633Y604500D01*
X625300Y603917D01*
X624800Y603583D01*
X624300Y603500D01*
G01X627817Y606833D02*
X628817Y603500D01*
X629900Y606833D01*
X630983Y603500D01*
X631983Y606833D01*
G01X605353Y638700D02*
Y643700D01*
X607520Y639533D01*
X609687Y643700D01*
Y638700D01*
G01X611703Y642033D02*
Y639700D01*
X612037Y639117D01*
X612537Y638783D01*
X613120Y638700D01*
X613703Y638783D01*
X614203Y639117D01*
X614537Y639700D01*
G01Y638700D02*
Y642033D01*
G01X617470Y639283D02*
X617887Y638950D01*
X618470Y638700D01*
X618970D01*
X619470Y638867D01*
X619803Y639117D01*
X619970Y639450D01*
X619887Y639950D01*
X619553Y640200D01*
X618053Y640700D01*
X617720Y641283D01*
X617887Y641700D01*
X618220Y641950D01*
X618720Y642033D01*
X619220Y641950D01*
X619720Y641700D01*
G01X624320Y643700D02*
Y638700D01*
G01X623153Y642033D02*
X625487D01*
G01X635020Y638700D02*
Y642950D01*
X635187Y643367D01*
X635520Y643617D01*
X636020Y643700D01*
X636520Y643533D01*
X636770Y643117D01*
G01X635770Y641700D02*
X634103D01*
G01X641120Y638700D02*
X640620Y638783D01*
X640120Y639117D01*
X639787Y639700D01*
X639620Y640367D01*
X639787Y641033D01*
X640120Y641617D01*
X640620Y641950D01*
X641120Y642033D01*
X641620Y641950D01*
X642120Y641617D01*
X642453Y641033D01*
X642537Y640367D01*
X642453Y639700D01*
X642120Y639117D01*
X641620Y638783D01*
X641120Y638700D01*
G01X646720D02*
Y643700D01*
G01X652320Y638700D02*
Y643700D01*
G01X657920Y638700D02*
X657420Y638783D01*
X656920Y639117D01*
X656587Y639700D01*
X656420Y640367D01*
X656587Y641033D01*
X656920Y641617D01*
X657420Y641950D01*
X657920Y642033D01*
X658420Y641950D01*
X658920Y641617D01*
X659253Y641033D01*
X659337Y640367D01*
X659253Y639700D01*
X658920Y639117D01*
X658420Y638783D01*
X657920Y638700D01*
G01X661437Y642033D02*
X662437Y638700D01*
X663520Y642033D01*
X664603Y638700D01*
X665603Y642033D01*
G01X606583Y575167D02*
X608583D01*
G01X607500Y576250D02*
Y574083D01*
G01X611517Y577667D02*
X612017Y578167D01*
X612600Y578417D01*
X613267Y578500D01*
X614100Y578333D01*
X614683Y577917D01*
X614850Y577417D01*
X614767Y576917D01*
X614433Y576500D01*
X612767Y575667D01*
X612017Y575083D01*
X611517Y574250D01*
X611350Y573500D01*
X614850D01*
G01X617200Y573333D02*
X620200Y578500D01*
G01X623217Y575167D02*
X625383D01*
G01X630900Y573500D02*
Y578500D01*
X627817Y574917D01*
X631983D01*
G01X633000Y573500D02*
Y576833D01*
G01Y575917D02*
X633250Y576333D01*
X633667Y576667D01*
X634250Y576833D01*
X634833Y576667D01*
X635250Y576333D01*
X635500Y575917D01*
Y573500D01*
G01Y575917D02*
X635750Y576333D01*
X636167Y576667D01*
X636750Y576833D01*
X637333Y576667D01*
X637750Y576333D01*
X638000Y575833D01*
Y573500D01*
G01X641100Y576833D02*
Y573500D01*
G01Y578167D02*
X640933Y578250D01*
Y578417D01*
X641100Y578500D01*
X641267Y578417D01*
Y578250D01*
X641100Y578167D01*
G01X646700Y573500D02*
Y578500D01*
G01X590417Y860000D02*
X592500Y855000D01*
X594583Y860000D01*
G01X596267Y856000D02*
X596767Y855417D01*
X597433Y855083D01*
X598183Y855000D01*
X598850Y855083D01*
X599517Y855500D01*
X599933Y856000D01*
X600017Y856500D01*
X599850Y857083D01*
X599267Y857500D01*
X598683Y857667D01*
X597933D01*
G01X598683D02*
X599183Y857917D01*
X599600Y858333D01*
X599767Y858833D01*
X599600Y859333D01*
X599183Y859750D01*
X598433Y860000D01*
X597683Y859917D01*
X596933Y859583D01*
G01X603700Y854833D02*
X603533Y854917D01*
Y855083D01*
X603700Y855167D01*
X603867Y855083D01*
Y854917D01*
X603700Y854833D01*
G01X610300Y855000D02*
Y860000D01*
X607217Y856417D01*
X611383D01*
G01X614900Y854833D02*
X614733Y854917D01*
Y855083D01*
X614900Y855167D01*
X615067Y855083D01*
Y854917D01*
X614900Y854833D01*
G01X620500Y855000D02*
Y860000D01*
X619500Y859000D01*
G01Y855000D02*
X621500D01*
G01X641317Y859167D02*
X641817Y859667D01*
X642400Y859917D01*
X643067Y860000D01*
X643900Y859833D01*
X644483Y859417D01*
X644650Y858917D01*
X644567Y858417D01*
X644233Y858000D01*
X642567Y857167D01*
X641817Y856583D01*
X641317Y855750D01*
X641150Y855000D01*
X644650D01*
G01X648500Y860000D02*
X647833Y859833D01*
X647333Y859417D01*
X647000Y858917D01*
X646750Y858250D01*
X646667Y857500D01*
X646750Y856750D01*
X647000Y856083D01*
X647333Y855583D01*
X647833Y855167D01*
X648500Y855000D01*
X649167Y855167D01*
X649667Y855583D01*
X650000Y856083D01*
X650250Y856750D01*
X650333Y857500D01*
X650250Y858250D01*
X650000Y858917D01*
X649667Y859417D01*
X649167Y859833D01*
X648500Y860000D01*
G01X654100Y855000D02*
Y860000D01*
X653100Y859000D01*
G01Y855000D02*
X655100D01*
G01X657867Y855750D02*
X658367Y855333D01*
X658950Y855083D01*
X659700Y855000D01*
X660450Y855167D01*
X661033Y855500D01*
X661450Y856083D01*
X661533Y856750D01*
X661367Y857417D01*
X660950Y857833D01*
X660367Y858167D01*
X659783Y858250D01*
X659200Y858167D01*
X658450Y857833D01*
X658700Y860000D01*
X660950D01*
G01X663800Y854833D02*
X666800Y860000D01*
G01X670900D02*
X670233Y859833D01*
X669733Y859417D01*
X669400Y858917D01*
X669150Y858250D01*
X669067Y857500D01*
X669150Y856750D01*
X669400Y856083D01*
X669733Y855583D01*
X670233Y855167D01*
X670900Y855000D01*
X671567Y855167D01*
X672067Y855583D01*
X672400Y856083D01*
X672650Y856750D01*
X672733Y857500D01*
X672650Y858250D01*
X672400Y858917D01*
X672067Y859417D01*
X671567Y859833D01*
X670900Y860000D01*
G01X674917Y857083D02*
X675500Y857667D01*
X676000Y858000D01*
X676667Y858167D01*
X677250Y858000D01*
X677667Y857667D01*
X678000Y857167D01*
X678083Y856583D01*
X678000Y856083D01*
X677667Y855583D01*
X677167Y855167D01*
X676583Y855000D01*
X675917Y855167D01*
X675333Y855667D01*
X675000Y856417D01*
X674917Y857250D01*
X675083Y858333D01*
X675333Y858917D01*
X675750Y859500D01*
X676333Y859917D01*
X676917Y860000D01*
X677500Y859833D01*
X677917Y859417D01*
G01X736937Y-65320D02*
X737437Y-65737D01*
X738020Y-65987D01*
X738770Y-66070D01*
X739520Y-65903D01*
X740103Y-65570D01*
X740520Y-64987D01*
X740603Y-64320D01*
X740437Y-63653D01*
X740020Y-63237D01*
X739437Y-62903D01*
X738853Y-62820D01*
X738270Y-62903D01*
X737520Y-63237D01*
X737770Y-61070D01*
X740020D01*
G01X744370Y-66237D02*
X744203Y-66153D01*
Y-65987D01*
X744370Y-65903D01*
X744537Y-65987D01*
Y-66153D01*
X744370Y-66237D01*
G01X749970Y-66070D02*
Y-61070D01*
X748970Y-62070D01*
G01Y-66070D02*
X750970D01*
G01X760170Y-61070D02*
X762170D01*
G01X761170D02*
Y-66070D01*
G01X760170D02*
X762170D01*
G01X766270D02*
Y-61820D01*
X766437Y-61403D01*
X766770Y-61153D01*
X767270Y-61070D01*
X767770Y-61237D01*
X768020Y-61653D01*
G01X767020Y-63070D02*
X765353D01*
G01X778470Y-63570D02*
X780137D01*
Y-65070D01*
X779637Y-65570D01*
X779053Y-65903D01*
X778220Y-66070D01*
X777387Y-65903D01*
X776803Y-65570D01*
X776303Y-65070D01*
X775970Y-64487D01*
X775803Y-63820D01*
Y-63237D01*
X775970Y-62737D01*
X776303Y-62153D01*
X776803Y-61653D01*
X777303Y-61320D01*
X777970Y-61070D01*
X778553D01*
X779220Y-61237D01*
X779720Y-61570D01*
G01X782320Y-63820D02*
X784987D01*
X784737Y-63237D01*
X784320Y-62903D01*
X783737Y-62737D01*
X783153Y-62820D01*
X782653Y-63070D01*
X782320Y-63653D01*
X782153Y-64153D01*
Y-64653D01*
X782320Y-65153D01*
X782737Y-65653D01*
X783237Y-65987D01*
X783820Y-66070D01*
X784403Y-65903D01*
X784987Y-65403D01*
G01X788003Y-66070D02*
Y-62737D01*
G01Y-63403D02*
X788420Y-63070D01*
X788837Y-62820D01*
X789420Y-62737D01*
X789837Y-62820D01*
X790337Y-63070D01*
G01X793270Y-66070D02*
Y-61070D01*
G01Y-63570D02*
X793687Y-63070D01*
X794187Y-62820D01*
X794687Y-62737D01*
X795437Y-62903D01*
X795937Y-63237D01*
X796270Y-63820D01*
Y-64487D01*
X796103Y-65153D01*
X795770Y-65653D01*
X795187Y-65987D01*
X794687Y-66070D01*
X794187Y-65987D01*
X793687Y-65737D01*
X793270Y-65320D01*
G01X799120Y-63820D02*
X801787D01*
X801537Y-63237D01*
X801120Y-62903D01*
X800537Y-62737D01*
X799953Y-62820D01*
X799453Y-63070D01*
X799120Y-63653D01*
X798953Y-64153D01*
Y-64653D01*
X799120Y-65153D01*
X799537Y-65653D01*
X800037Y-65987D01*
X800620Y-66070D01*
X801203Y-65903D01*
X801787Y-65403D01*
G01X804803Y-66070D02*
Y-62737D01*
G01Y-63403D02*
X805220Y-63070D01*
X805637Y-62820D01*
X806220Y-62737D01*
X806637Y-62820D01*
X807137Y-63070D01*
G01X815753Y-66070D02*
Y-61070D01*
G01Y-63487D02*
X816170Y-63070D01*
X816587Y-62820D01*
X817253Y-62737D01*
X817753Y-62820D01*
X818337Y-63153D01*
X818587Y-63653D01*
Y-66070D01*
G01X824270D02*
Y-62737D01*
G01Y-63320D02*
X823937Y-62987D01*
X823437Y-62820D01*
X822853Y-62737D01*
X822270Y-62903D01*
X821770Y-63237D01*
X821437Y-63737D01*
X821270Y-64403D01*
X821437Y-65070D01*
X821770Y-65570D01*
X822270Y-65903D01*
X822853Y-66070D01*
X823437Y-65987D01*
X823937Y-65737D01*
X824270Y-65403D01*
G01X827120Y-65487D02*
X827537Y-65820D01*
X828120Y-66070D01*
X828620D01*
X829120Y-65903D01*
X829453Y-65653D01*
X829620Y-65320D01*
X829537Y-64820D01*
X829203Y-64570D01*
X827703Y-64070D01*
X827370Y-63487D01*
X827537Y-63070D01*
X827870Y-62820D01*
X828370Y-62737D01*
X828870Y-62820D01*
X829370Y-63070D01*
G01X839570Y-61070D02*
Y-66070D01*
G01X838403Y-62737D02*
X840737D01*
G01X843753Y-66070D02*
Y-61070D01*
G01Y-63487D02*
X844170Y-63070D01*
X844587Y-62820D01*
X845253Y-62737D01*
X845753Y-62820D01*
X846337Y-63153D01*
X846587Y-63653D01*
Y-66070D01*
G01X850770Y-62737D02*
Y-66070D01*
G01Y-61403D02*
X850603Y-61320D01*
Y-61153D01*
X850770Y-61070D01*
X850937Y-61153D01*
Y-61320D01*
X850770Y-61403D01*
G01X855120Y-65487D02*
X855537Y-65820D01*
X856120Y-66070D01*
X856620D01*
X857120Y-65903D01*
X857453Y-65653D01*
X857620Y-65320D01*
X857537Y-64820D01*
X857203Y-64570D01*
X855703Y-64070D01*
X855370Y-63487D01*
X855537Y-63070D01*
X855870Y-62820D01*
X856370Y-62737D01*
X856870Y-62820D01*
X857370Y-63070D01*
G01X866153Y-66070D02*
Y-61070D01*
G01X868820Y-62737D02*
X866153Y-64653D01*
G01X867237Y-63903D02*
X868987Y-66070D01*
G01X873170Y-62737D02*
Y-66070D01*
G01Y-61403D02*
X873003Y-61320D01*
Y-61153D01*
X873170Y-61070D01*
X873337Y-61153D01*
Y-61320D01*
X873170Y-61403D01*
G01X877353Y-66070D02*
Y-62737D01*
G01Y-63570D02*
X877687Y-63153D01*
X878187Y-62820D01*
X878853Y-62737D01*
X879437Y-62820D01*
X879937Y-63153D01*
X880187Y-63737D01*
Y-66070D01*
G01X885870Y-61070D02*
Y-66070D01*
G01Y-65320D02*
X885537Y-65737D01*
X885037Y-65987D01*
X884453Y-66070D01*
X883787Y-65903D01*
X883287Y-65487D01*
X882953Y-64987D01*
X882870Y-64403D01*
X882953Y-63820D01*
X883287Y-63320D01*
X883787Y-62903D01*
X884453Y-62737D01*
X885037Y-62820D01*
X885453Y-62987D01*
X885870Y-63320D01*
G01X895570Y-66070D02*
X895070Y-65987D01*
X894570Y-65653D01*
X894237Y-65070D01*
X894070Y-64403D01*
X894237Y-63737D01*
X894570Y-63153D01*
X895070Y-62820D01*
X895570Y-62737D01*
X896070Y-62820D01*
X896570Y-63153D01*
X896903Y-63737D01*
X896987Y-64403D01*
X896903Y-65070D01*
X896570Y-65653D01*
X896070Y-65987D01*
X895570Y-66070D01*
G01X900670D02*
Y-61820D01*
X900837Y-61403D01*
X901170Y-61153D01*
X901670Y-61070D01*
X902170Y-61237D01*
X902420Y-61653D01*
G01X901420Y-63070D02*
X899753D01*
G01X913870Y-61070D02*
Y-66070D01*
G01Y-65320D02*
X913537Y-65737D01*
X913037Y-65987D01*
X912453Y-66070D01*
X911787Y-65903D01*
X911287Y-65487D01*
X910953Y-64987D01*
X910870Y-64403D01*
X910953Y-63820D01*
X911287Y-63320D01*
X911787Y-62903D01*
X912453Y-62737D01*
X913037Y-62820D01*
X913453Y-62987D01*
X913870Y-63320D01*
G01X916720Y-63820D02*
X919387D01*
X919137Y-63237D01*
X918720Y-62903D01*
X918137Y-62737D01*
X917553Y-62820D01*
X917053Y-63070D01*
X916720Y-63653D01*
X916553Y-64153D01*
Y-64653D01*
X916720Y-65153D01*
X917137Y-65653D01*
X917637Y-65987D01*
X918220Y-66070D01*
X918803Y-65903D01*
X919387Y-65403D01*
G01X922320Y-65487D02*
X922737Y-65820D01*
X923320Y-66070D01*
X923820D01*
X924320Y-65903D01*
X924653Y-65653D01*
X924820Y-65320D01*
X924737Y-64820D01*
X924403Y-64570D01*
X922903Y-64070D01*
X922570Y-63487D01*
X922737Y-63070D01*
X923070Y-62820D01*
X923570Y-62737D01*
X924070Y-62820D01*
X924570Y-63070D01*
G01X929170Y-62737D02*
Y-66070D01*
G01Y-61403D02*
X929003Y-61320D01*
Y-61153D01*
X929170Y-61070D01*
X929337Y-61153D01*
Y-61320D01*
X929170Y-61403D01*
G01X933603Y-67320D02*
X934187Y-67653D01*
X934853Y-67737D01*
X935437Y-67653D01*
X935937Y-67237D01*
X936270Y-66653D01*
Y-62737D01*
G01Y-63403D02*
X935937Y-63070D01*
X935437Y-62820D01*
X934853Y-62737D01*
X934187Y-62903D01*
X933770Y-63237D01*
X933437Y-63820D01*
X933270Y-64403D01*
X933353Y-64903D01*
X933687Y-65487D01*
X934187Y-65903D01*
X934853Y-66070D01*
X935353Y-65987D01*
X935937Y-65653D01*
X936270Y-65320D01*
G01X938953Y-66070D02*
Y-62737D01*
G01Y-63570D02*
X939287Y-63153D01*
X939787Y-62820D01*
X940453Y-62737D01*
X941037Y-62820D01*
X941537Y-63153D01*
X941787Y-63737D01*
Y-66070D01*
G01X945803Y-66987D02*
X946137Y-65903D01*
G01X955670Y-67737D02*
Y-62737D01*
G01Y-63487D02*
X956087Y-63070D01*
X956503Y-62820D01*
X957170Y-62737D01*
X957753Y-62820D01*
X958337Y-63237D01*
X958587Y-63820D01*
X958670Y-64403D01*
X958587Y-64987D01*
X958337Y-65570D01*
X957837Y-65903D01*
X957170Y-66070D01*
X956587Y-65987D01*
X956003Y-65737D01*
X955670Y-65403D01*
G01X962770Y-66070D02*
Y-61070D01*
G01X967120Y-63820D02*
X969787D01*
X969537Y-63237D01*
X969120Y-62903D01*
X968537Y-62737D01*
X967953Y-62820D01*
X967453Y-63070D01*
X967120Y-63653D01*
X966953Y-64153D01*
Y-64653D01*
X967120Y-65153D01*
X967537Y-65653D01*
X968037Y-65987D01*
X968620Y-66070D01*
X969203Y-65903D01*
X969787Y-65403D01*
G01X975470Y-66070D02*
Y-62737D01*
G01Y-63320D02*
X975137Y-62987D01*
X974637Y-62820D01*
X974053Y-62737D01*
X973470Y-62903D01*
X972970Y-63237D01*
X972637Y-63737D01*
X972470Y-64403D01*
X972637Y-65070D01*
X972970Y-65570D01*
X973470Y-65903D01*
X974053Y-66070D01*
X974637Y-65987D01*
X975137Y-65737D01*
X975470Y-65403D01*
G01X978320Y-65487D02*
X978737Y-65820D01*
X979320Y-66070D01*
X979820D01*
X980320Y-65903D01*
X980653Y-65653D01*
X980820Y-65320D01*
X980737Y-64820D01*
X980403Y-64570D01*
X978903Y-64070D01*
X978570Y-63487D01*
X978737Y-63070D01*
X979070Y-62820D01*
X979570Y-62737D01*
X980070Y-62820D01*
X980570Y-63070D01*
G01X983920Y-63820D02*
X986587D01*
X986337Y-63237D01*
X985920Y-62903D01*
X985337Y-62737D01*
X984753Y-62820D01*
X984253Y-63070D01*
X983920Y-63653D01*
X983753Y-64153D01*
Y-64653D01*
X983920Y-65153D01*
X984337Y-65653D01*
X984837Y-65987D01*
X985420Y-66070D01*
X986003Y-65903D01*
X986587Y-65403D01*
G01X995870Y-66070D02*
Y-61820D01*
X996037Y-61403D01*
X996370Y-61153D01*
X996870Y-61070D01*
X997370Y-61237D01*
X997620Y-61653D01*
G01X996620Y-63070D02*
X994953D01*
G01X1001970Y-66070D02*
X1001470Y-65987D01*
X1000970Y-65653D01*
X1000637Y-65070D01*
X1000470Y-64403D01*
X1000637Y-63737D01*
X1000970Y-63153D01*
X1001470Y-62820D01*
X1001970Y-62737D01*
X1002470Y-62820D01*
X1002970Y-63153D01*
X1003303Y-63737D01*
X1003387Y-64403D01*
X1003303Y-65070D01*
X1002970Y-65653D01*
X1002470Y-65987D01*
X1001970Y-66070D01*
G01X1007570D02*
Y-61070D01*
G01X1013170Y-66070D02*
Y-61070D01*
G01X1018770Y-66070D02*
X1018270Y-65987D01*
X1017770Y-65653D01*
X1017437Y-65070D01*
X1017270Y-64403D01*
X1017437Y-63737D01*
X1017770Y-63153D01*
X1018270Y-62820D01*
X1018770Y-62737D01*
X1019270Y-62820D01*
X1019770Y-63153D01*
X1020103Y-63737D01*
X1020187Y-64403D01*
X1020103Y-65070D01*
X1019770Y-65653D01*
X1019270Y-65987D01*
X1018770Y-66070D01*
G01X1022287Y-62737D02*
X1023287Y-66070D01*
X1024370Y-62737D01*
X1025453Y-66070D01*
X1026453Y-62737D01*
G01X1029970Y-66237D02*
X1029803Y-66153D01*
Y-65987D01*
X1029970Y-65903D01*
X1030137Y-65987D01*
Y-66153D01*
X1029970Y-66237D01*
G01X1040170Y-61070D02*
X1042170D01*
G01X1041170D02*
Y-66070D01*
G01X1040170D02*
X1042170D01*
G01X1046270D02*
Y-61820D01*
X1046437Y-61403D01*
X1046770Y-61153D01*
X1047270Y-61070D01*
X1047770Y-61237D01*
X1048020Y-61653D01*
G01X1047020Y-63070D02*
X1045353D01*
G01X1056553Y-66070D02*
Y-62737D01*
G01Y-63570D02*
X1056887Y-63153D01*
X1057387Y-62820D01*
X1058053Y-62737D01*
X1058637Y-62820D01*
X1059137Y-63153D01*
X1059387Y-63737D01*
Y-66070D01*
G01X1063570D02*
X1063070Y-65987D01*
X1062570Y-65653D01*
X1062237Y-65070D01*
X1062070Y-64403D01*
X1062237Y-63737D01*
X1062570Y-63153D01*
X1063070Y-62820D01*
X1063570Y-62737D01*
X1064070Y-62820D01*
X1064570Y-63153D01*
X1064903Y-63737D01*
X1064987Y-64403D01*
X1064903Y-65070D01*
X1064570Y-65653D01*
X1064070Y-65987D01*
X1063570Y-66070D01*
G01X1069170Y-61070D02*
Y-66070D01*
G01X1068003Y-62737D02*
X1070337D01*
G01X1074603Y-66987D02*
X1074937Y-65903D01*
G01X1084470Y-67737D02*
Y-62737D01*
G01Y-63487D02*
X1084887Y-63070D01*
X1085303Y-62820D01*
X1085970Y-62737D01*
X1086553Y-62820D01*
X1087137Y-63237D01*
X1087387Y-63820D01*
X1087470Y-64403D01*
X1087387Y-64987D01*
X1087137Y-65570D01*
X1086637Y-65903D01*
X1085970Y-66070D01*
X1085387Y-65987D01*
X1084803Y-65737D01*
X1084470Y-65403D01*
G01X1091570Y-66070D02*
Y-61070D01*
G01X1095920Y-63820D02*
X1098587D01*
X1098337Y-63237D01*
X1097920Y-62903D01*
X1097337Y-62737D01*
X1096753Y-62820D01*
X1096253Y-63070D01*
X1095920Y-63653D01*
X1095753Y-64153D01*
Y-64653D01*
X1095920Y-65153D01*
X1096337Y-65653D01*
X1096837Y-65987D01*
X1097420Y-66070D01*
X1098003Y-65903D01*
X1098587Y-65403D01*
G01X1104270Y-66070D02*
Y-62737D01*
G01Y-63320D02*
X1103937Y-62987D01*
X1103437Y-62820D01*
X1102853Y-62737D01*
X1102270Y-62903D01*
X1101770Y-63237D01*
X1101437Y-63737D01*
X1101270Y-64403D01*
X1101437Y-65070D01*
X1101770Y-65570D01*
X1102270Y-65903D01*
X1102853Y-66070D01*
X1103437Y-65987D01*
X1103937Y-65737D01*
X1104270Y-65403D01*
G01X1107120Y-65487D02*
X1107537Y-65820D01*
X1108120Y-66070D01*
X1108620D01*
X1109120Y-65903D01*
X1109453Y-65653D01*
X1109620Y-65320D01*
X1109537Y-64820D01*
X1109203Y-64570D01*
X1107703Y-64070D01*
X1107370Y-63487D01*
X1107537Y-63070D01*
X1107870Y-62820D01*
X1108370Y-62737D01*
X1108870Y-62820D01*
X1109370Y-63070D01*
G01X1112720Y-63820D02*
X1115387D01*
X1115137Y-63237D01*
X1114720Y-62903D01*
X1114137Y-62737D01*
X1113553Y-62820D01*
X1113053Y-63070D01*
X1112720Y-63653D01*
X1112553Y-64153D01*
Y-64653D01*
X1112720Y-65153D01*
X1113137Y-65653D01*
X1113637Y-65987D01*
X1114220Y-66070D01*
X1114803Y-65903D01*
X1115387Y-65403D01*
G01X1125170Y-62737D02*
Y-66070D01*
G01Y-61403D02*
X1125003Y-61320D01*
Y-61153D01*
X1125170Y-61070D01*
X1125337Y-61153D01*
Y-61320D01*
X1125170Y-61403D01*
G01X1132270Y-67737D02*
Y-62737D01*
G01Y-63487D02*
X1131853Y-63070D01*
X1131353Y-62820D01*
X1130770Y-62737D01*
X1130270Y-62820D01*
X1129687Y-63237D01*
X1129353Y-63820D01*
X1129270Y-64403D01*
X1129353Y-64987D01*
X1129687Y-65570D01*
X1130270Y-65987D01*
X1130770Y-66070D01*
X1131353Y-65987D01*
X1131853Y-65737D01*
X1132270Y-65320D01*
G01X1134953Y-66070D02*
Y-62737D01*
G01Y-63570D02*
X1135287Y-63153D01*
X1135787Y-62820D01*
X1136453Y-62737D01*
X1137037Y-62820D01*
X1137537Y-63153D01*
X1137787Y-63737D01*
Y-66070D01*
G01X1141970D02*
X1141470Y-65987D01*
X1140970Y-65653D01*
X1140637Y-65070D01*
X1140470Y-64403D01*
X1140637Y-63737D01*
X1140970Y-63153D01*
X1141470Y-62820D01*
X1141970Y-62737D01*
X1142470Y-62820D01*
X1142970Y-63153D01*
X1143303Y-63737D01*
X1143387Y-64403D01*
X1143303Y-65070D01*
X1142970Y-65653D01*
X1142470Y-65987D01*
X1141970Y-66070D01*
G01X1146403D02*
Y-62737D01*
G01Y-63403D02*
X1146820Y-63070D01*
X1147237Y-62820D01*
X1147820Y-62737D01*
X1148237Y-62820D01*
X1148737Y-63070D01*
G01X1151920Y-63820D02*
X1154587D01*
X1154337Y-63237D01*
X1153920Y-62903D01*
X1153337Y-62737D01*
X1152753Y-62820D01*
X1152253Y-63070D01*
X1151920Y-63653D01*
X1151753Y-64153D01*
Y-64653D01*
X1151920Y-65153D01*
X1152337Y-65653D01*
X1152837Y-65987D01*
X1153420Y-66070D01*
X1154003Y-65903D01*
X1154587Y-65403D01*
G01X1164370Y-61070D02*
Y-66070D01*
G01X1163203Y-62737D02*
X1165537D01*
G01X1168553Y-66070D02*
Y-61070D01*
G01Y-63487D02*
X1168970Y-63070D01*
X1169387Y-62820D01*
X1170053Y-62737D01*
X1170553Y-62820D01*
X1171137Y-63153D01*
X1171387Y-63653D01*
Y-66070D01*
G01X1175570Y-62737D02*
Y-66070D01*
G01Y-61403D02*
X1175403Y-61320D01*
Y-61153D01*
X1175570Y-61070D01*
X1175737Y-61153D01*
Y-61320D01*
X1175570Y-61403D01*
G01X1179920Y-65487D02*
X1180337Y-65820D01*
X1180920Y-66070D01*
X1181420D01*
X1181920Y-65903D01*
X1182253Y-65653D01*
X1182420Y-65320D01*
X1182337Y-64820D01*
X1182003Y-64570D01*
X1180503Y-64070D01*
X1180170Y-63487D01*
X1180337Y-63070D01*
X1180670Y-62820D01*
X1181170Y-62737D01*
X1181670Y-62820D01*
X1182170Y-63070D01*
G01X1191203Y-66070D02*
Y-62737D01*
G01Y-63403D02*
X1191620Y-63070D01*
X1192037Y-62820D01*
X1192620Y-62737D01*
X1193037Y-62820D01*
X1193537Y-63070D01*
G01X1196720Y-63820D02*
X1199387D01*
X1199137Y-63237D01*
X1198720Y-62903D01*
X1198137Y-62737D01*
X1197553Y-62820D01*
X1197053Y-63070D01*
X1196720Y-63653D01*
X1196553Y-64153D01*
Y-64653D01*
X1196720Y-65153D01*
X1197137Y-65653D01*
X1197637Y-65987D01*
X1198220Y-66070D01*
X1198803Y-65903D01*
X1199387Y-65403D01*
G01X1205070Y-67737D02*
Y-62737D01*
G01Y-63487D02*
X1204653Y-63070D01*
X1204153Y-62820D01*
X1203570Y-62737D01*
X1203070Y-62820D01*
X1202487Y-63237D01*
X1202153Y-63820D01*
X1202070Y-64403D01*
X1202153Y-64987D01*
X1202487Y-65570D01*
X1203070Y-65987D01*
X1203570Y-66070D01*
X1204153Y-65987D01*
X1204653Y-65737D01*
X1205070Y-65320D01*
G01X1207753Y-62737D02*
Y-65070D01*
X1208087Y-65653D01*
X1208587Y-65987D01*
X1209170Y-66070D01*
X1209753Y-65987D01*
X1210253Y-65653D01*
X1210587Y-65070D01*
G01Y-66070D02*
Y-62737D01*
G01X1213520Y-63820D02*
X1216187D01*
X1215937Y-63237D01*
X1215520Y-62903D01*
X1214937Y-62737D01*
X1214353Y-62820D01*
X1213853Y-63070D01*
X1213520Y-63653D01*
X1213353Y-64153D01*
Y-64653D01*
X1213520Y-65153D01*
X1213937Y-65653D01*
X1214437Y-65987D01*
X1215020Y-66070D01*
X1215603Y-65903D01*
X1216187Y-65403D01*
G01X1219120Y-65487D02*
X1219537Y-65820D01*
X1220120Y-66070D01*
X1220620D01*
X1221120Y-65903D01*
X1221453Y-65653D01*
X1221620Y-65320D01*
X1221537Y-64820D01*
X1221203Y-64570D01*
X1219703Y-64070D01*
X1219370Y-63487D01*
X1219537Y-63070D01*
X1219870Y-62820D01*
X1220370Y-62737D01*
X1220870Y-62820D01*
X1221370Y-63070D01*
G01X1225970Y-61070D02*
Y-66070D01*
G01X1224803Y-62737D02*
X1227137D01*
G01X1231570Y-66237D02*
X1231403Y-66153D01*
Y-65987D01*
X1231570Y-65903D01*
X1231737Y-65987D01*
Y-66153D01*
X1231570Y-66237D01*
G01X722667Y-38250D02*
X723167Y-38667D01*
X723750Y-38917D01*
X724500Y-39000D01*
X725250Y-38833D01*
X725833Y-38500D01*
X726250Y-37917D01*
X726333Y-37250D01*
X726167Y-36583D01*
X725750Y-36167D01*
X725167Y-35833D01*
X724583Y-35750D01*
X724000Y-35833D01*
X723250Y-36167D01*
X723500Y-34000D01*
X725750D01*
G01X730100Y-39167D02*
X729933Y-39083D01*
Y-38917D01*
X730100Y-38833D01*
X730267Y-38917D01*
Y-39083D01*
X730100Y-39167D01*
G01X739633Y-39000D02*
Y-34000D01*
X741717D01*
X742383Y-34250D01*
X742800Y-34583D01*
X742967Y-35250D01*
X742800Y-35917D01*
X742300Y-36333D01*
X741717Y-36583D01*
X739633D01*
G01X741717D02*
X742967Y-39000D01*
G01X745650Y-36750D02*
X748317D01*
X748067Y-36167D01*
X747650Y-35833D01*
X747067Y-35667D01*
X746483Y-35750D01*
X745983Y-36000D01*
X745650Y-36583D01*
X745483Y-37083D01*
Y-37583D01*
X745650Y-38083D01*
X746067Y-38583D01*
X746567Y-38917D01*
X747150Y-39000D01*
X747733Y-38833D01*
X748317Y-38333D01*
G01X750000Y-39000D02*
Y-35667D01*
G01Y-36583D02*
X750250Y-36167D01*
X750667Y-35833D01*
X751250Y-35667D01*
X751833Y-35833D01*
X752250Y-36167D01*
X752500Y-36583D01*
Y-39000D01*
G01Y-36583D02*
X752750Y-36167D01*
X753167Y-35833D01*
X753750Y-35667D01*
X754333Y-35833D01*
X754750Y-36167D01*
X755000Y-36667D01*
Y-39000D01*
G01X759600D02*
Y-35667D01*
G01Y-36250D02*
X759267Y-35917D01*
X758767Y-35750D01*
X758183Y-35667D01*
X757600Y-35833D01*
X757100Y-36167D01*
X756767Y-36667D01*
X756600Y-37333D01*
X756767Y-38000D01*
X757100Y-38500D01*
X757600Y-38833D01*
X758183Y-39000D01*
X758767Y-38917D01*
X759267Y-38667D01*
X759600Y-38333D01*
G01X762533Y-39000D02*
Y-35667D01*
G01Y-36333D02*
X762950Y-36000D01*
X763367Y-35750D01*
X763950Y-35667D01*
X764367Y-35750D01*
X764867Y-36000D01*
G01X767883Y-39000D02*
Y-34000D01*
G01X770550Y-35667D02*
X767883Y-37583D01*
G01X768967Y-36833D02*
X770717Y-39000D01*
G01X773067Y-39167D02*
X776733Y-35500D01*
G01X774900Y-34833D02*
Y-39833D01*
G01X776733Y-39167D02*
X773067Y-35500D01*
G01X772400Y-37333D02*
X777400D01*
G01X713000Y-53000D02*
X1343000D01*
G01X713000Y-23000D02*
X1343000D01*
G01X713000Y850500D02*
Y-73000D01*
X1343000D01*
Y782000D01*
X713000D01*
G01X694500Y716000D02*
Y-69500D01*
G01X713000Y85500D02*
X1343000D01*
G01X721407Y374673D02*
X725073Y378340D01*
G01X723240Y379007D02*
Y374007D01*
G01X725073Y374673D02*
X721407Y378340D01*
G01X720740Y376507D02*
X725740D01*
G01X728423Y373173D02*
X727590Y374007D01*
X727173Y374840D01*
Y378173D01*
X727590Y379007D01*
X728423Y379840D01*
G01X732607Y375590D02*
X733107Y375173D01*
X733690Y374923D01*
X734440Y374840D01*
X735190Y375007D01*
X735773Y375340D01*
X736190Y375923D01*
X736273Y376590D01*
X736107Y377257D01*
X735690Y377673D01*
X735107Y378007D01*
X734523Y378090D01*
X733940Y378007D01*
X733190Y377673D01*
X733440Y379840D01*
X735690D01*
G01X740040Y374673D02*
X739873Y374757D01*
Y374923D01*
X740040Y375007D01*
X740207Y374923D01*
Y374757D01*
X740040Y374673D01*
G01X745640Y374840D02*
Y379840D01*
X744640Y378840D01*
G01Y374840D02*
X746640D01*
G01X751657Y373173D02*
X752490Y374007D01*
X752907Y374840D01*
Y378173D01*
X752490Y379007D01*
X751657Y379840D01*
G01X725500Y349500D02*
Y354500D01*
X722417Y350917D01*
X726583D01*
G01X730100Y349333D02*
X729933Y349417D01*
Y349583D01*
X730100Y349667D01*
X730267Y349583D01*
Y349417D01*
X730100Y349333D01*
G01X739800Y349500D02*
Y354500D01*
G01Y352000D02*
X740217Y352500D01*
X740717Y352750D01*
X741217Y352833D01*
X741967Y352667D01*
X742467Y352333D01*
X742800Y351750D01*
Y351083D01*
X742633Y350417D01*
X742300Y349917D01*
X741717Y349583D01*
X741217Y349500D01*
X740717Y349583D01*
X740217Y349833D01*
X739800Y350250D01*
G01X748400Y349500D02*
Y352833D01*
G01Y352250D02*
X748067Y352583D01*
X747567Y352750D01*
X746983Y352833D01*
X746400Y352667D01*
X745900Y352333D01*
X745567Y351833D01*
X745400Y351167D01*
X745567Y350500D01*
X745900Y350000D01*
X746400Y349667D01*
X746983Y349500D01*
X747567Y349583D01*
X748067Y349833D01*
X748400Y350167D01*
G01X753833Y352417D02*
X753250Y352750D01*
X752750Y352833D01*
X752083Y352667D01*
X751583Y352333D01*
X751250Y351750D01*
X751167Y351167D01*
X751250Y350583D01*
X751583Y350083D01*
X752083Y349667D01*
X752750Y349500D01*
X753333Y349667D01*
X753833Y350000D01*
G01X756683Y349500D02*
Y354500D01*
G01X759350Y352833D02*
X756683Y350917D01*
G01X757767Y351667D02*
X759517Y349500D01*
G01X765200Y354500D02*
Y349500D01*
G01Y350250D02*
X764867Y349833D01*
X764367Y349583D01*
X763783Y349500D01*
X763117Y349667D01*
X762617Y350083D01*
X762283Y350583D01*
X762200Y351167D01*
X762283Y351750D01*
X762617Y352250D01*
X763117Y352667D01*
X763783Y352833D01*
X764367Y352750D01*
X764783Y352583D01*
X765200Y352250D01*
G01X768133Y349500D02*
Y352833D01*
G01Y352167D02*
X768550Y352500D01*
X768967Y352750D01*
X769550Y352833D01*
X769967Y352750D01*
X770467Y352500D01*
G01X774900Y352833D02*
Y349500D01*
G01Y354167D02*
X774733Y354250D01*
Y354417D01*
X774900Y354500D01*
X775067Y354417D01*
Y354250D01*
X774900Y354167D01*
G01X780500Y349500D02*
Y354500D01*
G01X786100Y349500D02*
Y354500D01*
G01X798800Y349500D02*
Y352833D01*
G01Y352250D02*
X798467Y352583D01*
X797967Y352750D01*
X797383Y352833D01*
X796800Y352667D01*
X796300Y352333D01*
X795967Y351833D01*
X795800Y351167D01*
X795967Y350500D01*
X796300Y350000D01*
X796800Y349667D01*
X797383Y349500D01*
X797967Y349583D01*
X798467Y349833D01*
X798800Y350167D01*
G01X801483Y349500D02*
Y352833D01*
G01Y352000D02*
X801817Y352417D01*
X802317Y352750D01*
X802983Y352833D01*
X803567Y352750D01*
X804067Y352417D01*
X804317Y351833D01*
Y349500D01*
G01X810000Y354500D02*
Y349500D01*
G01Y350250D02*
X809667Y349833D01*
X809167Y349583D01*
X808583Y349500D01*
X807917Y349667D01*
X807417Y350083D01*
X807083Y350583D01*
X807000Y351167D01*
X807083Y351750D01*
X807417Y352250D01*
X807917Y352667D01*
X808583Y352833D01*
X809167Y352750D01*
X809583Y352583D01*
X810000Y352250D01*
G01X818450Y350083D02*
X818867Y349750D01*
X819450Y349500D01*
X819950D01*
X820450Y349667D01*
X820783Y349917D01*
X820950Y350250D01*
X820867Y350750D01*
X820533Y351000D01*
X819033Y351500D01*
X818700Y352083D01*
X818867Y352500D01*
X819200Y352750D01*
X819700Y352833D01*
X820200Y352750D01*
X820700Y352500D01*
G01X826800Y347833D02*
Y352833D01*
G01Y352083D02*
X826383Y352500D01*
X825883Y352750D01*
X825300Y352833D01*
X824800Y352750D01*
X824217Y352333D01*
X823883Y351750D01*
X823800Y351167D01*
X823883Y350583D01*
X824217Y350000D01*
X824800Y349583D01*
X825300Y349500D01*
X825883Y349583D01*
X826383Y349833D01*
X826800Y350250D01*
G01X829483Y352833D02*
Y350500D01*
X829817Y349917D01*
X830317Y349583D01*
X830900Y349500D01*
X831483Y349583D01*
X831983Y349917D01*
X832317Y350500D01*
G01Y349500D02*
Y352833D01*
G01X838000Y349500D02*
Y352833D01*
G01Y352250D02*
X837667Y352583D01*
X837167Y352750D01*
X836583Y352833D01*
X836000Y352667D01*
X835500Y352333D01*
X835167Y351833D01*
X835000Y351167D01*
X835167Y350500D01*
X835500Y350000D01*
X836000Y349667D01*
X836583Y349500D01*
X837167Y349583D01*
X837667Y349833D01*
X838000Y350167D01*
G01X840933Y349500D02*
Y352833D01*
G01Y352167D02*
X841350Y352500D01*
X841767Y352750D01*
X842350Y352833D01*
X842767Y352750D01*
X843267Y352500D01*
G01X846450Y351750D02*
X849117D01*
X848867Y352333D01*
X848450Y352667D01*
X847867Y352833D01*
X847283Y352750D01*
X846783Y352500D01*
X846450Y351917D01*
X846283Y351417D01*
Y350917D01*
X846450Y350417D01*
X846867Y349917D01*
X847367Y349583D01*
X847950Y349500D01*
X848533Y349667D01*
X849117Y350167D01*
G01X857483Y349500D02*
Y354500D01*
G01Y352083D02*
X857900Y352500D01*
X858317Y352750D01*
X858983Y352833D01*
X859483Y352750D01*
X860067Y352417D01*
X860317Y351917D01*
Y349500D01*
G01X864500D02*
X864000Y349583D01*
X863500Y349917D01*
X863167Y350500D01*
X863000Y351167D01*
X863167Y351833D01*
X863500Y352417D01*
X864000Y352750D01*
X864500Y352833D01*
X865000Y352750D01*
X865500Y352417D01*
X865833Y351833D01*
X865917Y351167D01*
X865833Y350500D01*
X865500Y349917D01*
X865000Y349583D01*
X864500Y349500D01*
G01X870100D02*
Y354500D01*
G01X874450Y351750D02*
X877117D01*
X876867Y352333D01*
X876450Y352667D01*
X875867Y352833D01*
X875283Y352750D01*
X874783Y352500D01*
X874450Y351917D01*
X874283Y351417D01*
Y350917D01*
X874450Y350417D01*
X874867Y349917D01*
X875367Y349583D01*
X875950Y349500D01*
X876533Y349667D01*
X877117Y350167D01*
G01X881300Y349333D02*
X881133Y349417D01*
Y349583D01*
X881300Y349667D01*
X881467Y349583D01*
Y349417D01*
X881300Y349333D01*
G01Y351583D02*
X881133Y351667D01*
Y351833D01*
X881300Y351917D01*
X881467Y351833D01*
Y351667D01*
X881300Y351583D01*
G01X713000Y335500D02*
X1343000D01*
G01X713000Y365500D02*
X1343000D01*
G01X721107Y408303D02*
X724773Y411970D01*
G01X722940Y412637D02*
Y407637D01*
G01X724773Y408303D02*
X721107Y411970D01*
G01X720440Y410137D02*
X725440D01*
G01X728123Y406803D02*
X727290Y407637D01*
X726873Y408470D01*
Y411803D01*
X727290Y412637D01*
X728123Y413470D01*
G01X732307Y409220D02*
X732807Y408803D01*
X733390Y408553D01*
X734140Y408470D01*
X734890Y408637D01*
X735473Y408970D01*
X735890Y409553D01*
X735973Y410220D01*
X735807Y410887D01*
X735390Y411303D01*
X734807Y411637D01*
X734223Y411720D01*
X733640Y411637D01*
X732890Y411303D01*
X733140Y413470D01*
X735390D01*
G01X739740Y408303D02*
X739573Y408387D01*
Y408553D01*
X739740Y408637D01*
X739907Y408553D01*
Y408387D01*
X739740Y408303D01*
G01X745340Y408470D02*
Y413470D01*
X744340Y412470D01*
G01Y408470D02*
X746340D01*
G01X751357Y406803D02*
X752190Y407637D01*
X752607Y408470D01*
Y411803D01*
X752190Y412637D01*
X751357Y413470D01*
G01X721217Y391740D02*
X723300Y386740D01*
X725383Y391740D01*
G01X728900Y390073D02*
Y386740D01*
G01Y391407D02*
X728733Y391490D01*
Y391657D01*
X728900Y391740D01*
X729067Y391657D01*
Y391490D01*
X728900Y391407D01*
G01X736000Y386740D02*
Y390073D01*
G01Y389490D02*
X735667Y389823D01*
X735167Y389990D01*
X734583Y390073D01*
X734000Y389907D01*
X733500Y389573D01*
X733167Y389073D01*
X733000Y388407D01*
X733167Y387740D01*
X733500Y387240D01*
X734000Y386907D01*
X734583Y386740D01*
X735167Y386823D01*
X735667Y387073D01*
X736000Y387407D01*
G01X744700Y391740D02*
X746700D01*
G01X745700D02*
Y386740D01*
G01X744700D02*
X746700D01*
G01X749883D02*
Y390073D01*
G01Y389240D02*
X750217Y389657D01*
X750717Y389990D01*
X751383Y390073D01*
X751967Y389990D01*
X752467Y389657D01*
X752717Y389073D01*
Y386740D01*
G01X760833D02*
Y391740D01*
X762833D01*
X763500Y391490D01*
X764000Y390907D01*
X764167Y390240D01*
X764000Y389573D01*
X763583Y389073D01*
X762833Y388823D01*
X760833D01*
G01X769600Y386740D02*
Y390073D01*
G01Y389490D02*
X769267Y389823D01*
X768767Y389990D01*
X768183Y390073D01*
X767600Y389907D01*
X767100Y389573D01*
X766767Y389073D01*
X766600Y388407D01*
X766767Y387740D01*
X767100Y387240D01*
X767600Y386907D01*
X768183Y386740D01*
X768767Y386823D01*
X769267Y387073D01*
X769600Y387407D01*
G01X775200Y391740D02*
Y386740D01*
G01Y387490D02*
X774867Y387073D01*
X774367Y386823D01*
X773783Y386740D01*
X773117Y386907D01*
X772617Y387323D01*
X772283Y387823D01*
X772200Y388407D01*
X772283Y388990D01*
X772617Y389490D01*
X773117Y389907D01*
X773783Y390073D01*
X774367Y389990D01*
X774783Y389823D01*
X775200Y389490D01*
G01X778883Y385073D02*
X778050Y385907D01*
X777633Y386740D01*
Y390073D01*
X778050Y390907D01*
X778883Y391740D01*
G01X782817D02*
X784900Y386740D01*
X786983Y391740D01*
G01X789500D02*
X791500D01*
G01X790500D02*
Y386740D01*
G01X789500D02*
X791500D01*
G01X794433D02*
Y391740D01*
X796433D01*
X797100Y391490D01*
X797600Y390907D01*
X797767Y390240D01*
X797600Y389573D01*
X797183Y389073D01*
X796433Y388823D01*
X794433D01*
G01X802117Y385073D02*
X802950Y385907D01*
X803367Y386740D01*
Y390073D01*
X802950Y390907D01*
X802117Y391740D01*
G01X720917Y424500D02*
X723000Y419500D01*
X725083Y424500D01*
G01X728600Y422833D02*
Y419500D01*
G01Y424167D02*
X728433Y424250D01*
Y424417D01*
X728600Y424500D01*
X728767Y424417D01*
Y424250D01*
X728600Y424167D01*
G01X735700Y419500D02*
Y422833D01*
G01Y422250D02*
X735367Y422583D01*
X734867Y422750D01*
X734283Y422833D01*
X733700Y422667D01*
X733200Y422333D01*
X732867Y421833D01*
X732700Y421167D01*
X732867Y420500D01*
X733200Y420000D01*
X733700Y419667D01*
X734283Y419500D01*
X734867Y419583D01*
X735367Y419833D01*
X735700Y420167D01*
G01X745400Y419500D02*
X744733Y419583D01*
X744150Y419917D01*
X743650Y420417D01*
X743317Y421000D01*
X743150Y421667D01*
Y422333D01*
X743317Y423000D01*
X743650Y423583D01*
X744150Y424083D01*
X744733Y424417D01*
X745400Y424500D01*
X746067Y424417D01*
X746650Y424083D01*
X747150Y423583D01*
X747483Y423000D01*
X747650Y422333D01*
Y421667D01*
X747483Y421000D01*
X747150Y420417D01*
X746650Y419917D01*
X746067Y419583D01*
X745400Y419500D01*
G01X749583D02*
Y422833D01*
G01Y422000D02*
X749917Y422417D01*
X750417Y422750D01*
X751083Y422833D01*
X751667Y422750D01*
X752167Y422417D01*
X752417Y421833D01*
Y419500D01*
G01X760533D02*
Y424500D01*
X762533D01*
X763200Y424250D01*
X763700Y423667D01*
X763867Y423000D01*
X763700Y422333D01*
X763283Y421833D01*
X762533Y421583D01*
X760533D01*
G01X769300Y419500D02*
Y422833D01*
G01Y422250D02*
X768967Y422583D01*
X768467Y422750D01*
X767883Y422833D01*
X767300Y422667D01*
X766800Y422333D01*
X766467Y421833D01*
X766300Y421167D01*
X766467Y420500D01*
X766800Y420000D01*
X767300Y419667D01*
X767883Y419500D01*
X768467Y419583D01*
X768967Y419833D01*
X769300Y420167D01*
G01X774900Y424500D02*
Y419500D01*
G01Y420250D02*
X774567Y419833D01*
X774067Y419583D01*
X773483Y419500D01*
X772817Y419667D01*
X772317Y420083D01*
X771983Y420583D01*
X771900Y421167D01*
X771983Y421750D01*
X772317Y422250D01*
X772817Y422667D01*
X773483Y422833D01*
X774067Y422750D01*
X774483Y422583D01*
X774900Y422250D01*
G01X778583Y417833D02*
X777750Y418667D01*
X777333Y419500D01*
Y422833D01*
X777750Y423667D01*
X778583Y424500D01*
G01X782517D02*
X784600Y419500D01*
X786683Y424500D01*
G01X790200Y419500D02*
X789533Y419583D01*
X788950Y419917D01*
X788450Y420417D01*
X788117Y421000D01*
X787950Y421667D01*
Y422333D01*
X788117Y423000D01*
X788450Y423583D01*
X788950Y424083D01*
X789533Y424417D01*
X790200Y424500D01*
X790867Y424417D01*
X791450Y424083D01*
X791950Y423583D01*
X792283Y423000D01*
X792450Y422333D01*
Y421667D01*
X792283Y421000D01*
X791950Y420417D01*
X791450Y419917D01*
X790867Y419583D01*
X790200Y419500D01*
G01X794133D02*
Y424500D01*
X796133D01*
X796800Y424250D01*
X797300Y423667D01*
X797467Y423000D01*
X797300Y422333D01*
X796883Y421833D01*
X796133Y421583D01*
X794133D01*
G01X801817Y417833D02*
X802650Y418667D01*
X803067Y419500D01*
Y422833D01*
X802650Y423667D01*
X801817Y424500D01*
G01X723667Y443167D02*
X724000Y443417D01*
X724250Y443833D01*
X724417Y444417D01*
X724250Y444917D01*
X723917Y445250D01*
X723333Y445500D01*
X721083D01*
Y440500D01*
X723833D01*
X724417Y440833D01*
X724750Y441333D01*
X724917Y441917D01*
X724750Y442500D01*
X724250Y443000D01*
X723667Y443167D01*
X721083D01*
G01X727183Y443833D02*
Y441500D01*
X727517Y440917D01*
X728017Y440583D01*
X728600Y440500D01*
X729183Y440583D01*
X729683Y440917D01*
X730017Y441500D01*
G01Y440500D02*
Y443833D01*
G01X733033Y440500D02*
Y443833D01*
G01Y443167D02*
X733450Y443500D01*
X733867Y443750D01*
X734450Y443833D01*
X734867Y443750D01*
X735367Y443500D01*
G01X739800Y443833D02*
Y440500D01*
G01Y445167D02*
X739633Y445250D01*
Y445417D01*
X739800Y445500D01*
X739967Y445417D01*
Y445250D01*
X739800Y445167D01*
G01X744150Y442750D02*
X746817D01*
X746567Y443333D01*
X746150Y443667D01*
X745567Y443833D01*
X744983Y443750D01*
X744483Y443500D01*
X744150Y442917D01*
X743983Y442417D01*
Y441917D01*
X744150Y441417D01*
X744567Y440917D01*
X745067Y440583D01*
X745650Y440500D01*
X746233Y440667D01*
X746817Y441167D01*
G01X752500Y445500D02*
Y440500D01*
G01Y441250D02*
X752167Y440833D01*
X751667Y440583D01*
X751083Y440500D01*
X750417Y440667D01*
X749917Y441083D01*
X749583Y441583D01*
X749500Y442167D01*
X749583Y442750D01*
X749917Y443250D01*
X750417Y443667D01*
X751083Y443833D01*
X751667Y443750D01*
X752083Y443583D01*
X752500Y443250D01*
G01X760783Y440500D02*
Y445500D01*
G01Y443083D02*
X761200Y443500D01*
X761617Y443750D01*
X762283Y443833D01*
X762783Y443750D01*
X763367Y443417D01*
X763617Y442917D01*
Y440500D01*
G01X767800D02*
X767300Y440583D01*
X766800Y440917D01*
X766467Y441500D01*
X766300Y442167D01*
X766467Y442833D01*
X766800Y443417D01*
X767300Y443750D01*
X767800Y443833D01*
X768300Y443750D01*
X768800Y443417D01*
X769133Y442833D01*
X769217Y442167D01*
X769133Y441500D01*
X768800Y440917D01*
X768300Y440583D01*
X767800Y440500D01*
G01X773400D02*
Y445500D01*
G01X777750Y442750D02*
X780417D01*
X780167Y443333D01*
X779750Y443667D01*
X779167Y443833D01*
X778583Y443750D01*
X778083Y443500D01*
X777750Y442917D01*
X777583Y442417D01*
Y441917D01*
X777750Y441417D01*
X778167Y440917D01*
X778667Y440583D01*
X779250Y440500D01*
X779833Y440667D01*
X780417Y441167D01*
G01X721417Y461500D02*
Y466500D01*
X724583D01*
G01X723417Y464083D02*
X721417D01*
G01X727183Y464833D02*
Y462500D01*
X727517Y461917D01*
X728017Y461583D01*
X728600Y461500D01*
X729183Y461583D01*
X729683Y461917D01*
X730017Y462500D01*
G01Y461500D02*
Y464833D01*
G01X734200Y461500D02*
Y466500D01*
G01X739800Y461500D02*
Y466500D01*
G01X749500Y459833D02*
Y464833D01*
G01Y464083D02*
X749917Y464500D01*
X750333Y464750D01*
X751000Y464833D01*
X751583Y464750D01*
X752167Y464333D01*
X752417Y463750D01*
X752500Y463167D01*
X752417Y462583D01*
X752167Y462000D01*
X751667Y461667D01*
X751000Y461500D01*
X750417Y461583D01*
X749833Y461833D01*
X749500Y462167D01*
G01X756600Y461500D02*
Y466500D01*
G01X760783Y464833D02*
Y462500D01*
X761117Y461917D01*
X761617Y461583D01*
X762200Y461500D01*
X762783Y461583D01*
X763283Y461917D01*
X763617Y462500D01*
G01Y461500D02*
Y464833D01*
G01X766633Y460250D02*
X767217Y459917D01*
X767883Y459833D01*
X768467Y459917D01*
X768967Y460333D01*
X769300Y460917D01*
Y464833D01*
G01Y464167D02*
X768967Y464500D01*
X768467Y464750D01*
X767883Y464833D01*
X767217Y464667D01*
X766800Y464333D01*
X766467Y463750D01*
X766300Y463167D01*
X766383Y462667D01*
X766717Y462083D01*
X767217Y461667D01*
X767883Y461500D01*
X768383Y461583D01*
X768967Y461917D01*
X769300Y462250D01*
G01X772233Y460250D02*
X772817Y459917D01*
X773483Y459833D01*
X774067Y459917D01*
X774567Y460333D01*
X774900Y460917D01*
Y464833D01*
G01Y464167D02*
X774567Y464500D01*
X774067Y464750D01*
X773483Y464833D01*
X772817Y464667D01*
X772400Y464333D01*
X772067Y463750D01*
X771900Y463167D01*
X771983Y462667D01*
X772317Y462083D01*
X772817Y461667D01*
X773483Y461500D01*
X773983Y461583D01*
X774567Y461917D01*
X774900Y462250D01*
G01X779000Y464833D02*
Y461500D01*
G01Y466167D02*
X778833Y466250D01*
Y466417D01*
X779000Y466500D01*
X779167Y466417D01*
Y466250D01*
X779000Y466167D01*
G01X783183Y461500D02*
Y464833D01*
G01Y464000D02*
X783517Y464417D01*
X784017Y464750D01*
X784683Y464833D01*
X785267Y464750D01*
X785767Y464417D01*
X786017Y463833D01*
Y461500D01*
G01X789033Y460250D02*
X789617Y459917D01*
X790283Y459833D01*
X790867Y459917D01*
X791367Y460333D01*
X791700Y460917D01*
Y464833D01*
G01Y464167D02*
X791367Y464500D01*
X790867Y464750D01*
X790283Y464833D01*
X789617Y464667D01*
X789200Y464333D01*
X788867Y463750D01*
X788700Y463167D01*
X788783Y462667D01*
X789117Y462083D01*
X789617Y461667D01*
X790283Y461500D01*
X790783Y461583D01*
X791367Y461917D01*
X791700Y462250D01*
G01X713000Y400500D02*
X1343000D01*
G01X713000Y435500D02*
X1343000D01*
G01X713000Y450500D02*
X1343000D01*
G01X721250Y530000D02*
Y535000D01*
G01X724750D02*
Y530000D01*
G01Y532500D02*
X721250D01*
G01X730100Y530000D02*
Y533333D01*
G01Y532750D02*
X729767Y533083D01*
X729267Y533250D01*
X728683Y533333D01*
X728100Y533167D01*
X727600Y532833D01*
X727267Y532333D01*
X727100Y531667D01*
X727267Y531000D01*
X727600Y530500D01*
X728100Y530167D01*
X728683Y530000D01*
X729267Y530083D01*
X729767Y530333D01*
X730100Y530667D01*
G01X734200Y530000D02*
Y535000D01*
G01X739300Y530000D02*
Y534250D01*
X739467Y534667D01*
X739800Y534917D01*
X740300Y535000D01*
X740800Y534833D01*
X741050Y534417D01*
G01X740050Y533000D02*
X738383D01*
G01X749333Y530000D02*
Y535000D01*
X751333D01*
X752000Y534750D01*
X752500Y534167D01*
X752667Y533500D01*
X752500Y532833D01*
X752083Y532333D01*
X751333Y532083D01*
X749333D01*
G01X756600Y530000D02*
Y535000D01*
G01X760783Y533333D02*
Y531000D01*
X761117Y530417D01*
X761617Y530083D01*
X762200Y530000D01*
X762783Y530083D01*
X763283Y530417D01*
X763617Y531000D01*
G01Y530000D02*
Y533333D01*
G01X766633Y528750D02*
X767217Y528417D01*
X767883Y528333D01*
X768467Y528417D01*
X768967Y528833D01*
X769300Y529417D01*
Y533333D01*
G01Y532667D02*
X768967Y533000D01*
X768467Y533250D01*
X767883Y533333D01*
X767217Y533167D01*
X766800Y532833D01*
X766467Y532250D01*
X766300Y531667D01*
X766383Y531167D01*
X766717Y530583D01*
X767217Y530167D01*
X767883Y530000D01*
X768383Y530083D01*
X768967Y530417D01*
X769300Y530750D01*
G01X772233Y528750D02*
X772817Y528417D01*
X773483Y528333D01*
X774067Y528417D01*
X774567Y528833D01*
X774900Y529417D01*
Y533333D01*
G01Y532667D02*
X774567Y533000D01*
X774067Y533250D01*
X773483Y533333D01*
X772817Y533167D01*
X772400Y532833D01*
X772067Y532250D01*
X771900Y531667D01*
X771983Y531167D01*
X772317Y530583D01*
X772817Y530167D01*
X773483Y530000D01*
X773983Y530083D01*
X774567Y530417D01*
X774900Y530750D01*
G01X779000Y533333D02*
Y530000D01*
G01Y534667D02*
X778833Y534750D01*
Y534917D01*
X779000Y535000D01*
X779167Y534917D01*
Y534750D01*
X779000Y534667D01*
G01X783183Y530000D02*
Y533333D01*
G01Y532500D02*
X783517Y532917D01*
X784017Y533250D01*
X784683Y533333D01*
X785267Y533250D01*
X785767Y532917D01*
X786017Y532333D01*
Y530000D01*
G01X789033Y528750D02*
X789617Y528417D01*
X790283Y528333D01*
X790867Y528417D01*
X791367Y528833D01*
X791700Y529417D01*
Y533333D01*
G01Y532667D02*
X791367Y533000D01*
X790867Y533250D01*
X790283Y533333D01*
X789617Y533167D01*
X789200Y532833D01*
X788867Y532250D01*
X788700Y531667D01*
X788783Y531167D01*
X789117Y530583D01*
X789617Y530167D01*
X790283Y530000D01*
X790783Y530083D01*
X791367Y530417D01*
X791700Y530750D01*
G01X713000Y477500D02*
X1343000D01*
G01X722833Y589000D02*
Y594000D01*
X724833D01*
X725500Y593750D01*
X726000Y593167D01*
X726167Y592500D01*
X726000Y591833D01*
X725583Y591333D01*
X724833Y591083D01*
X722833D01*
G01X730100Y589000D02*
Y594000D01*
G01X734283Y592333D02*
Y590000D01*
X734617Y589417D01*
X735117Y589083D01*
X735700Y589000D01*
X736283Y589083D01*
X736783Y589417D01*
X737117Y590000D01*
G01Y589000D02*
Y592333D01*
G01X740133Y587750D02*
X740717Y587417D01*
X741383Y587333D01*
X741967Y587417D01*
X742467Y587833D01*
X742800Y588417D01*
Y592333D01*
G01Y591667D02*
X742467Y592000D01*
X741967Y592250D01*
X741383Y592333D01*
X740717Y592167D01*
X740300Y591833D01*
X739967Y591250D01*
X739800Y590667D01*
X739883Y590167D01*
X740217Y589583D01*
X740717Y589167D01*
X741383Y589000D01*
X741883Y589083D01*
X742467Y589417D01*
X742800Y589750D01*
G01X745733Y587750D02*
X746317Y587417D01*
X746983Y587333D01*
X747567Y587417D01*
X748067Y587833D01*
X748400Y588417D01*
Y592333D01*
G01Y591667D02*
X748067Y592000D01*
X747567Y592250D01*
X746983Y592333D01*
X746317Y592167D01*
X745900Y591833D01*
X745567Y591250D01*
X745400Y590667D01*
X745483Y590167D01*
X745817Y589583D01*
X746317Y589167D01*
X746983Y589000D01*
X747483Y589083D01*
X748067Y589417D01*
X748400Y589750D01*
G01X752500Y592333D02*
Y589000D01*
G01Y593667D02*
X752333Y593750D01*
Y593917D01*
X752500Y594000D01*
X752667Y593917D01*
Y593750D01*
X752500Y593667D01*
G01X756683Y589000D02*
Y592333D01*
G01Y591500D02*
X757017Y591917D01*
X757517Y592250D01*
X758183Y592333D01*
X758767Y592250D01*
X759267Y591917D01*
X759517Y591333D01*
Y589000D01*
G01X762533Y587750D02*
X763117Y587417D01*
X763783Y587333D01*
X764367Y587417D01*
X764867Y587833D01*
X765200Y588417D01*
Y592333D01*
G01Y591667D02*
X764867Y592000D01*
X764367Y592250D01*
X763783Y592333D01*
X763117Y592167D01*
X762700Y591833D01*
X762367Y591250D01*
X762200Y590667D01*
X762283Y590167D01*
X762617Y589583D01*
X763117Y589167D01*
X763783Y589000D01*
X764283Y589083D01*
X764867Y589417D01*
X765200Y589750D01*
G01X776400Y594000D02*
Y589000D01*
G01Y589750D02*
X776067Y589333D01*
X775567Y589083D01*
X774983Y589000D01*
X774317Y589167D01*
X773817Y589583D01*
X773483Y590083D01*
X773400Y590667D01*
X773483Y591250D01*
X773817Y591750D01*
X774317Y592167D01*
X774983Y592333D01*
X775567Y592250D01*
X775983Y592083D01*
X776400Y591750D01*
G01X779250Y591250D02*
X781917D01*
X781667Y591833D01*
X781250Y592167D01*
X780667Y592333D01*
X780083Y592250D01*
X779583Y592000D01*
X779250Y591417D01*
X779083Y590917D01*
Y590417D01*
X779250Y589917D01*
X779667Y589417D01*
X780167Y589083D01*
X780750Y589000D01*
X781333Y589167D01*
X781917Y589667D01*
G01X785600Y589000D02*
Y593250D01*
X785767Y593667D01*
X786100Y593917D01*
X786600Y594000D01*
X787100Y593833D01*
X787350Y593417D01*
G01X786350Y592000D02*
X784683D01*
G01X791700Y592333D02*
Y589000D01*
G01Y593667D02*
X791533Y593750D01*
Y593917D01*
X791700Y594000D01*
X791867Y593917D01*
Y593750D01*
X791700Y593667D01*
G01X795883Y589000D02*
Y592333D01*
G01Y591500D02*
X796217Y591917D01*
X796717Y592250D01*
X797383Y592333D01*
X797967Y592250D01*
X798467Y591917D01*
X798717Y591333D01*
Y589000D01*
G01X801650Y591250D02*
X804317D01*
X804067Y591833D01*
X803650Y592167D01*
X803067Y592333D01*
X802483Y592250D01*
X801983Y592000D01*
X801650Y591417D01*
X801483Y590917D01*
Y590417D01*
X801650Y589917D01*
X802067Y589417D01*
X802567Y589083D01*
X803150Y589000D01*
X803733Y589167D01*
X804317Y589667D01*
G01X713000Y579500D02*
X1343000D01*
G01X713000Y604500D02*
X1343000D01*
G01X713000Y752000D02*
X1344500D01*
G01X722667Y765000D02*
X723167Y764417D01*
X723833Y764083D01*
X724583Y764000D01*
X725250Y764083D01*
X725917Y764500D01*
X726333Y765000D01*
X726417Y765500D01*
X726250Y766083D01*
X725667Y766500D01*
X725083Y766667D01*
X724333D01*
G01X725083D02*
X725583Y766917D01*
X726000Y767333D01*
X726167Y767833D01*
X726000Y768333D01*
X725583Y768750D01*
X724833Y769000D01*
X724083Y768917D01*
X723333Y768583D01*
G01X730100Y763833D02*
X729933Y763917D01*
Y764083D01*
X730100Y764167D01*
X730267Y764083D01*
Y763917D01*
X730100Y763833D01*
G01X739633Y764000D02*
Y769000D01*
X741633D01*
X742300Y768750D01*
X742800Y768167D01*
X742967Y767500D01*
X742800Y766833D01*
X742383Y766333D01*
X741633Y766083D01*
X739633D01*
G01X746900Y764000D02*
Y769000D01*
G01X751083Y767333D02*
Y765000D01*
X751417Y764417D01*
X751917Y764083D01*
X752500Y764000D01*
X753083Y764083D01*
X753583Y764417D01*
X753917Y765000D01*
G01Y764000D02*
Y767333D01*
G01X756933Y762750D02*
X757517Y762417D01*
X758183Y762333D01*
X758767Y762417D01*
X759267Y762833D01*
X759600Y763417D01*
Y767333D01*
G01Y766667D02*
X759267Y767000D01*
X758767Y767250D01*
X758183Y767333D01*
X757517Y767167D01*
X757100Y766833D01*
X756767Y766250D01*
X756600Y765667D01*
X756683Y765167D01*
X757017Y764583D01*
X757517Y764167D01*
X758183Y764000D01*
X758683Y764083D01*
X759267Y764417D01*
X759600Y764750D01*
G01X767800Y767333D02*
X769300Y764000D01*
X770800Y767333D01*
G01X774900D02*
Y764000D01*
G01Y768667D02*
X774733Y768750D01*
Y768917D01*
X774900Y769000D01*
X775067Y768917D01*
Y768750D01*
X774900Y768667D01*
G01X782000Y764000D02*
Y767333D01*
G01Y766750D02*
X781667Y767083D01*
X781167Y767250D01*
X780583Y767333D01*
X780000Y767167D01*
X779500Y766833D01*
X779167Y766333D01*
X779000Y765667D01*
X779167Y765000D01*
X779500Y764500D01*
X780000Y764167D01*
X780583Y764000D01*
X781167Y764083D01*
X781667Y764333D01*
X782000Y764667D01*
G01X790200Y763833D02*
X793200Y769000D01*
G01X795217D02*
X797300Y764000D01*
X799383Y769000D01*
G01X802900Y764000D02*
X802233Y764083D01*
X801650Y764417D01*
X801150Y764917D01*
X800817Y765500D01*
X800650Y766167D01*
Y766833D01*
X800817Y767500D01*
X801150Y768083D01*
X801650Y768583D01*
X802233Y768917D01*
X802900Y769000D01*
X803567Y768917D01*
X804150Y768583D01*
X804650Y768083D01*
X804983Y767500D01*
X805150Y766833D01*
Y766167D01*
X804983Y765500D01*
X804650Y764917D01*
X804150Y764417D01*
X803567Y764083D01*
X802900Y764000D01*
G01X806833D02*
Y769000D01*
X808833D01*
X809500Y768750D01*
X810000Y768167D01*
X810167Y767500D01*
X810000Y766833D01*
X809583Y766333D01*
X808833Y766083D01*
X806833D01*
G01X812600Y763833D02*
X815600Y769000D01*
G01X817617D02*
X819700Y764000D01*
X821783Y769000D01*
G01X824300D02*
X826300D01*
G01X825300D02*
Y764000D01*
G01X824300D02*
X826300D01*
G01X829233D02*
Y769000D01*
X831233D01*
X831900Y768750D01*
X832400Y768167D01*
X832567Y767500D01*
X832400Y766833D01*
X831983Y766333D01*
X831233Y766083D01*
X829233D01*
G01X836500Y763833D02*
X836333Y763917D01*
Y764083D01*
X836500Y764167D01*
X836667Y764083D01*
Y763917D01*
X836500Y763833D01*
G01Y766083D02*
X836333Y766167D01*
Y766333D01*
X836500Y766417D01*
X836667Y766333D01*
Y766167D01*
X836500Y766083D01*
G01X724813Y813000D02*
Y818000D01*
X726897D01*
X727563Y817750D01*
X727980Y817417D01*
X728147Y816750D01*
X727980Y816083D01*
X727480Y815667D01*
X726897Y815417D01*
X724813D01*
G01X726897D02*
X728147Y813000D01*
G01X732080D02*
X731580Y813083D01*
X731080Y813417D01*
X730747Y814000D01*
X730580Y814667D01*
X730747Y815333D01*
X731080Y815917D01*
X731580Y816250D01*
X732080Y816333D01*
X732580Y816250D01*
X733080Y815917D01*
X733413Y815333D01*
X733497Y814667D01*
X733413Y814000D01*
X733080Y813417D01*
X732580Y813083D01*
X732080Y813000D01*
G01X736263Y816333D02*
Y814000D01*
X736597Y813417D01*
X737097Y813083D01*
X737680Y813000D01*
X738263Y813083D01*
X738763Y813417D01*
X739097Y814000D01*
G01Y813000D02*
Y816333D01*
G01X743280Y818000D02*
Y813000D01*
G01X742113Y816333D02*
X744447D01*
G01X748880D02*
Y813000D01*
G01Y817667D02*
X748713Y817750D01*
Y817917D01*
X748880Y818000D01*
X749047Y817917D01*
Y817750D01*
X748880Y817667D01*
G01X753063Y813000D02*
Y816333D01*
G01Y815500D02*
X753397Y815917D01*
X753897Y816250D01*
X754563Y816333D01*
X755147Y816250D01*
X755647Y815917D01*
X755897Y815333D01*
Y813000D01*
G01X758913Y811750D02*
X759497Y811417D01*
X760163Y811333D01*
X760747Y811417D01*
X761247Y811833D01*
X761580Y812417D01*
Y816333D01*
G01Y815667D02*
X761247Y816000D01*
X760747Y816250D01*
X760163Y816333D01*
X759497Y816167D01*
X759080Y815833D01*
X758747Y815250D01*
X758580Y814667D01*
X758663Y814167D01*
X758997Y813583D01*
X759497Y813167D01*
X760163Y813000D01*
X760663Y813083D01*
X761247Y813417D01*
X761580Y813750D01*
G01X712980Y850500D02*
X1343000D01*
G01X802167Y-15500D02*
Y-10500D01*
X803833D01*
X804500Y-10750D01*
X805000Y-11083D01*
X805417Y-11583D01*
X805750Y-12167D01*
X805833Y-13000D01*
X805750Y-13833D01*
X805417Y-14417D01*
X805000Y-14917D01*
X804500Y-15250D01*
X803833Y-15500D01*
X802167D01*
G01X809600D02*
Y-10500D01*
X808600Y-11500D01*
G01Y-15500D02*
X810600D01*
G01X813617Y-13417D02*
X814200Y-12833D01*
X814700Y-12500D01*
X815367Y-12333D01*
X815950Y-12500D01*
X816367Y-12833D01*
X816700Y-13333D01*
X816783Y-13917D01*
X816700Y-14417D01*
X816367Y-14917D01*
X815867Y-15333D01*
X815283Y-15500D01*
X814617Y-15333D01*
X814033Y-14833D01*
X813700Y-14083D01*
X813617Y-13250D01*
X813783Y-12167D01*
X814033Y-11583D01*
X814450Y-11000D01*
X815033Y-10583D01*
X815617Y-10500D01*
X816200Y-10667D01*
X816617Y-11083D01*
G01X777167Y123000D02*
Y128000D01*
X778833D01*
X779500Y127750D01*
X780000Y127417D01*
X780417Y126917D01*
X780750Y126333D01*
X780833Y125500D01*
X780750Y124667D01*
X780417Y124083D01*
X780000Y123583D01*
X779500Y123250D01*
X778833Y123000D01*
X777167D01*
G01X783433D02*
Y126333D01*
G01Y125667D02*
X783850Y126000D01*
X784267Y126250D01*
X784850Y126333D01*
X785267Y126250D01*
X785767Y126000D01*
G01X790200Y126333D02*
Y123000D01*
G01Y127667D02*
X790033Y127750D01*
Y127917D01*
X790200Y128000D01*
X790367Y127917D01*
Y127750D01*
X790200Y127667D01*
G01X795800Y123000D02*
Y128000D01*
G01X801400Y123000D02*
Y128000D01*
G01X811017Y123000D02*
Y128000D01*
X814183D01*
G01X813017Y125583D02*
X811017D01*
G01X817033Y123000D02*
Y126333D01*
G01Y125667D02*
X817450Y126000D01*
X817867Y126250D01*
X818450Y126333D01*
X818867Y126250D01*
X819367Y126000D01*
G01X823800Y123000D02*
X823300Y123083D01*
X822800Y123417D01*
X822467Y124000D01*
X822300Y124667D01*
X822467Y125333D01*
X822800Y125917D01*
X823300Y126250D01*
X823800Y126333D01*
X824300Y126250D01*
X824800Y125917D01*
X825133Y125333D01*
X825217Y124667D01*
X825133Y124000D01*
X824800Y123417D01*
X824300Y123083D01*
X823800Y123000D01*
G01X826900D02*
Y126333D01*
G01Y125417D02*
X827150Y125833D01*
X827567Y126167D01*
X828150Y126333D01*
X828733Y126167D01*
X829150Y125833D01*
X829400Y125417D01*
Y123000D01*
G01Y125417D02*
X829650Y125833D01*
X830067Y126167D01*
X830650Y126333D01*
X831233Y126167D01*
X831650Y125833D01*
X831900Y125333D01*
Y123000D01*
G01X838933Y128000D02*
Y123000D01*
X842267D01*
G01X846200D02*
Y128000D01*
X845200Y127000D01*
G01Y123000D02*
X847200D01*
G01X856983Y121333D02*
X856150Y122167D01*
X855733Y123000D01*
Y126333D01*
X856150Y127167D01*
X856983Y128000D01*
G01X863000D02*
Y123000D01*
G01X861083Y128000D02*
X864917D01*
G01X868600Y123000D02*
X867933Y123083D01*
X867350Y123417D01*
X866850Y123917D01*
X866517Y124500D01*
X866350Y125167D01*
Y125833D01*
X866517Y126500D01*
X866850Y127083D01*
X867350Y127583D01*
X867933Y127917D01*
X868600Y128000D01*
X869267Y127917D01*
X869850Y127583D01*
X870350Y127083D01*
X870683Y126500D01*
X870850Y125833D01*
Y125167D01*
X870683Y124500D01*
X870350Y123917D01*
X869850Y123417D01*
X869267Y123083D01*
X868600Y123000D01*
G01X872533D02*
Y128000D01*
X874533D01*
X875200Y127750D01*
X875700Y127167D01*
X875867Y126500D01*
X875700Y125833D01*
X875283Y125333D01*
X874533Y125083D01*
X872533D01*
G01X880217Y121333D02*
X881050Y122167D01*
X881467Y123000D01*
Y126333D01*
X881050Y127167D01*
X880217Y128000D01*
G01X891000D02*
Y123000D01*
G01X889833Y126333D02*
X892167D01*
G01X896600Y123000D02*
X896100Y123083D01*
X895600Y123417D01*
X895267Y124000D01*
X895100Y124667D01*
X895267Y125333D01*
X895600Y125917D01*
X896100Y126250D01*
X896600Y126333D01*
X897100Y126250D01*
X897600Y125917D01*
X897933Y125333D01*
X898017Y124667D01*
X897933Y124000D01*
X897600Y123417D01*
X897100Y123083D01*
X896600Y123000D01*
G01X906133Y128000D02*
Y123000D01*
X909467D01*
G01X912150Y126333D02*
X914650Y123000D01*
G01Y126333D02*
X912150Y123000D01*
G01X827667Y150500D02*
Y155500D01*
X829333D01*
X830000Y155250D01*
X830500Y154917D01*
X830917Y154417D01*
X831250Y153833D01*
X831333Y153000D01*
X831250Y152167D01*
X830917Y151583D01*
X830500Y151083D01*
X830000Y150750D01*
X829333Y150500D01*
X827667D01*
G01X835100D02*
Y155500D01*
X834100Y154500D01*
G01Y150500D02*
X836100D01*
G01X777583Y104700D02*
Y99700D01*
X780917D01*
G01X783600Y103033D02*
X786100Y99700D01*
G01Y103033D02*
X783600Y99700D01*
G01X790450Y99533D02*
X790283Y99617D01*
Y99783D01*
X790450Y99867D01*
X790617Y99783D01*
Y99617D01*
X790450Y99533D01*
G01Y101783D02*
X790283Y101867D01*
Y102033D01*
X790450Y102117D01*
X790617Y102033D01*
Y101867D01*
X790450Y101783D01*
G01X799150Y99700D02*
Y103033D01*
G01Y102117D02*
X799400Y102533D01*
X799817Y102867D01*
X800400Y103033D01*
X800983Y102867D01*
X801400Y102533D01*
X801650Y102117D01*
Y99700D01*
G01Y102117D02*
X801900Y102533D01*
X802317Y102867D01*
X802900Y103033D01*
X803483Y102867D01*
X803900Y102533D01*
X804150Y102033D01*
Y99700D01*
G01X805833Y103033D02*
Y100700D01*
X806167Y100117D01*
X806667Y99783D01*
X807250Y99700D01*
X807833Y99783D01*
X808333Y100117D01*
X808667Y100700D01*
G01Y99700D02*
Y103033D01*
G01X811600Y100283D02*
X812017Y99950D01*
X812600Y99700D01*
X813100D01*
X813600Y99867D01*
X813933Y100117D01*
X814100Y100450D01*
X814017Y100950D01*
X813683Y101200D01*
X812183Y101700D01*
X811850Y102283D01*
X812017Y102700D01*
X812350Y102950D01*
X812850Y103033D01*
X813350Y102950D01*
X813850Y102700D01*
G01X818450Y104700D02*
Y99700D01*
G01X817283Y103033D02*
X819617D01*
G01X828150Y99700D02*
Y104700D01*
G01Y102200D02*
X828567Y102700D01*
X829067Y102950D01*
X829567Y103033D01*
X830317Y102867D01*
X830817Y102533D01*
X831150Y101950D01*
Y101283D01*
X830983Y100617D01*
X830650Y100117D01*
X830067Y99783D01*
X829567Y99700D01*
X829067Y99783D01*
X828567Y100033D01*
X828150Y100450D01*
G01X834000Y101950D02*
X836667D01*
X836417Y102533D01*
X836000Y102867D01*
X835417Y103033D01*
X834833Y102950D01*
X834333Y102700D01*
X834000Y102117D01*
X833833Y101617D01*
Y101117D01*
X834000Y100617D01*
X834417Y100117D01*
X834917Y99783D01*
X835500Y99700D01*
X836083Y99867D01*
X836667Y100367D01*
G01X844950Y99700D02*
Y104700D01*
G01Y102200D02*
X845367Y102700D01*
X845867Y102950D01*
X846367Y103033D01*
X847117Y102867D01*
X847617Y102533D01*
X847950Y101950D01*
Y101283D01*
X847783Y100617D01*
X847450Y100117D01*
X846867Y99783D01*
X846367Y99700D01*
X845867Y99783D01*
X845367Y100033D01*
X844950Y100450D01*
G01X850883Y99700D02*
Y103033D01*
G01Y102367D02*
X851300Y102700D01*
X851717Y102950D01*
X852300Y103033D01*
X852717Y102950D01*
X853217Y102700D01*
G01X857650Y99700D02*
X857150Y99783D01*
X856650Y100117D01*
X856317Y100700D01*
X856150Y101367D01*
X856317Y102033D01*
X856650Y102617D01*
X857150Y102950D01*
X857650Y103033D01*
X858150Y102950D01*
X858650Y102617D01*
X858983Y102033D01*
X859067Y101367D01*
X858983Y100700D01*
X858650Y100117D01*
X858150Y99783D01*
X857650Y99700D01*
G01X861833D02*
Y104700D01*
G01X864500Y103033D02*
X861833Y101117D01*
G01X862917Y101867D02*
X864667Y99700D01*
G01X867600Y101950D02*
X870267D01*
X870017Y102533D01*
X869600Y102867D01*
X869017Y103033D01*
X868433Y102950D01*
X867933Y102700D01*
X867600Y102117D01*
X867433Y101617D01*
Y101117D01*
X867600Y100617D01*
X868017Y100117D01*
X868517Y99783D01*
X869100Y99700D01*
X869683Y99867D01*
X870267Y100367D01*
G01X873033Y99700D02*
Y103033D01*
G01Y102200D02*
X873367Y102617D01*
X873867Y102950D01*
X874533Y103033D01*
X875117Y102950D01*
X875617Y102617D01*
X875867Y102033D01*
Y99700D01*
G01X885650D02*
Y104700D01*
G01X892750Y99700D02*
Y103033D01*
G01Y102450D02*
X892417Y102783D01*
X891917Y102950D01*
X891333Y103033D01*
X890750Y102867D01*
X890250Y102533D01*
X889917Y102033D01*
X889750Y101367D01*
X889917Y100700D01*
X890250Y100200D01*
X890750Y99867D01*
X891333Y99700D01*
X891917Y99783D01*
X892417Y100033D01*
X892750Y100367D01*
G01X895100Y98200D02*
X895600Y98033D01*
X896267Y98200D01*
X896683Y98533D01*
X897017Y98950D01*
X897517Y100283D01*
X898600Y103033D01*
G01X895933D02*
X897517Y100283D01*
G01X901200Y101950D02*
X903867D01*
X903617Y102533D01*
X903200Y102867D01*
X902617Y103033D01*
X902033Y102950D01*
X901533Y102700D01*
X901200Y102117D01*
X901033Y101617D01*
Y101117D01*
X901200Y100617D01*
X901617Y100117D01*
X902117Y99783D01*
X902700Y99700D01*
X903283Y99867D01*
X903867Y100367D01*
G01X906883Y99700D02*
Y103033D01*
G01Y102367D02*
X907300Y102700D01*
X907717Y102950D01*
X908300Y103033D01*
X908717Y102950D01*
X909217Y102700D01*
G01X776983Y116310D02*
Y111310D01*
X780317D01*
G01X782833D02*
Y114643D01*
G01Y113810D02*
X783167Y114227D01*
X783667Y114560D01*
X784333Y114643D01*
X784917Y114560D01*
X785417Y114227D01*
X785667Y113643D01*
Y111310D01*
G01X789850Y111143D02*
X789683Y111227D01*
Y111393D01*
X789850Y111477D01*
X790017Y111393D01*
Y111227D01*
X789850Y111143D01*
G01Y113393D02*
X789683Y113477D01*
Y113643D01*
X789850Y113727D01*
X790017Y113643D01*
Y113477D01*
X789850Y113393D01*
G01X802383Y114227D02*
X801800Y114560D01*
X801300Y114643D01*
X800633Y114477D01*
X800133Y114143D01*
X799800Y113560D01*
X799717Y112977D01*
X799800Y112393D01*
X800133Y111893D01*
X800633Y111477D01*
X801300Y111310D01*
X801883Y111477D01*
X802383Y111810D01*
G01X808150Y111310D02*
Y114643D01*
G01Y114060D02*
X807817Y114393D01*
X807317Y114560D01*
X806733Y114643D01*
X806150Y114477D01*
X805650Y114143D01*
X805317Y113643D01*
X805150Y112977D01*
X805317Y112310D01*
X805650Y111810D01*
X806150Y111477D01*
X806733Y111310D01*
X807317Y111393D01*
X807817Y111643D01*
X808150Y111977D01*
G01X810833Y111310D02*
Y114643D01*
G01Y113810D02*
X811167Y114227D01*
X811667Y114560D01*
X812333Y114643D01*
X812917Y114560D01*
X813417Y114227D01*
X813667Y113643D01*
Y111310D01*
G01X817850Y114643D02*
X818683Y115685D01*
Y116310D01*
X818058D01*
Y115685D01*
X818683D01*
G01X823450Y116310D02*
Y111310D01*
G01X822283Y114643D02*
X824617D01*
G01X833150Y111310D02*
Y116310D01*
G01Y113810D02*
X833567Y114310D01*
X834067Y114560D01*
X834567Y114643D01*
X835317Y114477D01*
X835817Y114143D01*
X836150Y113560D01*
Y112893D01*
X835983Y112227D01*
X835650Y111727D01*
X835067Y111393D01*
X834567Y111310D01*
X834067Y111393D01*
X833567Y111643D01*
X833150Y112060D01*
G01X839000Y113560D02*
X841667D01*
X841417Y114143D01*
X841000Y114477D01*
X840417Y114643D01*
X839833Y114560D01*
X839333Y114310D01*
X839000Y113727D01*
X838833Y113227D01*
Y112727D01*
X839000Y112227D01*
X839417Y111727D01*
X839917Y111393D01*
X840500Y111310D01*
X841083Y111477D01*
X841667Y111977D01*
G01X849950Y111310D02*
Y116310D01*
G01Y113810D02*
X850367Y114310D01*
X850867Y114560D01*
X851367Y114643D01*
X852117Y114477D01*
X852617Y114143D01*
X852950Y113560D01*
Y112893D01*
X852783Y112227D01*
X852450Y111727D01*
X851867Y111393D01*
X851367Y111310D01*
X850867Y111393D01*
X850367Y111643D01*
X849950Y112060D01*
G01X855883Y111310D02*
Y114643D01*
G01Y113977D02*
X856300Y114310D01*
X856717Y114560D01*
X857300Y114643D01*
X857717Y114560D01*
X858217Y114310D01*
G01X862650Y111310D02*
X862150Y111393D01*
X861650Y111727D01*
X861317Y112310D01*
X861150Y112977D01*
X861317Y113643D01*
X861650Y114227D01*
X862150Y114560D01*
X862650Y114643D01*
X863150Y114560D01*
X863650Y114227D01*
X863983Y113643D01*
X864067Y112977D01*
X863983Y112310D01*
X863650Y111727D01*
X863150Y111393D01*
X862650Y111310D01*
G01X866833D02*
Y116310D01*
G01X869500Y114643D02*
X866833Y112727D01*
G01X867917Y113477D02*
X869667Y111310D01*
G01X872600Y113560D02*
X875267D01*
X875017Y114143D01*
X874600Y114477D01*
X874017Y114643D01*
X873433Y114560D01*
X872933Y114310D01*
X872600Y113727D01*
X872433Y113227D01*
Y112727D01*
X872600Y112227D01*
X873017Y111727D01*
X873517Y111393D01*
X874100Y111310D01*
X874683Y111477D01*
X875267Y111977D01*
G01X878033Y111310D02*
Y114643D01*
G01Y113810D02*
X878367Y114227D01*
X878867Y114560D01*
X879533Y114643D01*
X880117Y114560D01*
X880617Y114227D01*
X880867Y113643D01*
Y111310D01*
G01X890650D02*
Y116310D01*
G01X897750Y111310D02*
Y114643D01*
G01Y114060D02*
X897417Y114393D01*
X896917Y114560D01*
X896333Y114643D01*
X895750Y114477D01*
X895250Y114143D01*
X894917Y113643D01*
X894750Y112977D01*
X894917Y112310D01*
X895250Y111810D01*
X895750Y111477D01*
X896333Y111310D01*
X896917Y111393D01*
X897417Y111643D01*
X897750Y111977D01*
G01X900100Y109810D02*
X900600Y109643D01*
X901267Y109810D01*
X901683Y110143D01*
X902017Y110560D01*
X902517Y111893D01*
X903600Y114643D01*
G01X900933D02*
X902517Y111893D01*
G01X906200Y113560D02*
X908867D01*
X908617Y114143D01*
X908200Y114477D01*
X907617Y114643D01*
X907033Y114560D01*
X906533Y114310D01*
X906200Y113727D01*
X906033Y113227D01*
Y112727D01*
X906200Y112227D01*
X906617Y111727D01*
X907117Y111393D01*
X907700Y111310D01*
X908283Y111477D01*
X908867Y111977D01*
G01X911883Y111310D02*
Y114643D01*
G01Y113977D02*
X912300Y114310D01*
X912717Y114560D01*
X913300Y114643D01*
X913717Y114560D01*
X914217Y114310D01*
G01X821590Y376450D02*
Y379783D01*
G01Y379200D02*
X821257Y379533D01*
X820757Y379700D01*
X820173Y379783D01*
X819590Y379617D01*
X819090Y379283D01*
X818757Y378783D01*
X818590Y378117D01*
X818757Y377450D01*
X819090Y376950D01*
X819590Y376617D01*
X820173Y376450D01*
X820757Y376533D01*
X821257Y376783D01*
X821590Y377117D01*
G01X824273Y376450D02*
Y379783D01*
G01Y378950D02*
X824607Y379367D01*
X825107Y379700D01*
X825773Y379783D01*
X826357Y379700D01*
X826857Y379367D01*
X827107Y378783D01*
Y376450D01*
G01X832790Y381450D02*
Y376450D01*
G01Y377200D02*
X832457Y376783D01*
X831957Y376533D01*
X831373Y376450D01*
X830707Y376617D01*
X830207Y377033D01*
X829873Y377533D01*
X829790Y378117D01*
X829873Y378700D01*
X830207Y379200D01*
X830707Y379617D01*
X831373Y379783D01*
X831957Y379700D01*
X832373Y379533D01*
X832790Y379200D01*
G01X843823Y379367D02*
X843240Y379700D01*
X842740Y379783D01*
X842073Y379617D01*
X841573Y379283D01*
X841240Y378700D01*
X841157Y378117D01*
X841240Y377533D01*
X841573Y377033D01*
X842073Y376617D01*
X842740Y376450D01*
X843323Y376617D01*
X843823Y376950D01*
G01X848090Y376450D02*
X847590Y376533D01*
X847090Y376867D01*
X846757Y377450D01*
X846590Y378117D01*
X846757Y378783D01*
X847090Y379367D01*
X847590Y379700D01*
X848090Y379783D01*
X848590Y379700D01*
X849090Y379367D01*
X849423Y378783D01*
X849507Y378117D01*
X849423Y377450D01*
X849090Y376867D01*
X848590Y376533D01*
X848090Y376450D01*
G01X852190Y379783D02*
X853690Y376450D01*
X855190Y379783D01*
G01X858040Y378700D02*
X860707D01*
X860457Y379283D01*
X860040Y379617D01*
X859457Y379783D01*
X858873Y379700D01*
X858373Y379450D01*
X858040Y378867D01*
X857873Y378367D01*
Y377867D01*
X858040Y377367D01*
X858457Y376867D01*
X858957Y376533D01*
X859540Y376450D01*
X860123Y376617D01*
X860707Y377117D01*
G01X863723Y376450D02*
Y379783D01*
G01Y379117D02*
X864140Y379450D01*
X864557Y379700D01*
X865140Y379783D01*
X865557Y379700D01*
X866057Y379450D01*
G01X869240Y378700D02*
X871907D01*
X871657Y379283D01*
X871240Y379617D01*
X870657Y379783D01*
X870073Y379700D01*
X869573Y379450D01*
X869240Y378867D01*
X869073Y378367D01*
Y377867D01*
X869240Y377367D01*
X869657Y376867D01*
X870157Y376533D01*
X870740Y376450D01*
X871323Y376617D01*
X871907Y377117D01*
G01X877590Y381450D02*
Y376450D01*
G01Y377200D02*
X877257Y376783D01*
X876757Y376533D01*
X876173Y376450D01*
X875507Y376617D01*
X875007Y377033D01*
X874673Y377533D01*
X874590Y378117D01*
X874673Y378700D01*
X875007Y379200D01*
X875507Y379617D01*
X876173Y379783D01*
X876757Y379700D01*
X877173Y379533D01*
X877590Y379200D01*
G01X885207Y379783D02*
X886207Y376450D01*
X887290Y379783D01*
X888373Y376450D01*
X889373Y379783D01*
G01X892890D02*
Y376450D01*
G01Y381117D02*
X892723Y381200D01*
Y381367D01*
X892890Y381450D01*
X893057Y381367D01*
Y381200D01*
X892890Y381117D01*
G01X898490Y381450D02*
Y376450D01*
G01X897323Y379783D02*
X899657D01*
G01X902673Y376450D02*
Y381450D01*
G01Y379033D02*
X903090Y379450D01*
X903507Y379700D01*
X904173Y379783D01*
X904673Y379700D01*
X905257Y379367D01*
X905507Y378867D01*
Y376450D01*
G01X916623Y379367D02*
X916040Y379700D01*
X915540Y379783D01*
X914873Y379617D01*
X914373Y379283D01*
X914040Y378700D01*
X913957Y378117D01*
X914040Y377533D01*
X914373Y377033D01*
X914873Y376617D01*
X915540Y376450D01*
X916123Y376617D01*
X916623Y376950D01*
G01X920890Y376450D02*
X920390Y376533D01*
X919890Y376867D01*
X919557Y377450D01*
X919390Y378117D01*
X919557Y378783D01*
X919890Y379367D01*
X920390Y379700D01*
X920890Y379783D01*
X921390Y379700D01*
X921890Y379367D01*
X922223Y378783D01*
X922307Y378117D01*
X922223Y377450D01*
X921890Y376867D01*
X921390Y376533D01*
X920890Y376450D01*
G01X924990Y374783D02*
Y379783D01*
G01Y379033D02*
X925407Y379450D01*
X925823Y379700D01*
X926490Y379783D01*
X927073Y379700D01*
X927657Y379283D01*
X927907Y378700D01*
X927990Y378117D01*
X927907Y377533D01*
X927657Y376950D01*
X927157Y376617D01*
X926490Y376450D01*
X925907Y376533D01*
X925323Y376783D01*
X924990Y377117D01*
G01X930590Y374783D02*
Y379783D01*
G01Y379033D02*
X931007Y379450D01*
X931423Y379700D01*
X932090Y379783D01*
X932673Y379700D01*
X933257Y379283D01*
X933507Y378700D01*
X933590Y378117D01*
X933507Y377533D01*
X933257Y376950D01*
X932757Y376617D01*
X932090Y376450D01*
X931507Y376533D01*
X930923Y376783D01*
X930590Y377117D01*
G01X936440Y378700D02*
X939107D01*
X938857Y379283D01*
X938440Y379617D01*
X937857Y379783D01*
X937273Y379700D01*
X936773Y379450D01*
X936440Y378867D01*
X936273Y378367D01*
Y377867D01*
X936440Y377367D01*
X936857Y376867D01*
X937357Y376533D01*
X937940Y376450D01*
X938523Y376617D01*
X939107Y377117D01*
G01X942123Y376450D02*
Y379783D01*
G01Y379117D02*
X942540Y379450D01*
X942957Y379700D01*
X943540Y379783D01*
X943957Y379700D01*
X944457Y379450D01*
G01X825667Y314500D02*
Y319500D01*
X827333D01*
X828000Y319250D01*
X828500Y318917D01*
X828917Y318417D01*
X829250Y317833D01*
X829333Y317000D01*
X829250Y316167D01*
X828917Y315583D01*
X828500Y315083D01*
X828000Y314750D01*
X827333Y314500D01*
X825667D01*
G01X831517Y318667D02*
X832017Y319167D01*
X832600Y319417D01*
X833267Y319500D01*
X834100Y319333D01*
X834683Y318917D01*
X834850Y318417D01*
X834767Y317917D01*
X834433Y317500D01*
X832767Y316667D01*
X832017Y316083D01*
X831517Y315250D01*
X831350Y314500D01*
X834850D01*
G01X812000Y604500D02*
Y366000D01*
G01X823500Y455500D02*
Y458833D01*
G01Y458250D02*
X823167Y458583D01*
X822667Y458750D01*
X822083Y458833D01*
X821500Y458667D01*
X821000Y458333D01*
X820667Y457833D01*
X820500Y457167D01*
X820667Y456500D01*
X821000Y456000D01*
X821500Y455667D01*
X822083Y455500D01*
X822667Y455583D01*
X823167Y455833D01*
X823500Y456167D01*
G01X826183Y455500D02*
Y458833D01*
G01Y458000D02*
X826517Y458417D01*
X827017Y458750D01*
X827683Y458833D01*
X828267Y458750D01*
X828767Y458417D01*
X829017Y457833D01*
Y455500D01*
G01X834700Y460500D02*
Y455500D01*
G01Y456250D02*
X834367Y455833D01*
X833867Y455583D01*
X833283Y455500D01*
X832617Y455667D01*
X832117Y456083D01*
X831783Y456583D01*
X831700Y457167D01*
X831783Y457750D01*
X832117Y458250D01*
X832617Y458667D01*
X833283Y458833D01*
X833867Y458750D01*
X834283Y458583D01*
X834700Y458250D01*
G01X842900Y455500D02*
Y460500D01*
G01Y458000D02*
X843317Y458500D01*
X843817Y458750D01*
X844317Y458833D01*
X845067Y458667D01*
X845567Y458333D01*
X845900Y457750D01*
Y457083D01*
X845733Y456417D01*
X845400Y455917D01*
X844817Y455583D01*
X844317Y455500D01*
X843817Y455583D01*
X843317Y455833D01*
X842900Y456250D01*
G01X850000Y455500D02*
X849500Y455583D01*
X849000Y455917D01*
X848667Y456500D01*
X848500Y457167D01*
X848667Y457833D01*
X849000Y458417D01*
X849500Y458750D01*
X850000Y458833D01*
X850500Y458750D01*
X851000Y458417D01*
X851333Y457833D01*
X851417Y457167D01*
X851333Y456500D01*
X851000Y455917D01*
X850500Y455583D01*
X850000Y455500D01*
G01X855600Y460500D02*
Y455500D01*
G01X854433Y458833D02*
X856767D01*
G01X861200Y460500D02*
Y455500D01*
G01X860033Y458833D02*
X862367D01*
G01X866800Y455500D02*
X866300Y455583D01*
X865800Y455917D01*
X865467Y456500D01*
X865300Y457167D01*
X865467Y457833D01*
X865800Y458417D01*
X866300Y458750D01*
X866800Y458833D01*
X867300Y458750D01*
X867800Y458417D01*
X868133Y457833D01*
X868217Y457167D01*
X868133Y456500D01*
X867800Y455917D01*
X867300Y455583D01*
X866800Y455500D01*
G01X869900D02*
Y458833D01*
G01Y457917D02*
X870150Y458333D01*
X870567Y458667D01*
X871150Y458833D01*
X871733Y458667D01*
X872150Y458333D01*
X872400Y457917D01*
Y455500D01*
G01Y457917D02*
X872650Y458333D01*
X873067Y458667D01*
X873650Y458833D01*
X874233Y458667D01*
X874650Y458333D01*
X874900Y457833D01*
Y455500D01*
G01X882350Y456083D02*
X882767Y455750D01*
X883350Y455500D01*
X883850D01*
X884350Y455667D01*
X884683Y455917D01*
X884850Y456250D01*
X884767Y456750D01*
X884433Y457000D01*
X882933Y457500D01*
X882600Y458083D01*
X882767Y458500D01*
X883100Y458750D01*
X883600Y458833D01*
X884100Y458750D01*
X884600Y458500D01*
G01X889200Y458833D02*
Y455500D01*
G01Y460167D02*
X889033Y460250D01*
Y460417D01*
X889200Y460500D01*
X889367Y460417D01*
Y460250D01*
X889200Y460167D01*
G01X896300Y460500D02*
Y455500D01*
G01Y456250D02*
X895967Y455833D01*
X895467Y455583D01*
X894883Y455500D01*
X894217Y455667D01*
X893717Y456083D01*
X893383Y456583D01*
X893300Y457167D01*
X893383Y457750D01*
X893717Y458250D01*
X894217Y458667D01*
X894883Y458833D01*
X895467Y458750D01*
X895883Y458583D01*
X896300Y458250D01*
G01X899150Y457750D02*
X901817D01*
X901567Y458333D01*
X901150Y458667D01*
X900567Y458833D01*
X899983Y458750D01*
X899483Y458500D01*
X899150Y457917D01*
X898983Y457417D01*
Y456917D01*
X899150Y456417D01*
X899567Y455917D01*
X900067Y455583D01*
X900650Y455500D01*
X901233Y455667D01*
X901817Y456167D01*
G01X819917Y470833D02*
X820917Y467500D01*
X822000Y470833D01*
X823083Y467500D01*
X824083Y470833D01*
G01X827600D02*
Y467500D01*
G01Y472167D02*
X827433Y472250D01*
Y472417D01*
X827600Y472500D01*
X827767Y472417D01*
Y472250D01*
X827600Y472167D01*
G01X833200Y472500D02*
Y467500D01*
G01X832033Y470833D02*
X834367D01*
G01X837383Y467500D02*
Y472500D01*
G01Y470083D02*
X837800Y470500D01*
X838217Y470750D01*
X838883Y470833D01*
X839383Y470750D01*
X839967Y470417D01*
X840217Y469917D01*
Y467500D01*
G01X844400D02*
X843900Y467583D01*
X843400Y467917D01*
X843067Y468500D01*
X842900Y469167D01*
X843067Y469833D01*
X843400Y470417D01*
X843900Y470750D01*
X844400Y470833D01*
X844900Y470750D01*
X845400Y470417D01*
X845733Y469833D01*
X845817Y469167D01*
X845733Y468500D01*
X845400Y467917D01*
X844900Y467583D01*
X844400Y467500D01*
G01X848583Y470833D02*
Y468500D01*
X848917Y467917D01*
X849417Y467583D01*
X850000Y467500D01*
X850583Y467583D01*
X851083Y467917D01*
X851417Y468500D01*
G01Y467500D02*
Y470833D01*
G01X855600Y472500D02*
Y467500D01*
G01X854433Y470833D02*
X856767D01*
G01X865550Y468083D02*
X865967Y467750D01*
X866550Y467500D01*
X867050D01*
X867550Y467667D01*
X867883Y467917D01*
X868050Y468250D01*
X867967Y468750D01*
X867633Y469000D01*
X866133Y469500D01*
X865800Y470083D01*
X865967Y470500D01*
X866300Y470750D01*
X866800Y470833D01*
X867300Y470750D01*
X867800Y470500D01*
G01X872400Y467500D02*
X871900Y467583D01*
X871400Y467917D01*
X871067Y468500D01*
X870900Y469167D01*
X871067Y469833D01*
X871400Y470417D01*
X871900Y470750D01*
X872400Y470833D01*
X872900Y470750D01*
X873400Y470417D01*
X873733Y469833D01*
X873817Y469167D01*
X873733Y468500D01*
X873400Y467917D01*
X872900Y467583D01*
X872400Y467500D01*
G01X878000D02*
Y472500D01*
G01X885100D02*
Y467500D01*
G01Y468250D02*
X884767Y467833D01*
X884267Y467583D01*
X883683Y467500D01*
X883017Y467667D01*
X882517Y468083D01*
X882183Y468583D01*
X882100Y469167D01*
X882183Y469750D01*
X882517Y470250D01*
X883017Y470667D01*
X883683Y470833D01*
X884267Y470750D01*
X884683Y470583D01*
X885100Y470250D01*
G01X887950Y469750D02*
X890617D01*
X890367Y470333D01*
X889950Y470667D01*
X889367Y470833D01*
X888783Y470750D01*
X888283Y470500D01*
X887950Y469917D01*
X887783Y469417D01*
Y468917D01*
X887950Y468417D01*
X888367Y467917D01*
X888867Y467583D01*
X889450Y467500D01*
X890033Y467667D01*
X890617Y468167D01*
G01X893633Y467500D02*
Y470833D01*
G01Y470167D02*
X894050Y470500D01*
X894467Y470750D01*
X895050Y470833D01*
X895467Y470750D01*
X895967Y470500D01*
G01X903500Y467500D02*
Y470833D01*
G01Y469917D02*
X903750Y470333D01*
X904167Y470667D01*
X904750Y470833D01*
X905333Y470667D01*
X905750Y470333D01*
X906000Y469917D01*
Y467500D01*
G01Y469917D02*
X906250Y470333D01*
X906667Y470667D01*
X907250Y470833D01*
X907833Y470667D01*
X908250Y470333D01*
X908500Y469833D01*
Y467500D01*
G01X913100D02*
Y470833D01*
G01Y470250D02*
X912767Y470583D01*
X912267Y470750D01*
X911683Y470833D01*
X911100Y470667D01*
X910600Y470333D01*
X910267Y469833D01*
X910100Y469167D01*
X910267Y468500D01*
X910600Y468000D01*
X911100Y467667D01*
X911683Y467500D01*
X912267Y467583D01*
X912767Y467833D01*
X913100Y468167D01*
G01X915950Y468083D02*
X916367Y467750D01*
X916950Y467500D01*
X917450D01*
X917950Y467667D01*
X918283Y467917D01*
X918450Y468250D01*
X918367Y468750D01*
X918033Y469000D01*
X916533Y469500D01*
X916200Y470083D01*
X916367Y470500D01*
X916700Y470750D01*
X917200Y470833D01*
X917700Y470750D01*
X918200Y470500D01*
G01X921383Y467500D02*
Y472500D01*
G01X924050Y470833D02*
X921383Y468917D01*
G01X922467Y469667D02*
X924217Y467500D01*
G01X932500Y465833D02*
Y470833D01*
G01Y470083D02*
X932917Y470500D01*
X933333Y470750D01*
X934000Y470833D01*
X934583Y470750D01*
X935167Y470333D01*
X935417Y469750D01*
X935500Y469167D01*
X935417Y468583D01*
X935167Y468000D01*
X934667Y467667D01*
X934000Y467500D01*
X933417Y467583D01*
X932833Y467833D01*
X932500Y468167D01*
G01X941100Y467500D02*
Y470833D01*
G01Y470250D02*
X940767Y470583D01*
X940267Y470750D01*
X939683Y470833D01*
X939100Y470667D01*
X938600Y470333D01*
X938267Y469833D01*
X938100Y469167D01*
X938267Y468500D01*
X938600Y468000D01*
X939100Y467667D01*
X939683Y467500D01*
X940267Y467583D01*
X940767Y467833D01*
X941100Y468167D01*
G01X946700Y472500D02*
Y467500D01*
G01Y468250D02*
X946367Y467833D01*
X945867Y467583D01*
X945283Y467500D01*
X944617Y467667D01*
X944117Y468083D01*
X943783Y468583D01*
X943700Y469167D01*
X943783Y469750D01*
X944117Y470250D01*
X944617Y470667D01*
X945283Y470833D01*
X945867Y470750D01*
X946283Y470583D01*
X946700Y470250D01*
G01X956400Y467500D02*
X955900Y467583D01*
X955400Y467917D01*
X955067Y468500D01*
X954900Y469167D01*
X955067Y469833D01*
X955400Y470417D01*
X955900Y470750D01*
X956400Y470833D01*
X956900Y470750D01*
X957400Y470417D01*
X957733Y469833D01*
X957817Y469167D01*
X957733Y468500D01*
X957400Y467917D01*
X956900Y467583D01*
X956400Y467500D01*
G01X960583D02*
Y470833D01*
G01Y470000D02*
X960917Y470417D01*
X961417Y470750D01*
X962083Y470833D01*
X962667Y470750D01*
X963167Y470417D01*
X963417Y469833D01*
Y467500D01*
G01X973200Y472500D02*
Y467500D01*
G01X972033Y470833D02*
X974367D01*
G01X978800Y467500D02*
X978300Y467583D01*
X977800Y467917D01*
X977467Y468500D01*
X977300Y469167D01*
X977467Y469833D01*
X977800Y470417D01*
X978300Y470750D01*
X978800Y470833D01*
X979300Y470750D01*
X979800Y470417D01*
X980133Y469833D01*
X980217Y469167D01*
X980133Y468500D01*
X979800Y467917D01*
X979300Y467583D01*
X978800Y467500D01*
G01X982900Y465833D02*
Y470833D01*
G01Y470083D02*
X983317Y470500D01*
X983733Y470750D01*
X984400Y470833D01*
X984983Y470750D01*
X985567Y470333D01*
X985817Y469750D01*
X985900Y469167D01*
X985817Y468583D01*
X985567Y468000D01*
X985067Y467667D01*
X984400Y467500D01*
X983817Y467583D01*
X983233Y467833D01*
X982900Y468167D01*
G01X821500Y440500D02*
Y444750D01*
X821667Y445167D01*
X822000Y445417D01*
X822500Y445500D01*
X823000Y445333D01*
X823250Y444917D01*
G01X822250Y443500D02*
X820583D01*
G01X827600Y440500D02*
X827100Y440583D01*
X826600Y440917D01*
X826267Y441500D01*
X826100Y442167D01*
X826267Y442833D01*
X826600Y443417D01*
X827100Y443750D01*
X827600Y443833D01*
X828100Y443750D01*
X828600Y443417D01*
X828933Y442833D01*
X829017Y442167D01*
X828933Y441500D01*
X828600Y440917D01*
X828100Y440583D01*
X827600Y440500D01*
G01X833200D02*
Y445500D01*
G01X838800Y440500D02*
Y445500D01*
G01X844400Y440500D02*
X843900Y440583D01*
X843400Y440917D01*
X843067Y441500D01*
X842900Y442167D01*
X843067Y442833D01*
X843400Y443417D01*
X843900Y443750D01*
X844400Y443833D01*
X844900Y443750D01*
X845400Y443417D01*
X845733Y442833D01*
X845817Y442167D01*
X845733Y441500D01*
X845400Y440917D01*
X844900Y440583D01*
X844400Y440500D01*
G01X847917Y443833D02*
X848917Y440500D01*
X850000Y443833D01*
X851083Y440500D01*
X852083Y443833D01*
G01X861700Y443000D02*
X863367D01*
Y441500D01*
X862867Y441000D01*
X862283Y440667D01*
X861450Y440500D01*
X860617Y440667D01*
X860033Y441000D01*
X859533Y441500D01*
X859200Y442083D01*
X859033Y442750D01*
Y443333D01*
X859200Y443833D01*
X859533Y444417D01*
X860033Y444917D01*
X860533Y445250D01*
X861200Y445500D01*
X861783D01*
X862450Y445333D01*
X862950Y445000D01*
G01X865550Y442750D02*
X868217D01*
X867967Y443333D01*
X867550Y443667D01*
X866967Y443833D01*
X866383Y443750D01*
X865883Y443500D01*
X865550Y442917D01*
X865383Y442417D01*
Y441917D01*
X865550Y441417D01*
X865967Y440917D01*
X866467Y440583D01*
X867050Y440500D01*
X867633Y440667D01*
X868217Y441167D01*
G01X871233Y440500D02*
Y443833D01*
G01Y443167D02*
X871650Y443500D01*
X872067Y443750D01*
X872650Y443833D01*
X873067Y443750D01*
X873567Y443500D01*
G01X876500Y440500D02*
Y445500D01*
G01Y443000D02*
X876917Y443500D01*
X877417Y443750D01*
X877917Y443833D01*
X878667Y443667D01*
X879167Y443333D01*
X879500Y442750D01*
Y442083D01*
X879333Y441417D01*
X879000Y440917D01*
X878417Y440583D01*
X877917Y440500D01*
X877417Y440583D01*
X876917Y440833D01*
X876500Y441250D01*
G01X882350Y442750D02*
X885017D01*
X884767Y443333D01*
X884350Y443667D01*
X883767Y443833D01*
X883183Y443750D01*
X882683Y443500D01*
X882350Y442917D01*
X882183Y442417D01*
Y441917D01*
X882350Y441417D01*
X882767Y440917D01*
X883267Y440583D01*
X883850Y440500D01*
X884433Y440667D01*
X885017Y441167D01*
G01X888033Y440500D02*
Y443833D01*
G01Y443167D02*
X888450Y443500D01*
X888867Y443750D01*
X889450Y443833D01*
X889867Y443750D01*
X890367Y443500D01*
G01X821500Y419500D02*
Y423750D01*
X821667Y424167D01*
X822000Y424417D01*
X822500Y424500D01*
X823000Y424333D01*
X823250Y423917D01*
G01X822250Y422500D02*
X820583D01*
G01X827600Y419500D02*
X827100Y419583D01*
X826600Y419917D01*
X826267Y420500D01*
X826100Y421167D01*
X826267Y421833D01*
X826600Y422417D01*
X827100Y422750D01*
X827600Y422833D01*
X828100Y422750D01*
X828600Y422417D01*
X828933Y421833D01*
X829017Y421167D01*
X828933Y420500D01*
X828600Y419917D01*
X828100Y419583D01*
X827600Y419500D01*
G01X833200D02*
Y424500D01*
G01X838800Y419500D02*
Y424500D01*
G01X844400Y419500D02*
X843900Y419583D01*
X843400Y419917D01*
X843067Y420500D01*
X842900Y421167D01*
X843067Y421833D01*
X843400Y422417D01*
X843900Y422750D01*
X844400Y422833D01*
X844900Y422750D01*
X845400Y422417D01*
X845733Y421833D01*
X845817Y421167D01*
X845733Y420500D01*
X845400Y419917D01*
X844900Y419583D01*
X844400Y419500D01*
G01X847917Y422833D02*
X848917Y419500D01*
X850000Y422833D01*
X851083Y419500D01*
X852083Y422833D01*
G01X861700Y422000D02*
X863367D01*
Y420500D01*
X862867Y420000D01*
X862283Y419667D01*
X861450Y419500D01*
X860617Y419667D01*
X860033Y420000D01*
X859533Y420500D01*
X859200Y421083D01*
X859033Y421750D01*
Y422333D01*
X859200Y422833D01*
X859533Y423417D01*
X860033Y423917D01*
X860533Y424250D01*
X861200Y424500D01*
X861783D01*
X862450Y424333D01*
X862950Y424000D01*
G01X865550Y421750D02*
X868217D01*
X867967Y422333D01*
X867550Y422667D01*
X866967Y422833D01*
X866383Y422750D01*
X865883Y422500D01*
X865550Y421917D01*
X865383Y421417D01*
Y420917D01*
X865550Y420417D01*
X865967Y419917D01*
X866467Y419583D01*
X867050Y419500D01*
X867633Y419667D01*
X868217Y420167D01*
G01X871233Y419500D02*
Y422833D01*
G01Y422167D02*
X871650Y422500D01*
X872067Y422750D01*
X872650Y422833D01*
X873067Y422750D01*
X873567Y422500D01*
G01X876500Y419500D02*
Y424500D01*
G01Y422000D02*
X876917Y422500D01*
X877417Y422750D01*
X877917Y422833D01*
X878667Y422667D01*
X879167Y422333D01*
X879500Y421750D01*
Y421083D01*
X879333Y420417D01*
X879000Y419917D01*
X878417Y419583D01*
X877917Y419500D01*
X877417Y419583D01*
X876917Y419833D01*
X876500Y420250D01*
G01X882350Y421750D02*
X885017D01*
X884767Y422333D01*
X884350Y422667D01*
X883767Y422833D01*
X883183Y422750D01*
X882683Y422500D01*
X882350Y421917D01*
X882183Y421417D01*
Y420917D01*
X882350Y420417D01*
X882767Y419917D01*
X883267Y419583D01*
X883850Y419500D01*
X884433Y419667D01*
X885017Y420167D01*
G01X888033Y419500D02*
Y422833D01*
G01Y422167D02*
X888450Y422500D01*
X888867Y422750D01*
X889450Y422833D01*
X889867Y422750D01*
X890367Y422500D01*
G01X901900Y419500D02*
Y422833D01*
G01Y422250D02*
X901567Y422583D01*
X901067Y422750D01*
X900483Y422833D01*
X899900Y422667D01*
X899400Y422333D01*
X899067Y421833D01*
X898900Y421167D01*
X899067Y420500D01*
X899400Y420000D01*
X899900Y419667D01*
X900483Y419500D01*
X901067Y419583D01*
X901567Y419833D01*
X901900Y420167D01*
G01X904583Y419500D02*
Y422833D01*
G01Y422000D02*
X904917Y422417D01*
X905417Y422750D01*
X906083Y422833D01*
X906667Y422750D01*
X907167Y422417D01*
X907417Y421833D01*
Y419500D01*
G01X913100Y424500D02*
Y419500D01*
G01Y420250D02*
X912767Y419833D01*
X912267Y419583D01*
X911683Y419500D01*
X911017Y419667D01*
X910517Y420083D01*
X910183Y420583D01*
X910100Y421167D01*
X910183Y421750D01*
X910517Y422250D01*
X911017Y422667D01*
X911683Y422833D01*
X912267Y422750D01*
X912683Y422583D01*
X913100Y422250D01*
G01X921300Y417833D02*
Y422833D01*
G01Y422083D02*
X921717Y422500D01*
X922133Y422750D01*
X922800Y422833D01*
X923383Y422750D01*
X923967Y422333D01*
X924217Y421750D01*
X924300Y421167D01*
X924217Y420583D01*
X923967Y420000D01*
X923467Y419667D01*
X922800Y419500D01*
X922217Y419583D01*
X921633Y419833D01*
X921300Y420167D01*
G01X928400Y419500D02*
Y424500D01*
G01X932583Y422833D02*
Y420500D01*
X932917Y419917D01*
X933417Y419583D01*
X934000Y419500D01*
X934583Y419583D01*
X935083Y419917D01*
X935417Y420500D01*
G01Y419500D02*
Y422833D01*
G01X938433Y418250D02*
X939017Y417917D01*
X939683Y417833D01*
X940267Y417917D01*
X940767Y418333D01*
X941100Y418917D01*
Y422833D01*
G01Y422167D02*
X940767Y422500D01*
X940267Y422750D01*
X939683Y422833D01*
X939017Y422667D01*
X938600Y422333D01*
X938267Y421750D01*
X938100Y421167D01*
X938183Y420667D01*
X938517Y420083D01*
X939017Y419667D01*
X939683Y419500D01*
X940183Y419583D01*
X940767Y419917D01*
X941100Y420250D01*
G01X948717Y422833D02*
X949717Y419500D01*
X950800Y422833D01*
X951883Y419500D01*
X952883Y422833D01*
G01X956400D02*
Y419500D01*
G01Y424167D02*
X956233Y424250D01*
Y424417D01*
X956400Y424500D01*
X956567Y424417D01*
Y424250D01*
X956400Y424167D01*
G01X962000Y424500D02*
Y419500D01*
G01X960833Y422833D02*
X963167D01*
G01X966183Y419500D02*
Y424500D01*
G01Y422083D02*
X966600Y422500D01*
X967017Y422750D01*
X967683Y422833D01*
X968183Y422750D01*
X968767Y422417D01*
X969017Y421917D01*
Y419500D01*
G01X977633D02*
Y422833D01*
G01Y422167D02*
X978050Y422500D01*
X978467Y422750D01*
X979050Y422833D01*
X979467Y422750D01*
X979967Y422500D01*
G01X983150Y421750D02*
X985817D01*
X985567Y422333D01*
X985150Y422667D01*
X984567Y422833D01*
X983983Y422750D01*
X983483Y422500D01*
X983150Y421917D01*
X982983Y421417D01*
Y420917D01*
X983150Y420417D01*
X983567Y419917D01*
X984067Y419583D01*
X984650Y419500D01*
X985233Y419667D01*
X985817Y420167D01*
G01X988750Y420083D02*
X989167Y419750D01*
X989750Y419500D01*
X990250D01*
X990750Y419667D01*
X991083Y419917D01*
X991250Y420250D01*
X991167Y420750D01*
X990833Y421000D01*
X989333Y421500D01*
X989000Y422083D01*
X989167Y422500D01*
X989500Y422750D01*
X990000Y422833D01*
X990500Y422750D01*
X991000Y422500D01*
G01X995600Y422833D02*
Y419500D01*
G01Y424167D02*
X995433Y424250D01*
Y424417D01*
X995600Y424500D01*
X995767Y424417D01*
Y424250D01*
X995600Y424167D01*
G01X999783Y419500D02*
Y422833D01*
G01Y422000D02*
X1000117Y422417D01*
X1000617Y422750D01*
X1001283Y422833D01*
X1001867Y422750D01*
X1002367Y422417D01*
X1002617Y421833D01*
Y419500D01*
G01X819590Y389810D02*
Y394060D01*
X819757Y394477D01*
X820090Y394727D01*
X820590Y394810D01*
X821090Y394643D01*
X821340Y394227D01*
G01X820340Y392810D02*
X818673D01*
G01X825690Y389810D02*
X825190Y389893D01*
X824690Y390227D01*
X824357Y390810D01*
X824190Y391477D01*
X824357Y392143D01*
X824690Y392727D01*
X825190Y393060D01*
X825690Y393143D01*
X826190Y393060D01*
X826690Y392727D01*
X827023Y392143D01*
X827107Y391477D01*
X827023Y390810D01*
X826690Y390227D01*
X826190Y389893D01*
X825690Y389810D01*
G01X831290D02*
Y394810D01*
G01X836890Y389810D02*
Y394810D01*
G01X842490Y389810D02*
X841990Y389893D01*
X841490Y390227D01*
X841157Y390810D01*
X840990Y391477D01*
X841157Y392143D01*
X841490Y392727D01*
X841990Y393060D01*
X842490Y393143D01*
X842990Y393060D01*
X843490Y392727D01*
X843823Y392143D01*
X843907Y391477D01*
X843823Y390810D01*
X843490Y390227D01*
X842990Y389893D01*
X842490Y389810D01*
G01X846007Y393143D02*
X847007Y389810D01*
X848090Y393143D01*
X849173Y389810D01*
X850173Y393143D01*
G01X859790Y392310D02*
X861457D01*
Y390810D01*
X860957Y390310D01*
X860373Y389977D01*
X859540Y389810D01*
X858707Y389977D01*
X858123Y390310D01*
X857623Y390810D01*
X857290Y391393D01*
X857123Y392060D01*
Y392643D01*
X857290Y393143D01*
X857623Y393727D01*
X858123Y394227D01*
X858623Y394560D01*
X859290Y394810D01*
X859873D01*
X860540Y394643D01*
X861040Y394310D01*
G01X863640Y392060D02*
X866307D01*
X866057Y392643D01*
X865640Y392977D01*
X865057Y393143D01*
X864473Y393060D01*
X863973Y392810D01*
X863640Y392227D01*
X863473Y391727D01*
Y391227D01*
X863640Y390727D01*
X864057Y390227D01*
X864557Y389893D01*
X865140Y389810D01*
X865723Y389977D01*
X866307Y390477D01*
G01X869323Y389810D02*
Y393143D01*
G01Y392477D02*
X869740Y392810D01*
X870157Y393060D01*
X870740Y393143D01*
X871157Y393060D01*
X871657Y392810D01*
G01X874590Y389810D02*
Y394810D01*
G01Y392310D02*
X875007Y392810D01*
X875507Y393060D01*
X876007Y393143D01*
X876757Y392977D01*
X877257Y392643D01*
X877590Y392060D01*
Y391393D01*
X877423Y390727D01*
X877090Y390227D01*
X876507Y389893D01*
X876007Y389810D01*
X875507Y389893D01*
X875007Y390143D01*
X874590Y390560D01*
G01X880440Y392060D02*
X883107D01*
X882857Y392643D01*
X882440Y392977D01*
X881857Y393143D01*
X881273Y393060D01*
X880773Y392810D01*
X880440Y392227D01*
X880273Y391727D01*
Y391227D01*
X880440Y390727D01*
X880857Y390227D01*
X881357Y389893D01*
X881940Y389810D01*
X882523Y389977D01*
X883107Y390477D01*
G01X886123Y389810D02*
Y393143D01*
G01Y392477D02*
X886540Y392810D01*
X886957Y393060D01*
X887540Y393143D01*
X887957Y393060D01*
X888457Y392810D01*
G01X899990Y389810D02*
Y393143D01*
G01Y392560D02*
X899657Y392893D01*
X899157Y393060D01*
X898573Y393143D01*
X897990Y392977D01*
X897490Y392643D01*
X897157Y392143D01*
X896990Y391477D01*
X897157Y390810D01*
X897490Y390310D01*
X897990Y389977D01*
X898573Y389810D01*
X899157Y389893D01*
X899657Y390143D01*
X899990Y390477D01*
G01X902673Y389810D02*
Y393143D01*
G01Y392310D02*
X903007Y392727D01*
X903507Y393060D01*
X904173Y393143D01*
X904757Y393060D01*
X905257Y392727D01*
X905507Y392143D01*
Y389810D01*
G01X911190Y394810D02*
Y389810D01*
G01Y390560D02*
X910857Y390143D01*
X910357Y389893D01*
X909773Y389810D01*
X909107Y389977D01*
X908607Y390393D01*
X908273Y390893D01*
X908190Y391477D01*
X908273Y392060D01*
X908607Y392560D01*
X909107Y392977D01*
X909773Y393143D01*
X910357Y393060D01*
X910773Y392893D01*
X911190Y392560D01*
G01X919390Y388143D02*
Y393143D01*
G01Y392393D02*
X919807Y392810D01*
X920223Y393060D01*
X920890Y393143D01*
X921473Y393060D01*
X922057Y392643D01*
X922307Y392060D01*
X922390Y391477D01*
X922307Y390893D01*
X922057Y390310D01*
X921557Y389977D01*
X920890Y389810D01*
X920307Y389893D01*
X919723Y390143D01*
X919390Y390477D01*
G01X926490Y389810D02*
Y394810D01*
G01X930673Y393143D02*
Y390810D01*
X931007Y390227D01*
X931507Y389893D01*
X932090Y389810D01*
X932673Y389893D01*
X933173Y390227D01*
X933507Y390810D01*
G01Y389810D02*
Y393143D01*
G01X936523Y388560D02*
X937107Y388227D01*
X937773Y388143D01*
X938357Y388227D01*
X938857Y388643D01*
X939190Y389227D01*
Y393143D01*
G01Y392477D02*
X938857Y392810D01*
X938357Y393060D01*
X937773Y393143D01*
X937107Y392977D01*
X936690Y392643D01*
X936357Y392060D01*
X936190Y391477D01*
X936273Y390977D01*
X936607Y390393D01*
X937107Y389977D01*
X937773Y389810D01*
X938273Y389893D01*
X938857Y390227D01*
X939190Y390560D01*
G01X946807Y393143D02*
X947807Y389810D01*
X948890Y393143D01*
X949973Y389810D01*
X950973Y393143D01*
G01X954490D02*
Y389810D01*
G01Y394477D02*
X954323Y394560D01*
Y394727D01*
X954490Y394810D01*
X954657Y394727D01*
Y394560D01*
X954490Y394477D01*
G01X960090Y394810D02*
Y389810D01*
G01X958923Y393143D02*
X961257D01*
G01X964273Y389810D02*
Y394810D01*
G01Y392393D02*
X964690Y392810D01*
X965107Y393060D01*
X965773Y393143D01*
X966273Y393060D01*
X966857Y392727D01*
X967107Y392227D01*
Y389810D01*
G01X975723D02*
Y393143D01*
G01Y392477D02*
X976140Y392810D01*
X976557Y393060D01*
X977140Y393143D01*
X977557Y393060D01*
X978057Y392810D01*
G01X981240Y392060D02*
X983907D01*
X983657Y392643D01*
X983240Y392977D01*
X982657Y393143D01*
X982073Y393060D01*
X981573Y392810D01*
X981240Y392227D01*
X981073Y391727D01*
Y391227D01*
X981240Y390727D01*
X981657Y390227D01*
X982157Y389893D01*
X982740Y389810D01*
X983323Y389977D01*
X983907Y390477D01*
G01X986840Y390393D02*
X987257Y390060D01*
X987840Y389810D01*
X988340D01*
X988840Y389977D01*
X989173Y390227D01*
X989340Y390560D01*
X989257Y391060D01*
X988923Y391310D01*
X987423Y391810D01*
X987090Y392393D01*
X987257Y392810D01*
X987590Y393060D01*
X988090Y393143D01*
X988590Y393060D01*
X989090Y392810D01*
G01X993690Y393143D02*
Y389810D01*
G01Y394477D02*
X993523Y394560D01*
Y394727D01*
X993690Y394810D01*
X993857Y394727D01*
Y394560D01*
X993690Y394477D01*
G01X997873Y389810D02*
Y393143D01*
G01Y392310D02*
X998207Y392727D01*
X998707Y393060D01*
X999373Y393143D01*
X999957Y393060D01*
X1000457Y392727D01*
X1000707Y392143D01*
Y389810D01*
G01X829750Y542583D02*
X830167Y542250D01*
X830750Y542000D01*
X831250D01*
X831750Y542167D01*
X832083Y542417D01*
X832250Y542750D01*
X832167Y543250D01*
X831833Y543500D01*
X830333Y544000D01*
X830000Y544583D01*
X830167Y545000D01*
X830500Y545250D01*
X831000Y545333D01*
X831500Y545250D01*
X832000Y545000D01*
G01X836600Y542000D02*
X836100Y542083D01*
X835600Y542417D01*
X835267Y543000D01*
X835100Y543667D01*
X835267Y544333D01*
X835600Y544917D01*
X836100Y545250D01*
X836600Y545333D01*
X837100Y545250D01*
X837600Y544917D01*
X837933Y544333D01*
X838017Y543667D01*
X837933Y543000D01*
X837600Y542417D01*
X837100Y542083D01*
X836600Y542000D01*
G01X842200D02*
Y547000D01*
G01X849300D02*
Y542000D01*
G01Y542750D02*
X848967Y542333D01*
X848467Y542083D01*
X847883Y542000D01*
X847217Y542167D01*
X846717Y542583D01*
X846383Y543083D01*
X846300Y543667D01*
X846383Y544250D01*
X846717Y544750D01*
X847217Y545167D01*
X847883Y545333D01*
X848467Y545250D01*
X848883Y545083D01*
X849300Y544750D01*
G01X852150Y544250D02*
X854817D01*
X854567Y544833D01*
X854150Y545167D01*
X853567Y545333D01*
X852983Y545250D01*
X852483Y545000D01*
X852150Y544417D01*
X851983Y543917D01*
Y543417D01*
X852150Y542917D01*
X852567Y542417D01*
X853067Y542083D01*
X853650Y542000D01*
X854233Y542167D01*
X854817Y542667D01*
G01X857833Y542000D02*
Y545333D01*
G01Y544667D02*
X858250Y545000D01*
X858667Y545250D01*
X859250Y545333D01*
X859667Y545250D01*
X860167Y545000D01*
G01X867700Y542000D02*
Y545333D01*
G01Y544417D02*
X867950Y544833D01*
X868367Y545167D01*
X868950Y545333D01*
X869533Y545167D01*
X869950Y544833D01*
X870200Y544417D01*
Y542000D01*
G01Y544417D02*
X870450Y544833D01*
X870867Y545167D01*
X871450Y545333D01*
X872033Y545167D01*
X872450Y544833D01*
X872700Y544333D01*
Y542000D01*
G01X877300D02*
Y545333D01*
G01Y544750D02*
X876967Y545083D01*
X876467Y545250D01*
X875883Y545333D01*
X875300Y545167D01*
X874800Y544833D01*
X874467Y544333D01*
X874300Y543667D01*
X874467Y543000D01*
X874800Y542500D01*
X875300Y542167D01*
X875883Y542000D01*
X876467Y542083D01*
X876967Y542333D01*
X877300Y542667D01*
G01X880150Y542583D02*
X880567Y542250D01*
X881150Y542000D01*
X881650D01*
X882150Y542167D01*
X882483Y542417D01*
X882650Y542750D01*
X882567Y543250D01*
X882233Y543500D01*
X880733Y544000D01*
X880400Y544583D01*
X880567Y545000D01*
X880900Y545250D01*
X881400Y545333D01*
X881900Y545250D01*
X882400Y545000D01*
G01X885583Y542000D02*
Y547000D01*
G01X888250Y545333D02*
X885583Y543417D01*
G01X886667Y544167D02*
X888417Y542000D01*
G01X896700Y540333D02*
Y545333D01*
G01Y544583D02*
X897117Y545000D01*
X897533Y545250D01*
X898200Y545333D01*
X898783Y545250D01*
X899367Y544833D01*
X899617Y544250D01*
X899700Y543667D01*
X899617Y543083D01*
X899367Y542500D01*
X898867Y542167D01*
X898200Y542000D01*
X897617Y542083D01*
X897033Y542333D01*
X896700Y542667D01*
G01X905300Y542000D02*
Y545333D01*
G01Y544750D02*
X904967Y545083D01*
X904467Y545250D01*
X903883Y545333D01*
X903300Y545167D01*
X902800Y544833D01*
X902467Y544333D01*
X902300Y543667D01*
X902467Y543000D01*
X902800Y542500D01*
X903300Y542167D01*
X903883Y542000D01*
X904467Y542083D01*
X904967Y542333D01*
X905300Y542667D01*
G01X910900Y547000D02*
Y542000D01*
G01Y542750D02*
X910567Y542333D01*
X910067Y542083D01*
X909483Y542000D01*
X908817Y542167D01*
X908317Y542583D01*
X907983Y543083D01*
X907900Y543667D01*
X907983Y544250D01*
X908317Y544750D01*
X908817Y545167D01*
X909483Y545333D01*
X910067Y545250D01*
X910483Y545083D01*
X910900Y544750D01*
G01X829917Y563333D02*
X830917Y560000D01*
X832000Y563333D01*
X833083Y560000D01*
X834083Y563333D01*
G01X836183Y560000D02*
Y565000D01*
G01Y562583D02*
X836600Y563000D01*
X837017Y563250D01*
X837683Y563333D01*
X838183Y563250D01*
X838767Y562917D01*
X839017Y562417D01*
Y560000D01*
G01X843200Y563333D02*
Y560000D01*
G01Y564667D02*
X843033Y564750D01*
Y564917D01*
X843200Y565000D01*
X843367Y564917D01*
Y564750D01*
X843200Y564667D01*
G01X850133Y562917D02*
X849550Y563250D01*
X849050Y563333D01*
X848383Y563167D01*
X847883Y562833D01*
X847550Y562250D01*
X847467Y561667D01*
X847550Y561083D01*
X847883Y560583D01*
X848383Y560167D01*
X849050Y560000D01*
X849633Y560167D01*
X850133Y560500D01*
G01X852983Y560000D02*
Y565000D01*
G01Y562583D02*
X853400Y563000D01*
X853817Y563250D01*
X854483Y563333D01*
X854983Y563250D01*
X855567Y562917D01*
X855817Y562417D01*
Y560000D01*
G01X864350Y560583D02*
X864767Y560250D01*
X865350Y560000D01*
X865850D01*
X866350Y560167D01*
X866683Y560417D01*
X866850Y560750D01*
X866767Y561250D01*
X866433Y561500D01*
X864933Y562000D01*
X864600Y562583D01*
X864767Y563000D01*
X865100Y563250D01*
X865600Y563333D01*
X866100Y563250D01*
X866600Y563000D01*
G01X871200Y563333D02*
Y560000D01*
G01Y564667D02*
X871033Y564750D01*
Y564917D01*
X871200Y565000D01*
X871367Y564917D01*
Y564750D01*
X871200Y564667D01*
G01X875550Y563333D02*
X878050D01*
X875550Y560000D01*
X878050D01*
G01X881150Y562250D02*
X883817D01*
X883567Y562833D01*
X883150Y563167D01*
X882567Y563333D01*
X881983Y563250D01*
X881483Y563000D01*
X881150Y562417D01*
X880983Y561917D01*
Y561417D01*
X881150Y560917D01*
X881567Y560417D01*
X882067Y560083D01*
X882650Y560000D01*
X883233Y560167D01*
X883817Y560667D01*
G01X893600Y563333D02*
Y560000D01*
G01Y564667D02*
X893433Y564750D01*
Y564917D01*
X893600Y565000D01*
X893767Y564917D01*
Y564750D01*
X893600Y564667D01*
G01X897950Y560583D02*
X898367Y560250D01*
X898950Y560000D01*
X899450D01*
X899950Y560167D01*
X900283Y560417D01*
X900450Y560750D01*
X900367Y561250D01*
X900033Y561500D01*
X898533Y562000D01*
X898200Y562583D01*
X898367Y563000D01*
X898700Y563250D01*
X899200Y563333D01*
X899700Y563250D01*
X900200Y563000D01*
G01X908900Y560000D02*
Y565000D01*
G01Y562500D02*
X909317Y563000D01*
X909817Y563250D01*
X910317Y563333D01*
X911067Y563167D01*
X911567Y562833D01*
X911900Y562250D01*
Y561583D01*
X911733Y560917D01*
X911400Y560417D01*
X910817Y560083D01*
X910317Y560000D01*
X909817Y560083D01*
X909317Y560333D01*
X908900Y560750D01*
G01X916000Y563333D02*
Y560000D01*
G01Y564667D02*
X915833Y564750D01*
Y564917D01*
X916000Y565000D01*
X916167Y564917D01*
Y564750D01*
X916000Y564667D01*
G01X920433Y558750D02*
X921017Y558417D01*
X921683Y558333D01*
X922267Y558417D01*
X922767Y558833D01*
X923100Y559417D01*
Y563333D01*
G01Y562667D02*
X922767Y563000D01*
X922267Y563250D01*
X921683Y563333D01*
X921017Y563167D01*
X920600Y562833D01*
X920267Y562250D01*
X920100Y561667D01*
X920183Y561167D01*
X920517Y560583D01*
X921017Y560167D01*
X921683Y560000D01*
X922183Y560083D01*
X922767Y560417D01*
X923100Y560750D01*
G01X926033Y558750D02*
X926617Y558417D01*
X927283Y558333D01*
X927867Y558417D01*
X928367Y558833D01*
X928700Y559417D01*
Y563333D01*
G01Y562667D02*
X928367Y563000D01*
X927867Y563250D01*
X927283Y563333D01*
X926617Y563167D01*
X926200Y562833D01*
X925867Y562250D01*
X925700Y561667D01*
X925783Y561167D01*
X926117Y560583D01*
X926617Y560167D01*
X927283Y560000D01*
X927783Y560083D01*
X928367Y560417D01*
X928700Y560750D01*
G01X931550Y562250D02*
X934217D01*
X933967Y562833D01*
X933550Y563167D01*
X932967Y563333D01*
X932383Y563250D01*
X931883Y563000D01*
X931550Y562417D01*
X931383Y561917D01*
Y561417D01*
X931550Y560917D01*
X931967Y560417D01*
X932467Y560083D01*
X933050Y560000D01*
X933633Y560167D01*
X934217Y560667D01*
G01X937233Y560000D02*
Y563333D01*
G01Y562667D02*
X937650Y563000D01*
X938067Y563250D01*
X938650Y563333D01*
X939067Y563250D01*
X939567Y563000D01*
G01X949600Y565000D02*
Y560000D01*
G01X948433Y563333D02*
X950767D01*
G01X953783Y560000D02*
Y565000D01*
G01Y562583D02*
X954200Y563000D01*
X954617Y563250D01*
X955283Y563333D01*
X955783Y563250D01*
X956367Y562917D01*
X956617Y562417D01*
Y560000D01*
G01X962300D02*
Y563333D01*
G01Y562750D02*
X961967Y563083D01*
X961467Y563250D01*
X960883Y563333D01*
X960300Y563167D01*
X959800Y562833D01*
X959467Y562333D01*
X959300Y561667D01*
X959467Y561000D01*
X959800Y560500D01*
X960300Y560167D01*
X960883Y560000D01*
X961467Y560083D01*
X961967Y560333D01*
X962300Y560667D01*
G01X964983Y560000D02*
Y563333D01*
G01Y562500D02*
X965317Y562917D01*
X965817Y563250D01*
X966483Y563333D01*
X967067Y563250D01*
X967567Y562917D01*
X967817Y562333D01*
Y560000D01*
G01X979100D02*
Y563333D01*
G01Y562750D02*
X978767Y563083D01*
X978267Y563250D01*
X977683Y563333D01*
X977100Y563167D01*
X976600Y562833D01*
X976267Y562333D01*
X976100Y561667D01*
X976267Y561000D01*
X976600Y560500D01*
X977100Y560167D01*
X977683Y560000D01*
X978267Y560083D01*
X978767Y560333D01*
X979100Y560667D01*
G01X981783Y560000D02*
Y563333D01*
G01Y562500D02*
X982117Y562917D01*
X982617Y563250D01*
X983283Y563333D01*
X983867Y563250D01*
X984367Y562917D01*
X984617Y562333D01*
Y560000D01*
G01X987383D02*
Y563333D01*
G01Y562500D02*
X987717Y562917D01*
X988217Y563250D01*
X988883Y563333D01*
X989467Y563250D01*
X989967Y562917D01*
X990217Y562333D01*
Y560000D01*
G01X992983Y563333D02*
Y561000D01*
X993317Y560417D01*
X993817Y560083D01*
X994400Y560000D01*
X994983Y560083D01*
X995483Y560417D01*
X995817Y561000D01*
G01Y560000D02*
Y563333D01*
G01X1001500Y560000D02*
Y563333D01*
G01Y562750D02*
X1001167Y563083D01*
X1000667Y563250D01*
X1000083Y563333D01*
X999500Y563167D01*
X999000Y562833D01*
X998667Y562333D01*
X998500Y561667D01*
X998667Y561000D01*
X999000Y560500D01*
X999500Y560167D01*
X1000083Y560000D01*
X1000667Y560083D01*
X1001167Y560333D01*
X1001500Y560667D01*
G01X1005600Y560000D02*
Y565000D01*
G01X822000Y569000D02*
Y574000D01*
X821000Y573000D01*
G01Y569000D02*
X823000D01*
G01X827600Y568833D02*
X827433Y568917D01*
Y569083D01*
X827600Y569167D01*
X827767Y569083D01*
Y568917D01*
X827600Y568833D01*
G01X833200Y569000D02*
X832533Y569083D01*
X831950Y569417D01*
X831450Y569917D01*
X831117Y570500D01*
X830950Y571167D01*
Y571833D01*
X831117Y572500D01*
X831450Y573083D01*
X831950Y573583D01*
X832533Y573917D01*
X833200Y574000D01*
X833867Y573917D01*
X834450Y573583D01*
X834950Y573083D01*
X835283Y572500D01*
X835450Y571833D01*
Y571167D01*
X835283Y570500D01*
X834950Y569917D01*
X834450Y569417D01*
X833867Y569083D01*
X833200Y569000D01*
G01X837383D02*
Y572333D01*
G01Y571500D02*
X837717Y571917D01*
X838217Y572250D01*
X838883Y572333D01*
X839467Y572250D01*
X839967Y571917D01*
X840217Y571333D01*
Y569000D01*
G01X843150Y571250D02*
X845817D01*
X845567Y571833D01*
X845150Y572167D01*
X844567Y572333D01*
X843983Y572250D01*
X843483Y572000D01*
X843150Y571417D01*
X842983Y570917D01*
Y570417D01*
X843150Y569917D01*
X843567Y569417D01*
X844067Y569083D01*
X844650Y569000D01*
X845233Y569167D01*
X845817Y569667D01*
G01X854350Y569583D02*
X854767Y569250D01*
X855350Y569000D01*
X855850D01*
X856350Y569167D01*
X856683Y569417D01*
X856850Y569750D01*
X856767Y570250D01*
X856433Y570500D01*
X854933Y571000D01*
X854600Y571583D01*
X854767Y572000D01*
X855100Y572250D01*
X855600Y572333D01*
X856100Y572250D01*
X856600Y572000D01*
G01X861200Y572333D02*
Y569000D01*
G01Y573667D02*
X861033Y573750D01*
Y573917D01*
X861200Y574000D01*
X861367Y573917D01*
Y573750D01*
X861200Y573667D01*
G01X868300Y574000D02*
Y569000D01*
G01Y569750D02*
X867967Y569333D01*
X867467Y569083D01*
X866883Y569000D01*
X866217Y569167D01*
X865717Y569583D01*
X865383Y570083D01*
X865300Y570667D01*
X865383Y571250D01*
X865717Y571750D01*
X866217Y572167D01*
X866883Y572333D01*
X867467Y572250D01*
X867883Y572083D01*
X868300Y571750D01*
G01X871150Y571250D02*
X873817D01*
X873567Y571833D01*
X873150Y572167D01*
X872567Y572333D01*
X871983Y572250D01*
X871483Y572000D01*
X871150Y571417D01*
X870983Y570917D01*
Y570417D01*
X871150Y569917D01*
X871567Y569417D01*
X872067Y569083D01*
X872650Y569000D01*
X873233Y569167D01*
X873817Y569667D01*
G01X881517Y572333D02*
X882517Y569000D01*
X883600Y572333D01*
X884683Y569000D01*
X885683Y572333D01*
G01X889200D02*
Y569000D01*
G01Y573667D02*
X889033Y573750D01*
Y573917D01*
X889200Y574000D01*
X889367Y573917D01*
Y573750D01*
X889200Y573667D01*
G01X894800Y574000D02*
Y569000D01*
G01X893633Y572333D02*
X895967D01*
G01X898983Y569000D02*
Y574000D01*
G01Y571583D02*
X899400Y572000D01*
X899817Y572250D01*
X900483Y572333D01*
X900983Y572250D01*
X901567Y571917D01*
X901817Y571417D01*
Y569000D01*
G01X910350Y569583D02*
X910767Y569250D01*
X911350Y569000D01*
X911850D01*
X912350Y569167D01*
X912683Y569417D01*
X912850Y569750D01*
X912767Y570250D01*
X912433Y570500D01*
X910933Y571000D01*
X910600Y571583D01*
X910767Y572000D01*
X911100Y572250D01*
X911600Y572333D01*
X912100Y572250D01*
X912600Y572000D01*
G01X917200Y569000D02*
X916700Y569083D01*
X916200Y569417D01*
X915867Y570000D01*
X915700Y570667D01*
X915867Y571333D01*
X916200Y571917D01*
X916700Y572250D01*
X917200Y572333D01*
X917700Y572250D01*
X918200Y571917D01*
X918533Y571333D01*
X918617Y570667D01*
X918533Y570000D01*
X918200Y569417D01*
X917700Y569083D01*
X917200Y569000D01*
G01X922800D02*
Y574000D01*
G01X929900D02*
Y569000D01*
G01Y569750D02*
X929567Y569333D01*
X929067Y569083D01*
X928483Y569000D01*
X927817Y569167D01*
X927317Y569583D01*
X926983Y570083D01*
X926900Y570667D01*
X926983Y571250D01*
X927317Y571750D01*
X927817Y572167D01*
X928483Y572333D01*
X929067Y572250D01*
X929483Y572083D01*
X929900Y571750D01*
G01X932750Y571250D02*
X935417D01*
X935167Y571833D01*
X934750Y572167D01*
X934167Y572333D01*
X933583Y572250D01*
X933083Y572000D01*
X932750Y571417D01*
X932583Y570917D01*
Y570417D01*
X932750Y569917D01*
X933167Y569417D01*
X933667Y569083D01*
X934250Y569000D01*
X934833Y569167D01*
X935417Y569667D01*
G01X938433Y569000D02*
Y572333D01*
G01Y571667D02*
X938850Y572000D01*
X939267Y572250D01*
X939850Y572333D01*
X940267Y572250D01*
X940767Y572000D01*
G01X948300Y569000D02*
Y572333D01*
G01Y571417D02*
X948550Y571833D01*
X948967Y572167D01*
X949550Y572333D01*
X950133Y572167D01*
X950550Y571833D01*
X950800Y571417D01*
Y569000D01*
G01Y571417D02*
X951050Y571833D01*
X951467Y572167D01*
X952050Y572333D01*
X952633Y572167D01*
X953050Y571833D01*
X953300Y571333D01*
Y569000D01*
G01X957900D02*
Y572333D01*
G01Y571750D02*
X957567Y572083D01*
X957067Y572250D01*
X956483Y572333D01*
X955900Y572167D01*
X955400Y571833D01*
X955067Y571333D01*
X954900Y570667D01*
X955067Y570000D01*
X955400Y569500D01*
X955900Y569167D01*
X956483Y569000D01*
X957067Y569083D01*
X957567Y569333D01*
X957900Y569667D01*
G01X960750Y569583D02*
X961167Y569250D01*
X961750Y569000D01*
X962250D01*
X962750Y569167D01*
X963083Y569417D01*
X963250Y569750D01*
X963167Y570250D01*
X962833Y570500D01*
X961333Y571000D01*
X961000Y571583D01*
X961167Y572000D01*
X961500Y572250D01*
X962000Y572333D01*
X962500Y572250D01*
X963000Y572000D01*
G01X966183Y569000D02*
Y574000D01*
G01X968850Y572333D02*
X966183Y570417D01*
G01X967267Y571167D02*
X969017Y569000D01*
G01X977300Y567333D02*
Y572333D01*
G01Y571583D02*
X977717Y572000D01*
X978133Y572250D01*
X978800Y572333D01*
X979383Y572250D01*
X979967Y571833D01*
X980217Y571250D01*
X980300Y570667D01*
X980217Y570083D01*
X979967Y569500D01*
X979467Y569167D01*
X978800Y569000D01*
X978217Y569083D01*
X977633Y569333D01*
X977300Y569667D01*
G01X985900Y569000D02*
Y572333D01*
G01Y571750D02*
X985567Y572083D01*
X985067Y572250D01*
X984483Y572333D01*
X983900Y572167D01*
X983400Y571833D01*
X983067Y571333D01*
X982900Y570667D01*
X983067Y570000D01*
X983400Y569500D01*
X983900Y569167D01*
X984483Y569000D01*
X985067Y569083D01*
X985567Y569333D01*
X985900Y569667D01*
G01X991500Y574000D02*
Y569000D01*
G01Y569750D02*
X991167Y569333D01*
X990667Y569083D01*
X990083Y569000D01*
X989417Y569167D01*
X988917Y569583D01*
X988583Y570083D01*
X988500Y570667D01*
X988583Y571250D01*
X988917Y571750D01*
X989417Y572167D01*
X990083Y572333D01*
X990667Y572250D01*
X991083Y572083D01*
X991500Y571750D01*
G01X831333Y551000D02*
Y554333D01*
G01Y553667D02*
X831750Y554000D01*
X832167Y554250D01*
X832750Y554333D01*
X833167Y554250D01*
X833667Y554000D01*
G01X838100Y554333D02*
Y551000D01*
G01Y555667D02*
X837933Y555750D01*
Y555917D01*
X838100Y556000D01*
X838267Y555917D01*
Y555750D01*
X838100Y555667D01*
G01X842283Y551000D02*
Y554333D01*
G01Y553500D02*
X842617Y553917D01*
X843117Y554250D01*
X843783Y554333D01*
X844367Y554250D01*
X844867Y553917D01*
X845117Y553333D01*
Y551000D01*
G01X848133Y549750D02*
X848717Y549417D01*
X849383Y549333D01*
X849967Y549417D01*
X850467Y549833D01*
X850800Y550417D01*
Y554333D01*
G01Y553667D02*
X850467Y554000D01*
X849967Y554250D01*
X849383Y554333D01*
X848717Y554167D01*
X848300Y553833D01*
X847967Y553250D01*
X847800Y552667D01*
X847883Y552167D01*
X848217Y551583D01*
X848717Y551167D01*
X849383Y551000D01*
X849883Y551083D01*
X850467Y551417D01*
X850800Y551750D01*
G01X859250Y551583D02*
X859667Y551250D01*
X860250Y551000D01*
X860750D01*
X861250Y551167D01*
X861583Y551417D01*
X861750Y551750D01*
X861667Y552250D01*
X861333Y552500D01*
X859833Y553000D01*
X859500Y553583D01*
X859667Y554000D01*
X860000Y554250D01*
X860500Y554333D01*
X861000Y554250D01*
X861500Y554000D01*
G01X866100Y554333D02*
Y551000D01*
G01Y555667D02*
X865933Y555750D01*
Y555917D01*
X866100Y556000D01*
X866267Y555917D01*
Y555750D01*
X866100Y555667D01*
G01X870450Y554333D02*
X872950D01*
X870450Y551000D01*
X872950D01*
G01X876050Y553250D02*
X878717D01*
X878467Y553833D01*
X878050Y554167D01*
X877467Y554333D01*
X876883Y554250D01*
X876383Y554000D01*
X876050Y553417D01*
X875883Y552917D01*
Y552417D01*
X876050Y551917D01*
X876467Y551417D01*
X876967Y551083D01*
X877550Y551000D01*
X878133Y551167D01*
X878717Y551667D01*
G01X888333Y550083D02*
X888667Y551167D01*
G01X794500Y674500D02*
Y669500D01*
G01X793333Y672833D02*
X795667D01*
G01X798683Y669500D02*
Y674500D01*
G01Y672083D02*
X799100Y672500D01*
X799517Y672750D01*
X800183Y672833D01*
X800683Y672750D01*
X801267Y672417D01*
X801517Y671917D01*
Y669500D01*
G01X805700Y672833D02*
Y669500D01*
G01Y674167D02*
X805533Y674250D01*
Y674417D01*
X805700Y674500D01*
X805867Y674417D01*
Y674250D01*
X805700Y674167D01*
G01X812633Y672417D02*
X812050Y672750D01*
X811550Y672833D01*
X810883Y672667D01*
X810383Y672333D01*
X810050Y671750D01*
X809967Y671167D01*
X810050Y670583D01*
X810383Y670083D01*
X810883Y669667D01*
X811550Y669500D01*
X812133Y669667D01*
X812633Y670000D01*
G01X815483Y669500D02*
Y674500D01*
G01X818150Y672833D02*
X815483Y670917D01*
G01X816567Y671667D02*
X818317Y669500D01*
G01X821083D02*
Y672833D01*
G01Y672000D02*
X821417Y672417D01*
X821917Y672750D01*
X822583Y672833D01*
X823167Y672750D01*
X823667Y672417D01*
X823917Y671833D01*
Y669500D01*
G01X826850Y671750D02*
X829517D01*
X829267Y672333D01*
X828850Y672667D01*
X828267Y672833D01*
X827683Y672750D01*
X827183Y672500D01*
X826850Y671917D01*
X826683Y671417D01*
Y670917D01*
X826850Y670417D01*
X827267Y669917D01*
X827767Y669583D01*
X828350Y669500D01*
X828933Y669667D01*
X829517Y670167D01*
G01X832450Y670083D02*
X832867Y669750D01*
X833450Y669500D01*
X833950D01*
X834450Y669667D01*
X834783Y669917D01*
X834950Y670250D01*
X834867Y670750D01*
X834533Y671000D01*
X833033Y671500D01*
X832700Y672083D01*
X832867Y672500D01*
X833200Y672750D01*
X833700Y672833D01*
X834200Y672750D01*
X834700Y672500D01*
G01X838050Y670083D02*
X838467Y669750D01*
X839050Y669500D01*
X839550D01*
X840050Y669667D01*
X840383Y669917D01*
X840550Y670250D01*
X840467Y670750D01*
X840133Y671000D01*
X838633Y671500D01*
X838300Y672083D01*
X838467Y672500D01*
X838800Y672750D01*
X839300Y672833D01*
X839800Y672750D01*
X840300Y672500D01*
G01X809000Y686500D02*
Y691500D01*
G01Y689000D02*
X809417Y689500D01*
X809917Y689750D01*
X810417Y689833D01*
X811167Y689667D01*
X811667Y689333D01*
X812000Y688750D01*
Y688083D01*
X811833Y687417D01*
X811500Y686917D01*
X810917Y686583D01*
X810417Y686500D01*
X809917Y686583D01*
X809417Y686833D01*
X809000Y687250D01*
G01X816100Y686500D02*
X815600Y686583D01*
X815100Y686917D01*
X814767Y687500D01*
X814600Y688167D01*
X814767Y688833D01*
X815100Y689417D01*
X815600Y689750D01*
X816100Y689833D01*
X816600Y689750D01*
X817100Y689417D01*
X817433Y688833D01*
X817517Y688167D01*
X817433Y687500D01*
X817100Y686917D01*
X816600Y686583D01*
X816100Y686500D01*
G01X823200D02*
Y689833D01*
G01Y689250D02*
X822867Y689583D01*
X822367Y689750D01*
X821783Y689833D01*
X821200Y689667D01*
X820700Y689333D01*
X820367Y688833D01*
X820200Y688167D01*
X820367Y687500D01*
X820700Y687000D01*
X821200Y686667D01*
X821783Y686500D01*
X822367Y686583D01*
X822867Y686833D01*
X823200Y687167D01*
G01X826133Y686500D02*
Y689833D01*
G01Y689167D02*
X826550Y689500D01*
X826967Y689750D01*
X827550Y689833D01*
X827967Y689750D01*
X828467Y689500D01*
G01X834400Y691500D02*
Y686500D01*
G01Y687250D02*
X834067Y686833D01*
X833567Y686583D01*
X832983Y686500D01*
X832317Y686667D01*
X831817Y687083D01*
X831483Y687583D01*
X831400Y688167D01*
X831483Y688750D01*
X831817Y689250D01*
X832317Y689667D01*
X832983Y689833D01*
X833567Y689750D01*
X833983Y689583D01*
X834400Y689250D01*
G01X843083Y734500D02*
Y739500D01*
G01Y737083D02*
X843500Y737500D01*
X843917Y737750D01*
X844583Y737833D01*
X845083Y737750D01*
X845667Y737417D01*
X845917Y736917D01*
Y734500D01*
G01X851600D02*
Y737833D01*
G01Y737250D02*
X851267Y737583D01*
X850767Y737750D01*
X850183Y737833D01*
X849600Y737667D01*
X849100Y737333D01*
X848767Y736833D01*
X848600Y736167D01*
X848767Y735500D01*
X849100Y735000D01*
X849600Y734667D01*
X850183Y734500D01*
X850767Y734583D01*
X851267Y734833D01*
X851600Y735167D01*
G01X855700Y734500D02*
Y739500D01*
G01X860800Y734500D02*
Y738750D01*
X860967Y739167D01*
X861300Y739417D01*
X861800Y739500D01*
X862300Y739333D01*
X862550Y738917D01*
G01X861550Y737500D02*
X859883D01*
G01X871000Y732833D02*
Y737833D01*
G01Y737083D02*
X871417Y737500D01*
X871833Y737750D01*
X872500Y737833D01*
X873083Y737750D01*
X873667Y737333D01*
X873917Y736750D01*
X874000Y736167D01*
X873917Y735583D01*
X873667Y735000D01*
X873167Y734667D01*
X872500Y734500D01*
X871917Y734583D01*
X871333Y734833D01*
X871000Y735167D01*
G01X878100Y734500D02*
Y739500D01*
G01X882283Y737833D02*
Y735500D01*
X882617Y734917D01*
X883117Y734583D01*
X883700Y734500D01*
X884283Y734583D01*
X884783Y734917D01*
X885117Y735500D01*
G01Y734500D02*
Y737833D01*
G01X888133Y733250D02*
X888717Y732917D01*
X889383Y732833D01*
X889967Y732917D01*
X890467Y733333D01*
X890800Y733917D01*
Y737833D01*
G01Y737167D02*
X890467Y737500D01*
X889967Y737750D01*
X889383Y737833D01*
X888717Y737667D01*
X888300Y737333D01*
X887967Y736750D01*
X887800Y736167D01*
X887883Y735667D01*
X888217Y735083D01*
X888717Y734667D01*
X889383Y734500D01*
X889883Y734583D01*
X890467Y734917D01*
X890800Y735250D01*
G01X893733Y733250D02*
X894317Y732917D01*
X894983Y732833D01*
X895567Y732917D01*
X896067Y733333D01*
X896400Y733917D01*
Y737833D01*
G01Y737167D02*
X896067Y737500D01*
X895567Y737750D01*
X894983Y737833D01*
X894317Y737667D01*
X893900Y737333D01*
X893567Y736750D01*
X893400Y736167D01*
X893483Y735667D01*
X893817Y735083D01*
X894317Y734667D01*
X894983Y734500D01*
X895483Y734583D01*
X896067Y734917D01*
X896400Y735250D01*
G01X900500Y737833D02*
Y734500D01*
G01Y739167D02*
X900333Y739250D01*
Y739417D01*
X900500Y739500D01*
X900667Y739417D01*
Y739250D01*
X900500Y739167D01*
G01X904683Y734500D02*
Y737833D01*
G01Y737000D02*
X905017Y737417D01*
X905517Y737750D01*
X906183Y737833D01*
X906767Y737750D01*
X907267Y737417D01*
X907517Y736833D01*
Y734500D01*
G01X910533Y733250D02*
X911117Y732917D01*
X911783Y732833D01*
X912367Y732917D01*
X912867Y733333D01*
X913200Y733917D01*
Y737833D01*
G01Y737167D02*
X912867Y737500D01*
X912367Y737750D01*
X911783Y737833D01*
X911117Y737667D01*
X910700Y737333D01*
X910367Y736750D01*
X910200Y736167D01*
X910283Y735667D01*
X910617Y735083D01*
X911117Y734667D01*
X911783Y734500D01*
X912283Y734583D01*
X912867Y734917D01*
X913200Y735250D01*
G01X798500Y795500D02*
Y790500D01*
G01X796583Y795500D02*
X800417D01*
G01X802017Y793833D02*
X803017Y790500D01*
X804100Y793833D01*
X805183Y790500D01*
X806183Y793833D01*
G01X809700D02*
Y790500D01*
G01Y795167D02*
X809533Y795250D01*
Y795417D01*
X809700Y795500D01*
X809867Y795417D01*
Y795250D01*
X809700Y795167D01*
G01X814050Y791083D02*
X814467Y790750D01*
X815050Y790500D01*
X815550D01*
X816050Y790667D01*
X816383Y790917D01*
X816550Y791250D01*
X816467Y791750D01*
X816133Y792000D01*
X814633Y792500D01*
X814300Y793083D01*
X814467Y793500D01*
X814800Y793750D01*
X815300Y793833D01*
X815800Y793750D01*
X816300Y793500D01*
G01X820900Y795500D02*
Y790500D01*
G01X819733Y793833D02*
X822067D01*
G01X833600Y790500D02*
Y793833D01*
G01Y793250D02*
X833267Y793583D01*
X832767Y793750D01*
X832183Y793833D01*
X831600Y793667D01*
X831100Y793333D01*
X830767Y792833D01*
X830600Y792167D01*
X830767Y791500D01*
X831100Y791000D01*
X831600Y790667D01*
X832183Y790500D01*
X832767Y790583D01*
X833267Y790833D01*
X833600Y791167D01*
G01X836283Y790500D02*
Y793833D01*
G01Y793000D02*
X836617Y793417D01*
X837117Y793750D01*
X837783Y793833D01*
X838367Y793750D01*
X838867Y793417D01*
X839117Y792833D01*
Y790500D01*
G01X844800Y795500D02*
Y790500D01*
G01Y791250D02*
X844467Y790833D01*
X843967Y790583D01*
X843383Y790500D01*
X842717Y790667D01*
X842217Y791083D01*
X841883Y791583D01*
X841800Y792167D01*
X841883Y792750D01*
X842217Y793250D01*
X842717Y793667D01*
X843383Y793833D01*
X843967Y793750D01*
X844383Y793583D01*
X844800Y793250D01*
G01X853000Y790500D02*
Y795500D01*
G01Y793000D02*
X853417Y793500D01*
X853917Y793750D01*
X854417Y793833D01*
X855167Y793667D01*
X855667Y793333D01*
X856000Y792750D01*
Y792083D01*
X855833Y791417D01*
X855500Y790917D01*
X854917Y790583D01*
X854417Y790500D01*
X853917Y790583D01*
X853417Y790833D01*
X853000Y791250D01*
G01X860100Y790500D02*
X859600Y790583D01*
X859100Y790917D01*
X858767Y791500D01*
X858600Y792167D01*
X858767Y792833D01*
X859100Y793417D01*
X859600Y793750D01*
X860100Y793833D01*
X860600Y793750D01*
X861100Y793417D01*
X861433Y792833D01*
X861517Y792167D01*
X861433Y791500D01*
X861100Y790917D01*
X860600Y790583D01*
X860100Y790500D01*
G01X863617Y793833D02*
X864617Y790500D01*
X865700Y793833D01*
X866783Y790500D01*
X867783Y793833D01*
G01X796833Y826500D02*
Y831500D01*
X798917D01*
X799583Y831250D01*
X800000Y830917D01*
X800167Y830250D01*
X800000Y829583D01*
X799500Y829167D01*
X798917Y828917D01*
X796833D01*
G01X798917D02*
X800167Y826500D01*
G01X804100D02*
X803600Y826583D01*
X803100Y826917D01*
X802767Y827500D01*
X802600Y828167D01*
X802767Y828833D01*
X803100Y829417D01*
X803600Y829750D01*
X804100Y829833D01*
X804600Y829750D01*
X805100Y829417D01*
X805433Y828833D01*
X805517Y828167D01*
X805433Y827500D01*
X805100Y826917D01*
X804600Y826583D01*
X804100Y826500D01*
G01X808283Y829833D02*
Y827500D01*
X808617Y826917D01*
X809117Y826583D01*
X809700Y826500D01*
X810283Y826583D01*
X810783Y826917D01*
X811117Y827500D01*
G01Y826500D02*
Y829833D01*
G01X815300Y831500D02*
Y826500D01*
G01X814133Y829833D02*
X816467D01*
G01X820900D02*
Y826500D01*
G01Y831167D02*
X820733Y831250D01*
Y831417D01*
X820900Y831500D01*
X821067Y831417D01*
Y831250D01*
X820900Y831167D01*
G01X825083Y826500D02*
Y829833D01*
G01Y829000D02*
X825417Y829417D01*
X825917Y829750D01*
X826583Y829833D01*
X827167Y829750D01*
X827667Y829417D01*
X827917Y828833D01*
Y826500D01*
G01X830933Y825250D02*
X831517Y824917D01*
X832183Y824833D01*
X832767Y824917D01*
X833267Y825333D01*
X833600Y825917D01*
Y829833D01*
G01Y829167D02*
X833267Y829500D01*
X832767Y829750D01*
X832183Y829833D01*
X831517Y829667D01*
X831100Y829333D01*
X830767Y828750D01*
X830600Y828167D01*
X830683Y827667D01*
X831017Y827083D01*
X831517Y826667D01*
X832183Y826500D01*
X832683Y826583D01*
X833267Y826917D01*
X833600Y827250D01*
G01X843300Y831500D02*
Y826500D01*
G01X842133Y829833D02*
X844467D01*
G01X848900Y826500D02*
X848400Y826583D01*
X847900Y826917D01*
X847567Y827500D01*
X847400Y828167D01*
X847567Y828833D01*
X847900Y829417D01*
X848400Y829750D01*
X848900Y829833D01*
X849400Y829750D01*
X849900Y829417D01*
X850233Y828833D01*
X850317Y828167D01*
X850233Y827500D01*
X849900Y826917D01*
X849400Y826583D01*
X848900Y826500D01*
G01X854500D02*
Y831500D01*
G01X858850Y828750D02*
X861517D01*
X861267Y829333D01*
X860850Y829667D01*
X860267Y829833D01*
X859683Y829750D01*
X859183Y829500D01*
X858850Y828917D01*
X858683Y828417D01*
Y827917D01*
X858850Y827417D01*
X859267Y826917D01*
X859767Y826583D01*
X860350Y826500D01*
X860933Y826667D01*
X861517Y827167D01*
G01X864533Y826500D02*
Y829833D01*
G01Y829167D02*
X864950Y829500D01*
X865367Y829750D01*
X865950Y829833D01*
X866367Y829750D01*
X866867Y829500D01*
G01X872800Y826500D02*
Y829833D01*
G01Y829250D02*
X872467Y829583D01*
X871967Y829750D01*
X871383Y829833D01*
X870800Y829667D01*
X870300Y829333D01*
X869967Y828833D01*
X869800Y828167D01*
X869967Y827500D01*
X870300Y827000D01*
X870800Y826667D01*
X871383Y826500D01*
X871967Y826583D01*
X872467Y826833D01*
X872800Y827167D01*
G01X875483Y826500D02*
Y829833D01*
G01Y829000D02*
X875817Y829417D01*
X876317Y829750D01*
X876983Y829833D01*
X877567Y829750D01*
X878067Y829417D01*
X878317Y828833D01*
Y826500D01*
G01X883833Y829417D02*
X883250Y829750D01*
X882750Y829833D01*
X882083Y829667D01*
X881583Y829333D01*
X881250Y828750D01*
X881167Y828167D01*
X881250Y827583D01*
X881583Y827083D01*
X882083Y826667D01*
X882750Y826500D01*
X883333Y826667D01*
X883833Y827000D01*
G01X886850Y828750D02*
X889517D01*
X889267Y829333D01*
X888850Y829667D01*
X888267Y829833D01*
X887683Y829750D01*
X887183Y829500D01*
X886850Y828917D01*
X886683Y828417D01*
Y827917D01*
X886850Y827417D01*
X887267Y826917D01*
X887767Y826583D01*
X888350Y826500D01*
X888933Y826667D01*
X889517Y827167D01*
G01X788000Y850610D02*
Y782110D01*
G01Y805500D02*
X1343000D01*
G01X928583Y23083D02*
X929167Y22667D01*
X929833Y22500D01*
X930500Y22667D01*
X931083Y23167D01*
X931500Y23917D01*
X931667Y24667D01*
Y25583D01*
X931500Y26333D01*
X931083Y27000D01*
X930583Y27333D01*
X930000Y27500D01*
X929333Y27333D01*
X928833Y27000D01*
X928500Y26500D01*
X928333Y25833D01*
X928500Y25250D01*
X928917Y24667D01*
X929417Y24333D01*
X930000Y24250D01*
X930667Y24417D01*
X931167Y24833D01*
X931667Y25583D01*
G01X934017Y24583D02*
X934600Y25167D01*
X935100Y25500D01*
X935767Y25667D01*
X936350Y25500D01*
X936767Y25167D01*
X937100Y24667D01*
X937183Y24083D01*
X937100Y23583D01*
X936767Y23083D01*
X936267Y22667D01*
X935683Y22500D01*
X935017Y22667D01*
X934433Y23167D01*
X934100Y23917D01*
X934017Y24750D01*
X934183Y25833D01*
X934433Y26417D01*
X934850Y27000D01*
X935433Y27417D01*
X936017Y27500D01*
X936600Y27333D01*
X937017Y26917D01*
G01X909000Y67500D02*
Y72500D01*
X905917Y68917D01*
X910083D01*
G01X911767Y68250D02*
X912267Y67833D01*
X912850Y67583D01*
X913600Y67500D01*
X914350Y67667D01*
X914933Y68000D01*
X915350Y68583D01*
X915433Y69250D01*
X915267Y69917D01*
X914850Y70333D01*
X914267Y70667D01*
X913683Y70750D01*
X913100Y70667D01*
X912350Y70333D01*
X912600Y72500D01*
X914850D01*
G01X909250Y184083D02*
X909667Y183750D01*
X910250Y183500D01*
X910750D01*
X911250Y183667D01*
X911583Y183917D01*
X911750Y184250D01*
X911667Y184750D01*
X911333Y185000D01*
X909833Y185500D01*
X909500Y186083D01*
X909667Y186500D01*
X910000Y186750D01*
X910500Y186833D01*
X911000Y186750D01*
X911500Y186500D01*
G01X916100Y188500D02*
Y183500D01*
G01X914933Y186833D02*
X917267D01*
G01X920283D02*
Y184500D01*
X920617Y183917D01*
X921117Y183583D01*
X921700Y183500D01*
X922283Y183583D01*
X922783Y183917D01*
X923117Y184500D01*
G01Y183500D02*
Y186833D01*
G01X925800Y183500D02*
Y188500D01*
G01Y186000D02*
X926217Y186500D01*
X926717Y186750D01*
X927217Y186833D01*
X927967Y186667D01*
X928467Y186333D01*
X928800Y185750D01*
Y185083D01*
X928633Y184417D01*
X928300Y183917D01*
X927717Y183583D01*
X927217Y183500D01*
X926717Y183583D01*
X926217Y183833D01*
X925800Y184250D01*
G01X938500Y183500D02*
Y188500D01*
G01X942850Y185750D02*
X945517D01*
X945267Y186333D01*
X944850Y186667D01*
X944267Y186833D01*
X943683Y186750D01*
X943183Y186500D01*
X942850Y185917D01*
X942683Y185417D01*
Y184917D01*
X942850Y184417D01*
X943267Y183917D01*
X943767Y183583D01*
X944350Y183500D01*
X944933Y183667D01*
X945517Y184167D01*
G01X948283Y183500D02*
Y186833D01*
G01Y186000D02*
X948617Y186417D01*
X949117Y186750D01*
X949783Y186833D01*
X950367Y186750D01*
X950867Y186417D01*
X951117Y185833D01*
Y183500D01*
G01X954133Y182250D02*
X954717Y181917D01*
X955383Y181833D01*
X955967Y181917D01*
X956467Y182333D01*
X956800Y182917D01*
Y186833D01*
G01Y186167D02*
X956467Y186500D01*
X955967Y186750D01*
X955383Y186833D01*
X954717Y186667D01*
X954300Y186333D01*
X953967Y185750D01*
X953800Y185167D01*
X953883Y184667D01*
X954217Y184083D01*
X954717Y183667D01*
X955383Y183500D01*
X955883Y183583D01*
X956467Y183917D01*
X956800Y184250D01*
G01X960900Y188500D02*
Y183500D01*
G01X959733Y186833D02*
X962067D01*
G01X965083Y183500D02*
Y188500D01*
G01Y186083D02*
X965500Y186500D01*
X965917Y186750D01*
X966583Y186833D01*
X967083Y186750D01*
X967667Y186417D01*
X967917Y185917D01*
Y183500D01*
G01X971017Y184417D02*
X973183D01*
G01Y185917D02*
X971017D01*
G01X976117Y185583D02*
X976700Y186167D01*
X977200Y186500D01*
X977867Y186667D01*
X978450Y186500D01*
X978867Y186167D01*
X979200Y185667D01*
X979283Y185083D01*
X979200Y184583D01*
X978867Y184083D01*
X978367Y183667D01*
X977783Y183500D01*
X977117Y183667D01*
X976533Y184167D01*
X976200Y184917D01*
X976117Y185750D01*
X976283Y186833D01*
X976533Y187417D01*
X976950Y188000D01*
X977533Y188417D01*
X978117Y188500D01*
X978700Y188333D01*
X979117Y187917D01*
G01X982383Y185167D02*
X984383D01*
G01X983300Y186250D02*
Y184083D01*
G01X987400Y183333D02*
X990400Y188500D01*
G01X993417Y185167D02*
X995583D01*
G01X998267Y184250D02*
X998767Y183833D01*
X999350Y183583D01*
X1000100Y183500D01*
X1000850Y183667D01*
X1001433Y184000D01*
X1001850Y184583D01*
X1001933Y185250D01*
X1001767Y185917D01*
X1001350Y186333D01*
X1000767Y186667D01*
X1000183Y186750D01*
X999600Y186667D01*
X998850Y186333D01*
X999100Y188500D01*
X1001350D01*
G01X1003200Y183500D02*
Y186833D01*
G01Y185917D02*
X1003450Y186333D01*
X1003867Y186667D01*
X1004450Y186833D01*
X1005033Y186667D01*
X1005450Y186333D01*
X1005700Y185917D01*
Y183500D01*
G01Y185917D02*
X1005950Y186333D01*
X1006367Y186667D01*
X1006950Y186833D01*
X1007533Y186667D01*
X1007950Y186333D01*
X1008200Y185833D01*
Y183500D01*
G01X1011300Y186833D02*
Y183500D01*
G01Y188167D02*
X1011133Y188250D01*
Y188417D01*
X1011300Y188500D01*
X1011467Y188417D01*
Y188250D01*
X1011300Y188167D01*
G01X1016900Y183500D02*
Y188500D01*
G01X868250Y152000D02*
Y157000D01*
G01X871750D02*
Y152000D01*
G01Y154500D02*
X868250D01*
G01X875600Y152000D02*
X874933Y152083D01*
X874350Y152417D01*
X873850Y152917D01*
X873517Y153500D01*
X873350Y154167D01*
Y154833D01*
X873517Y155500D01*
X873850Y156083D01*
X874350Y156583D01*
X874933Y156917D01*
X875600Y157000D01*
X876267Y156917D01*
X876850Y156583D01*
X877350Y156083D01*
X877683Y155500D01*
X877850Y154833D01*
Y154167D01*
X877683Y153500D01*
X877350Y152917D01*
X876850Y152417D01*
X876267Y152083D01*
X875600Y152000D01*
G01X879533Y157000D02*
Y152000D01*
X882867D01*
G01X888467D02*
X885133D01*
Y157000D01*
X888467D01*
G01X887133Y154583D02*
X885133D01*
G01X912300Y152000D02*
Y155333D01*
G01Y154417D02*
X912550Y154833D01*
X912967Y155167D01*
X913550Y155333D01*
X914133Y155167D01*
X914550Y154833D01*
X914800Y154417D01*
Y152000D01*
G01Y154417D02*
X915050Y154833D01*
X915467Y155167D01*
X916050Y155333D01*
X916633Y155167D01*
X917050Y154833D01*
X917300Y154333D01*
Y152000D01*
G01X920400Y155333D02*
Y152000D01*
G01Y156667D02*
X920233Y156750D01*
Y156917D01*
X920400Y157000D01*
X920567Y156917D01*
Y156750D01*
X920400Y156667D01*
G01X926000Y152000D02*
Y157000D01*
G01X930350Y152583D02*
X930767Y152250D01*
X931350Y152000D01*
X931850D01*
X932350Y152167D01*
X932683Y152417D01*
X932850Y152750D01*
X932767Y153250D01*
X932433Y153500D01*
X930933Y154000D01*
X930600Y154583D01*
X930767Y155000D01*
X931100Y155250D01*
X931600Y155333D01*
X932100Y155250D01*
X932600Y155000D01*
G01X936783Y150333D02*
X935950Y151167D01*
X935533Y152000D01*
Y155333D01*
X935950Y156167D01*
X936783Y157000D01*
G01X941133Y152000D02*
Y157000D01*
X943133D01*
X943800Y156750D01*
X944300Y156167D01*
X944467Y155500D01*
X944300Y154833D01*
X943883Y154333D01*
X943133Y154083D01*
X941133D01*
G01X948400Y157000D02*
Y152000D01*
G01X946483Y157000D02*
X950317D01*
G01X952250Y152000D02*
Y157000D01*
G01X955750D02*
Y152000D01*
G01Y154500D02*
X952250D01*
G01X960017Y150333D02*
X960850Y151167D01*
X961267Y152000D01*
Y155333D01*
X960850Y156167D01*
X960017Y157000D01*
G01X900833Y214500D02*
Y209500D01*
X904167D01*
G01X906683D02*
Y212833D01*
G01Y212000D02*
X907017Y212417D01*
X907517Y212750D01*
X908183Y212833D01*
X908767Y212750D01*
X909267Y212417D01*
X909517Y211833D01*
Y209500D01*
G01X902833Y255500D02*
Y250500D01*
X906167D01*
G01X908850Y253833D02*
X911350Y250500D01*
G01Y253833D02*
X908850Y250500D01*
G01X889267Y349073D02*
X892933Y352740D01*
G01X891100Y353407D02*
Y348407D01*
G01X892933Y349073D02*
X889267Y352740D01*
G01X888600Y350907D02*
X893600D01*
G01X896283Y347573D02*
X895450Y348407D01*
X895033Y349240D01*
Y352573D01*
X895450Y353407D01*
X896283Y354240D01*
G01X900467Y349990D02*
X900967Y349573D01*
X901550Y349323D01*
X902300Y349240D01*
X903050Y349407D01*
X903633Y349740D01*
X904050Y350323D01*
X904133Y350990D01*
X903967Y351657D01*
X903550Y352073D01*
X902967Y352407D01*
X902383Y352490D01*
X901800Y352407D01*
X901050Y352073D01*
X901300Y354240D01*
X903550D01*
G01X907900Y349073D02*
X907733Y349157D01*
Y349323D01*
X907900Y349407D01*
X908067Y349323D01*
Y349157D01*
X907900Y349073D01*
G01X913500Y349240D02*
Y354240D01*
X912500Y353240D01*
G01Y349240D02*
X914500D01*
G01X919517Y347573D02*
X920350Y348407D01*
X920767Y349240D01*
Y352573D01*
X920350Y353407D01*
X919517Y354240D01*
G01X868167Y308167D02*
X868500Y308417D01*
X868750Y308833D01*
X868917Y309417D01*
X868750Y309917D01*
X868417Y310250D01*
X867833Y310500D01*
X865583D01*
Y305500D01*
X868333D01*
X868917Y305833D01*
X869250Y306333D01*
X869417Y306917D01*
X869250Y307500D01*
X868750Y308000D01*
X868167Y308167D01*
X865583D01*
G01X871017Y305500D02*
X873100Y310500D01*
X875183Y305500D01*
G01X874433Y307250D02*
X871767D01*
G01X880533Y310083D02*
X880033Y310333D01*
X879450Y310500D01*
X878783D01*
X878033Y310250D01*
X877450Y309833D01*
X877033Y309333D01*
X876700Y308500D01*
X876617Y307750D01*
X876783Y307000D01*
X877033Y306500D01*
X877533Y306000D01*
X878117Y305667D01*
X878700Y305500D01*
X879283D01*
X879867Y305667D01*
X880367Y305917D01*
X880783Y306250D01*
G01X882467Y305500D02*
Y310500D01*
G01X885633D02*
X882467Y307417D01*
G01X886133Y305500D02*
X883883Y308833D01*
G01X893667Y305500D02*
Y310500D01*
X895333D01*
X896000Y310250D01*
X896500Y309917D01*
X896917Y309417D01*
X897250Y308833D01*
X897333Y308000D01*
X897250Y307167D01*
X896917Y306583D01*
X896500Y306083D01*
X896000Y305750D01*
X895333Y305500D01*
X893667D01*
G01X899433D02*
Y310500D01*
X901517D01*
X902183Y310250D01*
X902600Y309917D01*
X902767Y309250D01*
X902600Y308583D01*
X902100Y308167D01*
X901517Y307917D01*
X899433D01*
G01X901517D02*
X902767Y305500D01*
G01X905700Y310500D02*
X907700D01*
G01X906700D02*
Y305500D01*
G01X905700D02*
X907700D01*
G01X910633Y310500D02*
Y305500D01*
X913967D01*
G01X916233Y310500D02*
Y305500D01*
X919567D01*
G01X943400D02*
Y308833D01*
G01Y307917D02*
X943650Y308333D01*
X944067Y308667D01*
X944650Y308833D01*
X945233Y308667D01*
X945650Y308333D01*
X945900Y307917D01*
Y305500D01*
G01Y307917D02*
X946150Y308333D01*
X946567Y308667D01*
X947150Y308833D01*
X947733Y308667D01*
X948150Y308333D01*
X948400Y307833D01*
Y305500D01*
G01X951500Y308833D02*
Y305500D01*
G01Y310167D02*
X951333Y310250D01*
Y310417D01*
X951500Y310500D01*
X951667Y310417D01*
Y310250D01*
X951500Y310167D01*
G01X957100Y305500D02*
Y310500D01*
G01X961450Y306083D02*
X961867Y305750D01*
X962450Y305500D01*
X962950D01*
X963450Y305667D01*
X963783Y305917D01*
X963950Y306250D01*
X963867Y306750D01*
X963533Y307000D01*
X962033Y307500D01*
X961700Y308083D01*
X961867Y308500D01*
X962200Y308750D01*
X962700Y308833D01*
X963200Y308750D01*
X963700Y308500D01*
G01X967883Y303833D02*
X967050Y304667D01*
X966633Y305500D01*
Y308833D01*
X967050Y309667D01*
X967883Y310500D01*
G01X971983Y305500D02*
Y310500D01*
X975817Y305500D01*
Y310500D01*
G01X977833Y305500D02*
Y310500D01*
X979833D01*
X980500Y310250D01*
X981000Y309667D01*
X981167Y309000D01*
X981000Y308333D01*
X980583Y307833D01*
X979833Y307583D01*
X977833D01*
G01X985100Y310500D02*
Y305500D01*
G01X983183Y310500D02*
X987017D01*
G01X988950Y305500D02*
Y310500D01*
G01X992450D02*
Y305500D01*
G01Y308000D02*
X988950D01*
G01X996717Y303833D02*
X997550Y304667D01*
X997967Y305500D01*
Y308833D01*
X997550Y309667D01*
X996717Y310500D01*
G01X894000Y556000D02*
Y551000D01*
G01X892833Y554333D02*
X895167D01*
G01X898183Y551000D02*
Y556000D01*
G01Y553583D02*
X898600Y554000D01*
X899017Y554250D01*
X899683Y554333D01*
X900183Y554250D01*
X900767Y553917D01*
X901017Y553417D01*
Y551000D01*
G01X903950Y553250D02*
X906617D01*
X906367Y553833D01*
X905950Y554167D01*
X905367Y554333D01*
X904783Y554250D01*
X904283Y554000D01*
X903950Y553417D01*
X903783Y552917D01*
Y552417D01*
X903950Y551917D01*
X904367Y551417D01*
X904867Y551083D01*
X905450Y551000D01*
X906033Y551167D01*
X906617Y551667D01*
G01X916400Y551000D02*
X915900Y551083D01*
X915400Y551417D01*
X915067Y552000D01*
X914900Y552667D01*
X915067Y553333D01*
X915400Y553917D01*
X915900Y554250D01*
X916400Y554333D01*
X916900Y554250D01*
X917400Y553917D01*
X917733Y553333D01*
X917817Y552667D01*
X917733Y552000D01*
X917400Y551417D01*
X916900Y551083D01*
X916400Y551000D01*
G01X922000Y556000D02*
Y551000D01*
G01X920833Y554333D02*
X923167D01*
G01X926183Y551000D02*
Y556000D01*
G01Y553583D02*
X926600Y554000D01*
X927017Y554250D01*
X927683Y554333D01*
X928183Y554250D01*
X928767Y553917D01*
X929017Y553417D01*
Y551000D01*
G01X931950Y553250D02*
X934617D01*
X934367Y553833D01*
X933950Y554167D01*
X933367Y554333D01*
X932783Y554250D01*
X932283Y554000D01*
X931950Y553417D01*
X931783Y552917D01*
Y552417D01*
X931950Y551917D01*
X932367Y551417D01*
X932867Y551083D01*
X933450Y551000D01*
X934033Y551167D01*
X934617Y551667D01*
G01X937633Y551000D02*
Y554333D01*
G01Y553667D02*
X938050Y554000D01*
X938467Y554250D01*
X939050Y554333D01*
X939467Y554250D01*
X939967Y554000D01*
G01X948750Y551583D02*
X949167Y551250D01*
X949750Y551000D01*
X950250D01*
X950750Y551167D01*
X951083Y551417D01*
X951250Y551750D01*
X951167Y552250D01*
X950833Y552500D01*
X949333Y553000D01*
X949000Y553583D01*
X949167Y554000D01*
X949500Y554250D01*
X950000Y554333D01*
X950500Y554250D01*
X951000Y554000D01*
G01X955600Y554333D02*
Y551000D01*
G01Y555667D02*
X955433Y555750D01*
Y555917D01*
X955600Y556000D01*
X955767Y555917D01*
Y555750D01*
X955600Y555667D01*
G01X962700Y556000D02*
Y551000D01*
G01Y551750D02*
X962367Y551333D01*
X961867Y551083D01*
X961283Y551000D01*
X960617Y551167D01*
X960117Y551583D01*
X959783Y552083D01*
X959700Y552667D01*
X959783Y553250D01*
X960117Y553750D01*
X960617Y554167D01*
X961283Y554333D01*
X961867Y554250D01*
X962283Y554083D01*
X962700Y553750D01*
G01X965550Y553250D02*
X968217D01*
X967967Y553833D01*
X967550Y554167D01*
X966967Y554333D01*
X966383Y554250D01*
X965883Y554000D01*
X965550Y553417D01*
X965383Y552917D01*
Y552417D01*
X965550Y551917D01*
X965967Y551417D01*
X966467Y551083D01*
X967050Y551000D01*
X967633Y551167D01*
X968217Y551667D01*
G01X975917Y554333D02*
X976917Y551000D01*
X978000Y554333D01*
X979083Y551000D01*
X980083Y554333D01*
G01X983600D02*
Y551000D01*
G01Y555667D02*
X983433Y555750D01*
Y555917D01*
X983600Y556000D01*
X983767Y555917D01*
Y555750D01*
X983600Y555667D01*
G01X989200Y556000D02*
Y551000D01*
G01X988033Y554333D02*
X990367D01*
G01X993383Y551000D02*
Y556000D01*
G01Y553583D02*
X993800Y554000D01*
X994217Y554250D01*
X994883Y554333D01*
X995383Y554250D01*
X995967Y553917D01*
X996217Y553417D01*
Y551000D01*
G01X1000400D02*
X999900Y551083D01*
X999400Y551417D01*
X999067Y552000D01*
X998900Y552667D01*
X999067Y553333D01*
X999400Y553917D01*
X999900Y554250D01*
X1000400Y554333D01*
X1000900Y554250D01*
X1001400Y553917D01*
X1001733Y553333D01*
X1001817Y552667D01*
X1001733Y552000D01*
X1001400Y551417D01*
X1000900Y551083D01*
X1000400Y551000D01*
G01X1004583Y554333D02*
Y552000D01*
X1004917Y551417D01*
X1005417Y551083D01*
X1006000Y551000D01*
X1006583Y551083D01*
X1007083Y551417D01*
X1007417Y552000D01*
G01Y551000D02*
Y554333D01*
G01X1011600Y556000D02*
Y551000D01*
G01X1010433Y554333D02*
X1012767D01*
G01X878000Y591500D02*
X879667D01*
Y590000D01*
X879167Y589500D01*
X878583Y589167D01*
X877750Y589000D01*
X876917Y589167D01*
X876333Y589500D01*
X875833Y590000D01*
X875500Y590583D01*
X875333Y591250D01*
Y591833D01*
X875500Y592333D01*
X875833Y592917D01*
X876333Y593417D01*
X876833Y593750D01*
X877500Y594000D01*
X878083D01*
X878750Y593833D01*
X879250Y593500D01*
G01X881850Y591250D02*
X884517D01*
X884267Y591833D01*
X883850Y592167D01*
X883267Y592333D01*
X882683Y592250D01*
X882183Y592000D01*
X881850Y591417D01*
X881683Y590917D01*
Y590417D01*
X881850Y589917D01*
X882267Y589417D01*
X882767Y589083D01*
X883350Y589000D01*
X883933Y589167D01*
X884517Y589667D01*
G01X887533Y589000D02*
Y592333D01*
G01Y591667D02*
X887950Y592000D01*
X888367Y592250D01*
X888950Y592333D01*
X889367Y592250D01*
X889867Y592000D01*
G01X892800Y589000D02*
Y594000D01*
G01Y591500D02*
X893217Y592000D01*
X893717Y592250D01*
X894217Y592333D01*
X894967Y592167D01*
X895467Y591833D01*
X895800Y591250D01*
Y590583D01*
X895633Y589917D01*
X895300Y589417D01*
X894717Y589083D01*
X894217Y589000D01*
X893717Y589083D01*
X893217Y589333D01*
X892800Y589750D01*
G01X898650Y591250D02*
X901317D01*
X901067Y591833D01*
X900650Y592167D01*
X900067Y592333D01*
X899483Y592250D01*
X898983Y592000D01*
X898650Y591417D01*
X898483Y590917D01*
Y590417D01*
X898650Y589917D01*
X899067Y589417D01*
X899567Y589083D01*
X900150Y589000D01*
X900733Y589167D01*
X901317Y589667D01*
G01X904333Y589000D02*
Y592333D01*
G01Y591667D02*
X904750Y592000D01*
X905167Y592250D01*
X905750Y592333D01*
X906167Y592250D01*
X906667Y592000D01*
G01X918200Y594000D02*
Y589000D01*
G01Y589750D02*
X917867Y589333D01*
X917367Y589083D01*
X916783Y589000D01*
X916117Y589167D01*
X915617Y589583D01*
X915283Y590083D01*
X915200Y590667D01*
X915283Y591250D01*
X915617Y591750D01*
X916117Y592167D01*
X916783Y592333D01*
X917367Y592250D01*
X917783Y592083D01*
X918200Y591750D01*
G01X921050Y591250D02*
X923717D01*
X923467Y591833D01*
X923050Y592167D01*
X922467Y592333D01*
X921883Y592250D01*
X921383Y592000D01*
X921050Y591417D01*
X920883Y590917D01*
Y590417D01*
X921050Y589917D01*
X921467Y589417D01*
X921967Y589083D01*
X922550Y589000D01*
X923133Y589167D01*
X923717Y589667D01*
G01X926650Y589583D02*
X927067Y589250D01*
X927650Y589000D01*
X928150D01*
X928650Y589167D01*
X928983Y589417D01*
X929150Y589750D01*
X929067Y590250D01*
X928733Y590500D01*
X927233Y591000D01*
X926900Y591583D01*
X927067Y592000D01*
X927400Y592250D01*
X927900Y592333D01*
X928400Y592250D01*
X928900Y592000D01*
G01X933500Y592333D02*
Y589000D01*
G01Y593667D02*
X933333Y593750D01*
Y593917D01*
X933500Y594000D01*
X933667Y593917D01*
Y593750D01*
X933500Y593667D01*
G01X937933Y587750D02*
X938517Y587417D01*
X939183Y587333D01*
X939767Y587417D01*
X940267Y587833D01*
X940600Y588417D01*
Y592333D01*
G01Y591667D02*
X940267Y592000D01*
X939767Y592250D01*
X939183Y592333D01*
X938517Y592167D01*
X938100Y591833D01*
X937767Y591250D01*
X937600Y590667D01*
X937683Y590167D01*
X938017Y589583D01*
X938517Y589167D01*
X939183Y589000D01*
X939683Y589083D01*
X940267Y589417D01*
X940600Y589750D01*
G01X943283Y589000D02*
Y592333D01*
G01Y591500D02*
X943617Y591917D01*
X944117Y592250D01*
X944783Y592333D01*
X945367Y592250D01*
X945867Y591917D01*
X946117Y591333D01*
Y589000D01*
G01X929000Y734500D02*
Y738750D01*
X929167Y739167D01*
X929500Y739417D01*
X930000Y739500D01*
X930500Y739333D01*
X930750Y738917D01*
G01X929750Y737500D02*
X928083D01*
G01X933683Y737833D02*
Y735500D01*
X934017Y734917D01*
X934517Y734583D01*
X935100Y734500D01*
X935683Y734583D01*
X936183Y734917D01*
X936517Y735500D01*
G01Y734500D02*
Y737833D01*
G01X940700Y734500D02*
Y739500D01*
G01X946300Y734500D02*
Y739500D01*
G01X956000Y732833D02*
Y737833D01*
G01Y737083D02*
X956417Y737500D01*
X956833Y737750D01*
X957500Y737833D01*
X958083Y737750D01*
X958667Y737333D01*
X958917Y736750D01*
X959000Y736167D01*
X958917Y735583D01*
X958667Y735000D01*
X958167Y734667D01*
X957500Y734500D01*
X956917Y734583D01*
X956333Y734833D01*
X956000Y735167D01*
G01X963100Y734500D02*
Y739500D01*
G01X967283Y737833D02*
Y735500D01*
X967617Y734917D01*
X968117Y734583D01*
X968700Y734500D01*
X969283Y734583D01*
X969783Y734917D01*
X970117Y735500D01*
G01Y734500D02*
Y737833D01*
G01X973133Y733250D02*
X973717Y732917D01*
X974383Y732833D01*
X974967Y732917D01*
X975467Y733333D01*
X975800Y733917D01*
Y737833D01*
G01Y737167D02*
X975467Y737500D01*
X974967Y737750D01*
X974383Y737833D01*
X973717Y737667D01*
X973300Y737333D01*
X972967Y736750D01*
X972800Y736167D01*
X972883Y735667D01*
X973217Y735083D01*
X973717Y734667D01*
X974383Y734500D01*
X974883Y734583D01*
X975467Y734917D01*
X975800Y735250D01*
G01X978733Y733250D02*
X979317Y732917D01*
X979983Y732833D01*
X980567Y732917D01*
X981067Y733333D01*
X981400Y733917D01*
Y737833D01*
G01Y737167D02*
X981067Y737500D01*
X980567Y737750D01*
X979983Y737833D01*
X979317Y737667D01*
X978900Y737333D01*
X978567Y736750D01*
X978400Y736167D01*
X978483Y735667D01*
X978817Y735083D01*
X979317Y734667D01*
X979983Y734500D01*
X980483Y734583D01*
X981067Y734917D01*
X981400Y735250D01*
G01X985500Y737833D02*
Y734500D01*
G01Y739167D02*
X985333Y739250D01*
Y739417D01*
X985500Y739500D01*
X985667Y739417D01*
Y739250D01*
X985500Y739167D01*
G01X989683Y734500D02*
Y737833D01*
G01Y737000D02*
X990017Y737417D01*
X990517Y737750D01*
X991183Y737833D01*
X991767Y737750D01*
X992267Y737417D01*
X992517Y736833D01*
Y734500D01*
G01X995533Y733250D02*
X996117Y732917D01*
X996783Y732833D01*
X997367Y732917D01*
X997867Y733333D01*
X998200Y733917D01*
Y737833D01*
G01Y737167D02*
X997867Y737500D01*
X997367Y737750D01*
X996783Y737833D01*
X996117Y737667D01*
X995700Y737333D01*
X995367Y736750D01*
X995200Y736167D01*
X995283Y735667D01*
X995617Y735083D01*
X996117Y734667D01*
X996783Y734500D01*
X997283Y734583D01*
X997867Y734917D01*
X998200Y735250D01*
G01X956000Y795980D02*
Y790980D01*
G01X954083Y795980D02*
X957917D01*
G01X959517Y794313D02*
X960517Y790980D01*
X961600Y794313D01*
X962683Y790980D01*
X963683Y794313D01*
G01X967200D02*
Y790980D01*
G01Y795647D02*
X967033Y795730D01*
Y795897D01*
X967200Y795980D01*
X967367Y795897D01*
Y795730D01*
X967200Y795647D01*
G01X971550Y791563D02*
X971967Y791230D01*
X972550Y790980D01*
X973050D01*
X973550Y791147D01*
X973883Y791397D01*
X974050Y791730D01*
X973967Y792230D01*
X973633Y792480D01*
X972133Y792980D01*
X971800Y793563D01*
X971967Y793980D01*
X972300Y794230D01*
X972800Y794313D01*
X973300Y794230D01*
X973800Y793980D01*
G01X978400Y795980D02*
Y790980D01*
G01X977233Y794313D02*
X979567D01*
G01X991100Y790980D02*
Y794313D01*
G01Y793730D02*
X990767Y794063D01*
X990267Y794230D01*
X989683Y794313D01*
X989100Y794147D01*
X988600Y793813D01*
X988267Y793313D01*
X988100Y792647D01*
X988267Y791980D01*
X988600Y791480D01*
X989100Y791147D01*
X989683Y790980D01*
X990267Y791063D01*
X990767Y791313D01*
X991100Y791647D01*
G01X993783Y790980D02*
Y794313D01*
G01Y793480D02*
X994117Y793897D01*
X994617Y794230D01*
X995283Y794313D01*
X995867Y794230D01*
X996367Y793897D01*
X996617Y793313D01*
Y790980D01*
G01X1002300Y795980D02*
Y790980D01*
G01Y791730D02*
X1001967Y791313D01*
X1001467Y791063D01*
X1000883Y790980D01*
X1000217Y791147D01*
X999717Y791563D01*
X999383Y792063D01*
X999300Y792647D01*
X999383Y793230D01*
X999717Y793730D01*
X1000217Y794147D01*
X1000883Y794313D01*
X1001467Y794230D01*
X1001883Y794063D01*
X1002300Y793730D01*
G01X1010500Y790980D02*
Y795980D01*
G01Y793480D02*
X1010917Y793980D01*
X1011417Y794230D01*
X1011917Y794313D01*
X1012667Y794147D01*
X1013167Y793813D01*
X1013500Y793230D01*
Y792563D01*
X1013333Y791897D01*
X1013000Y791397D01*
X1012417Y791063D01*
X1011917Y790980D01*
X1011417Y791063D01*
X1010917Y791313D01*
X1010500Y791730D01*
G01X1017600Y790980D02*
X1017100Y791063D01*
X1016600Y791397D01*
X1016267Y791980D01*
X1016100Y792647D01*
X1016267Y793313D01*
X1016600Y793897D01*
X1017100Y794230D01*
X1017600Y794313D01*
X1018100Y794230D01*
X1018600Y793897D01*
X1018933Y793313D01*
X1019017Y792647D01*
X1018933Y791980D01*
X1018600Y791397D01*
X1018100Y791063D01*
X1017600Y790980D01*
G01X1021117Y794313D02*
X1022117Y790980D01*
X1023200Y794313D01*
X1024283Y790980D01*
X1025283Y794313D01*
G01X957500Y811500D02*
X959167D01*
Y810000D01*
X958667Y809500D01*
X958083Y809167D01*
X957250Y809000D01*
X956417Y809167D01*
X955833Y809500D01*
X955333Y810000D01*
X955000Y810583D01*
X954833Y811250D01*
Y811833D01*
X955000Y812333D01*
X955333Y812917D01*
X955833Y813417D01*
X956333Y813750D01*
X957000Y814000D01*
X957583D01*
X958250Y813833D01*
X958750Y813500D01*
G01X961100Y808833D02*
X964100Y814000D01*
G01X966617Y809000D02*
Y814000D01*
X969783D01*
G01X968617Y811583D02*
X966617D01*
G01X977650Y809667D02*
X978317Y809250D01*
X979067Y809000D01*
X979733D01*
X980400Y809250D01*
X980900Y809667D01*
X981150Y810250D01*
X980983Y810833D01*
X980567Y811333D01*
X979817Y811667D01*
X978817Y811833D01*
X978233Y812167D01*
X977983Y812750D01*
X978150Y813333D01*
X978567Y813750D01*
X979150Y814000D01*
X979733D01*
X980317Y813833D01*
X980817Y813417D01*
G01X985000Y809000D02*
Y814000D01*
G01X990600Y809000D02*
X990100Y809083D01*
X989600Y809417D01*
X989267Y810000D01*
X989100Y810667D01*
X989267Y811333D01*
X989600Y811917D01*
X990100Y812250D01*
X990600Y812333D01*
X991100Y812250D01*
X991600Y811917D01*
X991933Y811333D01*
X992017Y810667D01*
X991933Y810000D01*
X991600Y809417D01*
X991100Y809083D01*
X990600Y809000D01*
G01X996200Y814000D02*
Y809000D01*
G01X995033Y812333D02*
X997367D01*
G01X955750Y826250D02*
X958417D01*
X958167Y826833D01*
X957750Y827167D01*
X957167Y827333D01*
X956583Y827250D01*
X956083Y827000D01*
X955750Y826417D01*
X955583Y825917D01*
Y825417D01*
X955750Y824917D01*
X956167Y824417D01*
X956667Y824083D01*
X957250Y824000D01*
X957833Y824167D01*
X958417Y824667D01*
G01X964100Y829000D02*
Y824000D01*
G01Y824750D02*
X963767Y824333D01*
X963267Y824083D01*
X962683Y824000D01*
X962017Y824167D01*
X961517Y824583D01*
X961183Y825083D01*
X961100Y825667D01*
X961183Y826250D01*
X961517Y826750D01*
X962017Y827167D01*
X962683Y827333D01*
X963267Y827250D01*
X963683Y827083D01*
X964100Y826750D01*
G01X967033Y822750D02*
X967617Y822417D01*
X968283Y822333D01*
X968867Y822417D01*
X969367Y822833D01*
X969700Y823417D01*
Y827333D01*
G01Y826667D02*
X969367Y827000D01*
X968867Y827250D01*
X968283Y827333D01*
X967617Y827167D01*
X967200Y826833D01*
X966867Y826250D01*
X966700Y825667D01*
X966783Y825167D01*
X967117Y824583D01*
X967617Y824167D01*
X968283Y824000D01*
X968783Y824083D01*
X969367Y824417D01*
X969700Y824750D01*
G01X972550Y826250D02*
X975217D01*
X974967Y826833D01*
X974550Y827167D01*
X973967Y827333D01*
X973383Y827250D01*
X972883Y827000D01*
X972550Y826417D01*
X972383Y825917D01*
Y825417D01*
X972550Y824917D01*
X972967Y824417D01*
X973467Y824083D01*
X974050Y824000D01*
X974633Y824167D01*
X975217Y824667D01*
G01X985000Y829000D02*
Y824000D01*
G01X983833Y827333D02*
X986167D01*
G01X990600Y824000D02*
X990100Y824083D01*
X989600Y824417D01*
X989267Y825000D01*
X989100Y825667D01*
X989267Y826333D01*
X989600Y826917D01*
X990100Y827250D01*
X990600Y827333D01*
X991100Y827250D01*
X991600Y826917D01*
X991933Y826333D01*
X992017Y825667D01*
X991933Y825000D01*
X991600Y824417D01*
X991100Y824083D01*
X990600Y824000D01*
G01X1000383D02*
Y829000D01*
G01Y826583D02*
X1000800Y827000D01*
X1001217Y827250D01*
X1001883Y827333D01*
X1002383Y827250D01*
X1002967Y826917D01*
X1003217Y826417D01*
Y824000D01*
G01X1007400D02*
X1006900Y824083D01*
X1006400Y824417D01*
X1006067Y825000D01*
X1005900Y825667D01*
X1006067Y826333D01*
X1006400Y826917D01*
X1006900Y827250D01*
X1007400Y827333D01*
X1007900Y827250D01*
X1008400Y826917D01*
X1008733Y826333D01*
X1008817Y825667D01*
X1008733Y825000D01*
X1008400Y824417D01*
X1007900Y824083D01*
X1007400Y824000D01*
G01X1013000D02*
Y829000D01*
G01X1017350Y826250D02*
X1020017D01*
X1019767Y826833D01*
X1019350Y827167D01*
X1018767Y827333D01*
X1018183Y827250D01*
X1017683Y827000D01*
X1017350Y826417D01*
X1017183Y825917D01*
Y825417D01*
X1017350Y824917D01*
X1017767Y824417D01*
X1018267Y824083D01*
X1018850Y824000D01*
X1019433Y824167D01*
X1020017Y824667D01*
G01X955750Y842750D02*
X958417D01*
X958167Y843333D01*
X957750Y843667D01*
X957167Y843833D01*
X956583Y843750D01*
X956083Y843500D01*
X955750Y842917D01*
X955583Y842417D01*
Y841917D01*
X955750Y841417D01*
X956167Y840917D01*
X956667Y840583D01*
X957250Y840500D01*
X957833Y840667D01*
X958417Y841167D01*
G01X964100Y845500D02*
Y840500D01*
G01Y841250D02*
X963767Y840833D01*
X963267Y840583D01*
X962683Y840500D01*
X962017Y840667D01*
X961517Y841083D01*
X961183Y841583D01*
X961100Y842167D01*
X961183Y842750D01*
X961517Y843250D01*
X962017Y843667D01*
X962683Y843833D01*
X963267Y843750D01*
X963683Y843583D01*
X964100Y843250D01*
G01X967033Y839250D02*
X967617Y838917D01*
X968283Y838833D01*
X968867Y838917D01*
X969367Y839333D01*
X969700Y839917D01*
Y843833D01*
G01Y843167D02*
X969367Y843500D01*
X968867Y843750D01*
X968283Y843833D01*
X967617Y843667D01*
X967200Y843333D01*
X966867Y842750D01*
X966700Y842167D01*
X966783Y841667D01*
X967117Y841083D01*
X967617Y840667D01*
X968283Y840500D01*
X968783Y840583D01*
X969367Y840917D01*
X969700Y841250D01*
G01X972550Y842750D02*
X975217D01*
X974967Y843333D01*
X974550Y843667D01*
X973967Y843833D01*
X973383Y843750D01*
X972883Y843500D01*
X972550Y842917D01*
X972383Y842417D01*
Y841917D01*
X972550Y841417D01*
X972967Y840917D01*
X973467Y840583D01*
X974050Y840500D01*
X974633Y840667D01*
X975217Y841167D01*
G01X985000Y845500D02*
Y840500D01*
G01X983833Y843833D02*
X986167D01*
G01X990600Y840500D02*
X990100Y840583D01*
X989600Y840917D01*
X989267Y841500D01*
X989100Y842167D01*
X989267Y842833D01*
X989600Y843417D01*
X990100Y843750D01*
X990600Y843833D01*
X991100Y843750D01*
X991600Y843417D01*
X991933Y842833D01*
X992017Y842167D01*
X991933Y841500D01*
X991600Y840917D01*
X991100Y840583D01*
X990600Y840500D01*
G01X1000550Y842750D02*
X1003217D01*
X1002967Y843333D01*
X1002550Y843667D01*
X1001967Y843833D01*
X1001383Y843750D01*
X1000883Y843500D01*
X1000550Y842917D01*
X1000383Y842417D01*
Y841917D01*
X1000550Y841417D01*
X1000967Y840917D01*
X1001467Y840583D01*
X1002050Y840500D01*
X1002633Y840667D01*
X1003217Y841167D01*
G01X1008900Y845500D02*
Y840500D01*
G01Y841250D02*
X1008567Y840833D01*
X1008067Y840583D01*
X1007483Y840500D01*
X1006817Y840667D01*
X1006317Y841083D01*
X1005983Y841583D01*
X1005900Y842167D01*
X1005983Y842750D01*
X1006317Y843250D01*
X1006817Y843667D01*
X1007483Y843833D01*
X1008067Y843750D01*
X1008483Y843583D01*
X1008900Y843250D01*
G01X1011833Y839250D02*
X1012417Y838917D01*
X1013083Y838833D01*
X1013667Y838917D01*
X1014167Y839333D01*
X1014500Y839917D01*
Y843833D01*
G01Y843167D02*
X1014167Y843500D01*
X1013667Y843750D01*
X1013083Y843833D01*
X1012417Y843667D01*
X1012000Y843333D01*
X1011667Y842750D01*
X1011500Y842167D01*
X1011583Y841667D01*
X1011917Y841083D01*
X1012417Y840667D01*
X1013083Y840500D01*
X1013583Y840583D01*
X1014167Y840917D01*
X1014500Y841250D01*
G01X1017350Y842750D02*
X1020017D01*
X1019767Y843333D01*
X1019350Y843667D01*
X1018767Y843833D01*
X1018183Y843750D01*
X1017683Y843500D01*
X1017350Y842917D01*
X1017183Y842417D01*
Y841917D01*
X1017350Y841417D01*
X1017767Y840917D01*
X1018267Y840583D01*
X1018850Y840500D01*
X1019433Y840667D01*
X1020017Y841167D01*
G01X948000Y850610D02*
Y782110D01*
G01X948500Y819500D02*
X1343000D01*
G01X948500Y834500D02*
X1343000D01*
G01X995667Y5500D02*
Y10500D01*
X997333D01*
X998000Y10250D01*
X998500Y9917D01*
X998917Y9417D01*
X999250Y8833D01*
X999333Y8000D01*
X999250Y7167D01*
X998917Y6583D01*
X998500Y6083D01*
X998000Y5750D01*
X997333Y5500D01*
X995667D01*
G01X1003100D02*
Y10500D01*
X1002100Y9500D01*
G01Y5500D02*
X1004100D01*
G01X1007117Y7583D02*
X1007700Y8167D01*
X1008200Y8500D01*
X1008867Y8667D01*
X1009450Y8500D01*
X1009867Y8167D01*
X1010200Y7667D01*
X1010283Y7083D01*
X1010200Y6583D01*
X1009867Y6083D01*
X1009367Y5667D01*
X1008783Y5500D01*
X1008117Y5667D01*
X1007533Y6167D01*
X1007200Y6917D01*
X1007117Y7750D01*
X1007283Y8833D01*
X1007533Y9417D01*
X1007950Y10000D01*
X1008533Y10417D01*
X1009117Y10500D01*
X1009700Y10333D01*
X1010117Y9917D01*
G01X1014300Y5333D02*
X1014133Y5417D01*
Y5583D01*
X1014300Y5667D01*
X1014467Y5583D01*
Y5417D01*
X1014300Y5333D01*
G01Y7583D02*
X1014133Y7667D01*
Y7833D01*
X1014300Y7917D01*
X1014467Y7833D01*
Y7667D01*
X1014300Y7583D01*
G01X1018067Y5500D02*
Y10500D01*
X1019733D01*
X1020400Y10250D01*
X1020900Y9917D01*
X1021317Y9417D01*
X1021650Y8833D01*
X1021733Y8000D01*
X1021650Y7167D01*
X1021317Y6583D01*
X1020900Y6083D01*
X1020400Y5750D01*
X1019733Y5500D01*
X1018067D01*
G01X1025500Y8833D02*
Y5500D01*
G01Y10167D02*
X1025333Y10250D01*
Y10417D01*
X1025500Y10500D01*
X1025667Y10417D01*
Y10250D01*
X1025500Y10167D01*
G01X1032600Y5500D02*
Y8833D01*
G01Y8250D02*
X1032267Y8583D01*
X1031767Y8750D01*
X1031183Y8833D01*
X1030600Y8667D01*
X1030100Y8333D01*
X1029767Y7833D01*
X1029600Y7167D01*
X1029767Y6500D01*
X1030100Y6000D01*
X1030600Y5667D01*
X1031183Y5500D01*
X1031767Y5583D01*
X1032267Y5833D01*
X1032600Y6167D01*
G01X1034200Y5500D02*
Y8833D01*
G01Y7917D02*
X1034450Y8333D01*
X1034867Y8667D01*
X1035450Y8833D01*
X1036033Y8667D01*
X1036450Y8333D01*
X1036700Y7917D01*
Y5500D01*
G01Y7917D02*
X1036950Y8333D01*
X1037367Y8667D01*
X1037950Y8833D01*
X1038533Y8667D01*
X1038950Y8333D01*
X1039200Y7833D01*
Y5500D01*
G01X1041050Y7750D02*
X1043717D01*
X1043467Y8333D01*
X1043050Y8667D01*
X1042467Y8833D01*
X1041883Y8750D01*
X1041383Y8500D01*
X1041050Y7917D01*
X1040883Y7417D01*
Y6917D01*
X1041050Y6417D01*
X1041467Y5917D01*
X1041967Y5583D01*
X1042550Y5500D01*
X1043133Y5667D01*
X1043717Y6167D01*
G01X1047900Y10500D02*
Y5500D01*
G01X1046733Y8833D02*
X1049067D01*
G01X1052250Y7750D02*
X1054917D01*
X1054667Y8333D01*
X1054250Y8667D01*
X1053667Y8833D01*
X1053083Y8750D01*
X1052583Y8500D01*
X1052250Y7917D01*
X1052083Y7417D01*
Y6917D01*
X1052250Y6417D01*
X1052667Y5917D01*
X1053167Y5583D01*
X1053750Y5500D01*
X1054333Y5667D01*
X1054917Y6167D01*
G01X1057933Y5500D02*
Y8833D01*
G01Y8167D02*
X1058350Y8500D01*
X1058767Y8750D01*
X1059350Y8833D01*
X1059767Y8750D01*
X1060267Y8500D01*
G01X1070300Y5500D02*
Y10500D01*
X1069300Y9500D01*
G01Y5500D02*
X1071300D01*
G01X1074317Y7583D02*
X1074900Y8167D01*
X1075400Y8500D01*
X1076067Y8667D01*
X1076650Y8500D01*
X1077067Y8167D01*
X1077400Y7667D01*
X1077483Y7083D01*
X1077400Y6583D01*
X1077067Y6083D01*
X1076567Y5667D01*
X1075983Y5500D01*
X1075317Y5667D01*
X1074733Y6167D01*
X1074400Y6917D01*
X1074317Y7750D01*
X1074483Y8833D01*
X1074733Y9417D01*
X1075150Y10000D01*
X1075733Y10417D01*
X1076317Y10500D01*
X1076900Y10333D01*
X1077317Y9917D01*
G01X1079000Y5500D02*
Y8833D01*
G01Y7917D02*
X1079250Y8333D01*
X1079667Y8667D01*
X1080250Y8833D01*
X1080833Y8667D01*
X1081250Y8333D01*
X1081500Y7917D01*
Y5500D01*
G01Y7917D02*
X1081750Y8333D01*
X1082167Y8667D01*
X1082750Y8833D01*
X1083333Y8667D01*
X1083750Y8333D01*
X1084000Y7833D01*
Y5500D01*
G01X1087100Y8833D02*
Y5500D01*
G01Y10167D02*
X1086933Y10250D01*
Y10417D01*
X1087100Y10500D01*
X1087267Y10417D01*
Y10250D01*
X1087100Y10167D01*
G01X1092700Y5500D02*
Y10500D01*
G01X980667Y16500D02*
X977333D01*
Y21500D01*
X980667D01*
G01X979333Y19083D02*
X977333D01*
G01X983350Y19833D02*
X985850Y16500D01*
G01Y19833D02*
X983350Y16500D01*
G01X990200Y16333D02*
X990033Y16417D01*
Y16583D01*
X990200Y16667D01*
X990367Y16583D01*
Y16417D01*
X990200Y16333D01*
G01X994050Y16500D02*
Y21500D01*
G01X997550D02*
Y16500D01*
G01Y19000D02*
X994050D01*
G01X999733Y16500D02*
Y21500D01*
X1001817D01*
X1002483Y21250D01*
X1002900Y20917D01*
X1003067Y20250D01*
X1002900Y19583D01*
X1002400Y19167D01*
X1001817Y18917D01*
X999733D01*
G01X1001817D02*
X1003067Y16500D01*
G01X1008667D02*
X1005333D01*
Y21500D01*
X1008667D01*
G01X1007333Y19083D02*
X1005333D01*
G01X1013600Y16500D02*
Y21500D01*
X1010517Y17917D01*
X1014683D01*
G01X1016367Y17250D02*
X1016867Y16833D01*
X1017450Y16583D01*
X1018200Y16500D01*
X1018950Y16667D01*
X1019533Y17000D01*
X1019950Y17583D01*
X1020033Y18250D01*
X1019867Y18917D01*
X1019450Y19333D01*
X1018867Y19667D01*
X1018283Y19750D01*
X1017700Y19667D01*
X1016950Y19333D01*
X1017200Y21500D01*
X1019450D01*
G01X1022050Y16500D02*
X1025550Y21500D01*
G01X1022050D02*
X1025550Y16500D01*
G01X1027983Y17083D02*
X1028567Y16667D01*
X1029233Y16500D01*
X1029900Y16667D01*
X1030483Y17167D01*
X1030900Y17917D01*
X1031067Y18667D01*
Y19583D01*
X1030900Y20333D01*
X1030483Y21000D01*
X1029983Y21333D01*
X1029400Y21500D01*
X1028733Y21333D01*
X1028233Y21000D01*
X1027900Y20500D01*
X1027733Y19833D01*
X1027900Y19250D01*
X1028317Y18667D01*
X1028817Y18333D01*
X1029400Y18250D01*
X1030067Y18417D01*
X1030567Y18833D01*
X1031067Y19583D01*
G01X1033417Y18583D02*
X1034000Y19167D01*
X1034500Y19500D01*
X1035167Y19667D01*
X1035750Y19500D01*
X1036167Y19167D01*
X1036500Y18667D01*
X1036583Y18083D01*
X1036500Y17583D01*
X1036167Y17083D01*
X1035667Y16667D01*
X1035083Y16500D01*
X1034417Y16667D01*
X1033833Y17167D01*
X1033500Y17917D01*
X1033417Y18750D01*
X1033583Y19833D01*
X1033833Y20417D01*
X1034250Y21000D01*
X1034833Y21417D01*
X1035417Y21500D01*
X1036000Y21333D01*
X1036417Y20917D01*
G01X1040183Y14833D02*
X1039350Y15667D01*
X1038933Y16500D01*
Y19833D01*
X1039350Y20667D01*
X1040183Y21500D01*
G01X1044367Y16500D02*
Y21500D01*
X1046033D01*
X1046700Y21250D01*
X1047200Y20917D01*
X1047617Y20417D01*
X1047950Y19833D01*
X1048033Y19000D01*
X1047950Y18167D01*
X1047617Y17583D01*
X1047200Y17083D01*
X1046700Y16750D01*
X1046033Y16500D01*
X1044367D01*
G01X1051800D02*
Y21500D01*
X1050800Y20500D01*
G01Y16500D02*
X1052800D01*
G01X1055817Y18583D02*
X1056400Y19167D01*
X1056900Y19500D01*
X1057567Y19667D01*
X1058150Y19500D01*
X1058567Y19167D01*
X1058900Y18667D01*
X1058983Y18083D01*
X1058900Y17583D01*
X1058567Y17083D01*
X1058067Y16667D01*
X1057483Y16500D01*
X1056817Y16667D01*
X1056233Y17167D01*
X1055900Y17917D01*
X1055817Y18750D01*
X1055983Y19833D01*
X1056233Y20417D01*
X1056650Y21000D01*
X1057233Y21417D01*
X1057817Y21500D01*
X1058400Y21333D01*
X1058817Y20917D01*
G01X1061250Y16500D02*
X1064750Y21500D01*
G01X1061250D02*
X1064750Y16500D01*
G01X1069600D02*
Y21500D01*
X1066517Y17917D01*
X1070683D01*
G01X1074617Y14833D02*
X1075450Y15667D01*
X1075867Y16500D01*
Y19833D01*
X1075450Y20667D01*
X1074617Y21500D01*
G01X977333Y65500D02*
Y70500D01*
X979417D01*
X980083Y70250D01*
X980500Y69917D01*
X980667Y69250D01*
X980500Y68583D01*
X980000Y68167D01*
X979417Y67917D01*
X977333D01*
G01X979417D02*
X980667Y65500D01*
G01X986267D02*
X982933D01*
Y70500D01*
X986267D01*
G01X984933Y68083D02*
X982933D01*
G01X992033Y70083D02*
X991533Y70333D01*
X990950Y70500D01*
X990283D01*
X989533Y70250D01*
X988950Y69833D01*
X988533Y69333D01*
X988200Y68500D01*
X988117Y67750D01*
X988283Y67000D01*
X988533Y66500D01*
X989033Y66000D01*
X989617Y65667D01*
X990200Y65500D01*
X990783D01*
X991367Y65667D01*
X991867Y65917D01*
X992283Y66250D01*
G01X995800Y70500D02*
Y65500D01*
G01X993883Y70500D02*
X997717D01*
G01X999317Y65500D02*
X1001400Y70500D01*
X1003483Y65500D01*
G01X1002733Y67250D02*
X1000067D01*
G01X1005083Y65500D02*
Y70500D01*
X1008917Y65500D01*
Y70500D01*
G01X1013100Y68000D02*
X1014767D01*
Y66500D01*
X1014267Y66000D01*
X1013683Y65667D01*
X1012850Y65500D01*
X1012017Y65667D01*
X1011433Y66000D01*
X1010933Y66500D01*
X1010600Y67083D01*
X1010433Y67750D01*
Y68333D01*
X1010600Y68833D01*
X1010933Y69417D01*
X1011433Y69917D01*
X1011933Y70250D01*
X1012600Y70500D01*
X1013183D01*
X1013850Y70333D01*
X1014350Y70000D01*
G01X1016533Y70500D02*
Y65500D01*
X1019867D01*
G01X1025467D02*
X1022133D01*
Y70500D01*
X1025467D01*
G01X1024133Y68083D02*
X1022133D01*
G01X1033167Y65500D02*
Y70500D01*
X1034833D01*
X1035500Y70250D01*
X1036000Y69917D01*
X1036417Y69417D01*
X1036750Y68833D01*
X1036833Y68000D01*
X1036750Y67167D01*
X1036417Y66583D01*
X1036000Y66083D01*
X1035500Y65750D01*
X1034833Y65500D01*
X1033167D01*
G01X1038933D02*
Y70500D01*
X1041017D01*
X1041683Y70250D01*
X1042100Y69917D01*
X1042267Y69250D01*
X1042100Y68583D01*
X1041600Y68167D01*
X1041017Y67917D01*
X1038933D01*
G01X1041017D02*
X1042267Y65500D01*
G01X1045200Y70500D02*
X1047200D01*
G01X1046200D02*
Y65500D01*
G01X1045200D02*
X1047200D01*
G01X1050133Y70500D02*
Y65500D01*
X1053467D01*
G01X1055733Y70500D02*
Y65500D01*
X1059067D01*
G01X1066850D02*
Y70500D01*
G01X1070350D02*
Y65500D01*
G01Y68000D02*
X1066850D01*
G01X1074200Y65500D02*
X1073533Y65583D01*
X1072950Y65917D01*
X1072450Y66417D01*
X1072117Y67000D01*
X1071950Y67667D01*
Y68333D01*
X1072117Y69000D01*
X1072450Y69583D01*
X1072950Y70083D01*
X1073533Y70417D01*
X1074200Y70500D01*
X1074867Y70417D01*
X1075450Y70083D01*
X1075950Y69583D01*
X1076283Y69000D01*
X1076450Y68333D01*
Y67667D01*
X1076283Y67000D01*
X1075950Y66417D01*
X1075450Y65917D01*
X1074867Y65583D01*
X1074200Y65500D01*
G01X1078133Y70500D02*
Y65500D01*
X1081467D01*
G01X1087067D02*
X1083733D01*
Y70500D01*
X1087067D01*
G01X1085733Y68083D02*
X1083733D01*
G01X1094767Y65500D02*
Y70500D01*
X1096433D01*
X1097100Y70250D01*
X1097600Y69917D01*
X1098017Y69417D01*
X1098350Y68833D01*
X1098433Y68000D01*
X1098350Y67167D01*
X1098017Y66583D01*
X1097600Y66083D01*
X1097100Y65750D01*
X1096433Y65500D01*
X1094767D01*
G01X1103867D02*
X1100533D01*
Y70500D01*
X1103867D01*
G01X1102533Y68083D02*
X1100533D01*
G01X1106217Y65500D02*
Y70500D01*
X1109383D01*
G01X1108217Y68083D02*
X1106217D01*
G01X1112400Y70500D02*
X1114400D01*
G01X1113400D02*
Y65500D01*
G01X1112400D02*
X1114400D01*
G01X1117083D02*
Y70500D01*
X1120917Y65500D01*
Y70500D01*
G01X1126267Y65500D02*
X1122933D01*
Y70500D01*
X1126267D01*
G01X1124933Y68083D02*
X1122933D01*
G01X1026000Y336000D02*
Y86000D01*
G01X1033500Y370500D02*
Y375500D01*
G01Y373000D02*
X1033917Y373500D01*
X1034417Y373750D01*
X1034917Y373833D01*
X1035667Y373667D01*
X1036167Y373333D01*
X1036500Y372750D01*
Y372083D01*
X1036333Y371417D01*
X1036000Y370917D01*
X1035417Y370583D01*
X1034917Y370500D01*
X1034417Y370583D01*
X1033917Y370833D01*
X1033500Y371250D01*
G01X1039183Y373833D02*
Y371500D01*
X1039517Y370917D01*
X1040017Y370583D01*
X1040600Y370500D01*
X1041183Y370583D01*
X1041683Y370917D01*
X1042017Y371500D01*
G01Y370500D02*
Y373833D01*
G01X1044700Y370500D02*
Y375500D01*
G01Y373000D02*
X1045117Y373500D01*
X1045617Y373750D01*
X1046117Y373833D01*
X1046867Y373667D01*
X1047367Y373333D01*
X1047700Y372750D01*
Y372083D01*
X1047533Y371417D01*
X1047200Y370917D01*
X1046617Y370583D01*
X1046117Y370500D01*
X1045617Y370583D01*
X1045117Y370833D01*
X1044700Y371250D01*
G01X1050300Y370500D02*
Y375500D01*
G01Y373000D02*
X1050717Y373500D01*
X1051217Y373750D01*
X1051717Y373833D01*
X1052467Y373667D01*
X1052967Y373333D01*
X1053300Y372750D01*
Y372083D01*
X1053133Y371417D01*
X1052800Y370917D01*
X1052217Y370583D01*
X1051717Y370500D01*
X1051217Y370583D01*
X1050717Y370833D01*
X1050300Y371250D01*
G01X1057400Y370500D02*
Y375500D01*
G01X1061750Y372750D02*
X1064417D01*
X1064167Y373333D01*
X1063750Y373667D01*
X1063167Y373833D01*
X1062583Y373750D01*
X1062083Y373500D01*
X1061750Y372917D01*
X1061583Y372417D01*
Y371917D01*
X1061750Y371417D01*
X1062167Y370917D01*
X1062667Y370583D01*
X1063250Y370500D01*
X1063833Y370667D01*
X1064417Y371167D01*
G01X1074200Y373833D02*
Y370500D01*
G01Y375167D02*
X1074033Y375250D01*
Y375417D01*
X1074200Y375500D01*
X1074367Y375417D01*
Y375250D01*
X1074200Y375167D01*
G01X1078383Y370500D02*
Y373833D01*
G01Y373000D02*
X1078717Y373417D01*
X1079217Y373750D01*
X1079883Y373833D01*
X1080467Y373750D01*
X1080967Y373417D01*
X1081217Y372833D01*
Y370500D01*
G01X1084150Y371083D02*
X1084567Y370750D01*
X1085150Y370500D01*
X1085650D01*
X1086150Y370667D01*
X1086483Y370917D01*
X1086650Y371250D01*
X1086567Y371750D01*
X1086233Y372000D01*
X1084733Y372500D01*
X1084400Y373083D01*
X1084567Y373500D01*
X1084900Y373750D01*
X1085400Y373833D01*
X1085900Y373750D01*
X1086400Y373500D01*
G01X1091000Y373833D02*
Y370500D01*
G01Y375167D02*
X1090833Y375250D01*
Y375417D01*
X1091000Y375500D01*
X1091167Y375417D01*
Y375250D01*
X1091000Y375167D01*
G01X1098100Y375500D02*
Y370500D01*
G01Y371250D02*
X1097767Y370833D01*
X1097267Y370583D01*
X1096683Y370500D01*
X1096017Y370667D01*
X1095517Y371083D01*
X1095183Y371583D01*
X1095100Y372167D01*
X1095183Y372750D01*
X1095517Y373250D01*
X1096017Y373667D01*
X1096683Y373833D01*
X1097267Y373750D01*
X1097683Y373583D01*
X1098100Y373250D01*
G01X1100950Y372750D02*
X1103617D01*
X1103367Y373333D01*
X1102950Y373667D01*
X1102367Y373833D01*
X1101783Y373750D01*
X1101283Y373500D01*
X1100950Y372917D01*
X1100783Y372417D01*
Y371917D01*
X1100950Y371417D01*
X1101367Y370917D01*
X1101867Y370583D01*
X1102450Y370500D01*
X1103033Y370667D01*
X1103617Y371167D01*
G01X1113400Y375500D02*
Y370500D01*
G01X1112233Y373833D02*
X1114567D01*
G01X1117583Y370500D02*
Y375500D01*
G01Y373083D02*
X1118000Y373500D01*
X1118417Y373750D01*
X1119083Y373833D01*
X1119583Y373750D01*
X1120167Y373417D01*
X1120417Y372917D01*
Y370500D01*
G01X1123350Y372750D02*
X1126017D01*
X1125767Y373333D01*
X1125350Y373667D01*
X1124767Y373833D01*
X1124183Y373750D01*
X1123683Y373500D01*
X1123350Y372917D01*
X1123183Y372417D01*
Y371917D01*
X1123350Y371417D01*
X1123767Y370917D01*
X1124267Y370583D01*
X1124850Y370500D01*
X1125433Y370667D01*
X1126017Y371167D01*
G01X1134633Y370500D02*
Y373833D01*
G01Y373167D02*
X1135050Y373500D01*
X1135467Y373750D01*
X1136050Y373833D01*
X1136467Y373750D01*
X1136967Y373500D01*
G01X1140150Y372750D02*
X1142817D01*
X1142567Y373333D01*
X1142150Y373667D01*
X1141567Y373833D01*
X1140983Y373750D01*
X1140483Y373500D01*
X1140150Y372917D01*
X1139983Y372417D01*
Y371917D01*
X1140150Y371417D01*
X1140567Y370917D01*
X1141067Y370583D01*
X1141650Y370500D01*
X1142233Y370667D01*
X1142817Y371167D01*
G01X1145750Y371083D02*
X1146167Y370750D01*
X1146750Y370500D01*
X1147250D01*
X1147750Y370667D01*
X1148083Y370917D01*
X1148250Y371250D01*
X1148167Y371750D01*
X1147833Y372000D01*
X1146333Y372500D01*
X1146000Y373083D01*
X1146167Y373500D01*
X1146500Y373750D01*
X1147000Y373833D01*
X1147500Y373750D01*
X1148000Y373500D01*
G01X1152600Y373833D02*
Y370500D01*
G01Y375167D02*
X1152433Y375250D01*
Y375417D01*
X1152600Y375500D01*
X1152767Y375417D01*
Y375250D01*
X1152600Y375167D01*
G01X1156783Y370500D02*
Y373833D01*
G01Y373000D02*
X1157117Y373417D01*
X1157617Y373750D01*
X1158283Y373833D01*
X1158867Y373750D01*
X1159367Y373417D01*
X1159617Y372833D01*
Y370500D01*
G01X1163800Y370333D02*
X1163633Y370417D01*
Y370583D01*
X1163800Y370667D01*
X1163967Y370583D01*
Y370417D01*
X1163800Y370333D01*
G01X1021417Y383667D02*
X1021917Y384167D01*
X1022500Y384417D01*
X1023167Y384500D01*
X1024000Y384333D01*
X1024583Y383917D01*
X1024750Y383417D01*
X1024667Y382917D01*
X1024333Y382500D01*
X1022667Y381667D01*
X1021917Y381083D01*
X1021417Y380250D01*
X1021250Y379500D01*
X1024750D01*
G01X1028600Y379333D02*
X1028433Y379417D01*
Y379583D01*
X1028600Y379667D01*
X1028767Y379583D01*
Y379417D01*
X1028600Y379333D01*
G01X1032117Y384500D02*
X1034200Y379500D01*
X1036283Y384500D01*
G01X1039800Y382833D02*
Y379500D01*
G01Y384167D02*
X1039633Y384250D01*
Y384417D01*
X1039800Y384500D01*
X1039967Y384417D01*
Y384250D01*
X1039800Y384167D01*
G01X1046900Y379500D02*
Y382833D01*
G01Y382250D02*
X1046567Y382583D01*
X1046067Y382750D01*
X1045483Y382833D01*
X1044900Y382667D01*
X1044400Y382333D01*
X1044067Y381833D01*
X1043900Y381167D01*
X1044067Y380500D01*
X1044400Y380000D01*
X1044900Y379667D01*
X1045483Y379500D01*
X1046067Y379583D01*
X1046567Y379833D01*
X1046900Y380167D01*
G01X1055350Y380083D02*
X1055767Y379750D01*
X1056350Y379500D01*
X1056850D01*
X1057350Y379667D01*
X1057683Y379917D01*
X1057850Y380250D01*
X1057767Y380750D01*
X1057433Y381000D01*
X1055933Y381500D01*
X1055600Y382083D01*
X1055767Y382500D01*
X1056100Y382750D01*
X1056600Y382833D01*
X1057100Y382750D01*
X1057600Y382500D01*
G01X1060783Y379500D02*
Y384500D01*
G01Y382083D02*
X1061200Y382500D01*
X1061617Y382750D01*
X1062283Y382833D01*
X1062783Y382750D01*
X1063367Y382417D01*
X1063617Y381917D01*
Y379500D01*
G01X1067800D02*
X1067300Y379583D01*
X1066800Y379917D01*
X1066467Y380500D01*
X1066300Y381167D01*
X1066467Y381833D01*
X1066800Y382417D01*
X1067300Y382750D01*
X1067800Y382833D01*
X1068300Y382750D01*
X1068800Y382417D01*
X1069133Y381833D01*
X1069217Y381167D01*
X1069133Y380500D01*
X1068800Y379917D01*
X1068300Y379583D01*
X1067800Y379500D01*
G01X1071983Y382833D02*
Y380500D01*
X1072317Y379917D01*
X1072817Y379583D01*
X1073400Y379500D01*
X1073983Y379583D01*
X1074483Y379917D01*
X1074817Y380500D01*
G01Y379500D02*
Y382833D01*
G01X1079000Y379500D02*
Y384500D01*
G01X1086100D02*
Y379500D01*
G01Y380250D02*
X1085767Y379833D01*
X1085267Y379583D01*
X1084683Y379500D01*
X1084017Y379667D01*
X1083517Y380083D01*
X1083183Y380583D01*
X1083100Y381167D01*
X1083183Y381750D01*
X1083517Y382250D01*
X1084017Y382667D01*
X1084683Y382833D01*
X1085267Y382750D01*
X1085683Y382583D01*
X1086100Y382250D01*
G01X1094300Y379500D02*
Y384500D01*
G01Y382000D02*
X1094717Y382500D01*
X1095217Y382750D01*
X1095717Y382833D01*
X1096467Y382667D01*
X1096967Y382333D01*
X1097300Y381750D01*
Y381083D01*
X1097133Y380417D01*
X1096800Y379917D01*
X1096217Y379583D01*
X1095717Y379500D01*
X1095217Y379583D01*
X1094717Y379833D01*
X1094300Y380250D01*
G01X1100150Y381750D02*
X1102817D01*
X1102567Y382333D01*
X1102150Y382667D01*
X1101567Y382833D01*
X1100983Y382750D01*
X1100483Y382500D01*
X1100150Y381917D01*
X1099983Y381417D01*
Y380917D01*
X1100150Y380417D01*
X1100567Y379917D01*
X1101067Y379583D01*
X1101650Y379500D01*
X1102233Y379667D01*
X1102817Y380167D01*
G01X1111100Y377833D02*
Y382833D01*
G01Y382083D02*
X1111517Y382500D01*
X1111933Y382750D01*
X1112600Y382833D01*
X1113183Y382750D01*
X1113767Y382333D01*
X1114017Y381750D01*
X1114100Y381167D01*
X1114017Y380583D01*
X1113767Y380000D01*
X1113267Y379667D01*
X1112600Y379500D01*
X1112017Y379583D01*
X1111433Y379833D01*
X1111100Y380167D01*
G01X1118200Y379500D02*
Y384500D01*
G01X1122383Y382833D02*
Y380500D01*
X1122717Y379917D01*
X1123217Y379583D01*
X1123800Y379500D01*
X1124383Y379583D01*
X1124883Y379917D01*
X1125217Y380500D01*
G01Y379500D02*
Y382833D01*
G01X1128233Y378250D02*
X1128817Y377917D01*
X1129483Y377833D01*
X1130067Y377917D01*
X1130567Y378333D01*
X1130900Y378917D01*
Y382833D01*
G01Y382167D02*
X1130567Y382500D01*
X1130067Y382750D01*
X1129483Y382833D01*
X1128817Y382667D01*
X1128400Y382333D01*
X1128067Y381750D01*
X1127900Y381167D01*
X1127983Y380667D01*
X1128317Y380083D01*
X1128817Y379667D01*
X1129483Y379500D01*
X1129983Y379583D01*
X1130567Y379917D01*
X1130900Y380250D01*
G01X1133833Y378250D02*
X1134417Y377917D01*
X1135083Y377833D01*
X1135667Y377917D01*
X1136167Y378333D01*
X1136500Y378917D01*
Y382833D01*
G01Y382167D02*
X1136167Y382500D01*
X1135667Y382750D01*
X1135083Y382833D01*
X1134417Y382667D01*
X1134000Y382333D01*
X1133667Y381750D01*
X1133500Y381167D01*
X1133583Y380667D01*
X1133917Y380083D01*
X1134417Y379667D01*
X1135083Y379500D01*
X1135583Y379583D01*
X1136167Y379917D01*
X1136500Y380250D01*
G01X1139350Y381750D02*
X1142017D01*
X1141767Y382333D01*
X1141350Y382667D01*
X1140767Y382833D01*
X1140183Y382750D01*
X1139683Y382500D01*
X1139350Y381917D01*
X1139183Y381417D01*
Y380917D01*
X1139350Y380417D01*
X1139767Y379917D01*
X1140267Y379583D01*
X1140850Y379500D01*
X1141433Y379667D01*
X1142017Y380167D01*
G01X1147700Y384500D02*
Y379500D01*
G01Y380250D02*
X1147367Y379833D01*
X1146867Y379583D01*
X1146283Y379500D01*
X1145617Y379667D01*
X1145117Y380083D01*
X1144783Y380583D01*
X1144700Y381167D01*
X1144783Y381750D01*
X1145117Y382250D01*
X1145617Y382667D01*
X1146283Y382833D01*
X1146867Y382750D01*
X1147283Y382583D01*
X1147700Y382250D01*
G01X1155317Y382833D02*
X1156317Y379500D01*
X1157400Y382833D01*
X1158483Y379500D01*
X1159483Y382833D01*
G01X1163000D02*
Y379500D01*
G01Y384167D02*
X1162833Y384250D01*
Y384417D01*
X1163000Y384500D01*
X1163167Y384417D01*
Y384250D01*
X1163000Y384167D01*
G01X1168600Y384500D02*
Y379500D01*
G01X1167433Y382833D02*
X1169767D01*
G01X1172783Y379500D02*
Y384500D01*
G01Y382083D02*
X1173200Y382500D01*
X1173617Y382750D01*
X1174283Y382833D01*
X1174783Y382750D01*
X1175367Y382417D01*
X1175617Y381917D01*
Y379500D01*
G01X1183733D02*
X1187067Y381167D01*
X1183733Y382833D01*
G01X1189583Y380083D02*
X1190167Y379667D01*
X1190833Y379500D01*
X1191500Y379667D01*
X1192083Y380167D01*
X1192500Y380917D01*
X1192667Y381667D01*
Y382583D01*
X1192500Y383333D01*
X1192083Y384000D01*
X1191583Y384333D01*
X1191000Y384500D01*
X1190333Y384333D01*
X1189833Y384000D01*
X1189500Y383500D01*
X1189333Y382833D01*
X1189500Y382250D01*
X1189917Y381667D01*
X1190417Y381333D01*
X1191000Y381250D01*
X1191667Y381417D01*
X1192167Y381833D01*
X1192667Y382583D01*
G01X1196600Y384500D02*
X1195933Y384333D01*
X1195433Y383917D01*
X1195100Y383417D01*
X1194850Y382750D01*
X1194767Y382000D01*
X1194850Y381250D01*
X1195100Y380583D01*
X1195433Y380083D01*
X1195933Y379667D01*
X1196600Y379500D01*
X1197267Y379667D01*
X1197767Y380083D01*
X1198100Y380583D01*
X1198350Y381250D01*
X1198433Y382000D01*
X1198350Y382750D01*
X1198100Y383417D01*
X1197767Y383917D01*
X1197267Y384333D01*
X1196600Y384500D01*
G01X1200700Y379333D02*
X1203700Y384500D01*
G01X1200700D02*
X1200200Y384333D01*
X1199950Y384083D01*
X1199783Y383583D01*
X1199950Y383083D01*
X1200200Y382833D01*
X1200700Y382667D01*
X1201200Y382833D01*
X1201450Y383083D01*
X1201617Y383583D01*
X1201450Y384083D01*
X1201200Y384333D01*
X1200700Y384500D01*
G01X1203700Y381167D02*
X1203200Y381000D01*
X1202950Y380750D01*
X1202783Y380250D01*
X1202950Y379750D01*
X1203200Y379500D01*
X1203700Y379333D01*
X1204200Y379500D01*
X1204450Y379750D01*
X1204617Y380250D01*
X1204450Y380750D01*
X1204200Y381000D01*
X1203700Y381167D01*
G01X1212233Y379500D02*
Y382833D01*
G01Y382167D02*
X1212650Y382500D01*
X1213067Y382750D01*
X1213650Y382833D01*
X1214067Y382750D01*
X1214567Y382500D01*
G01X1217750Y381750D02*
X1220417D01*
X1220167Y382333D01*
X1219750Y382667D01*
X1219167Y382833D01*
X1218583Y382750D01*
X1218083Y382500D01*
X1217750Y381917D01*
X1217583Y381417D01*
Y380917D01*
X1217750Y380417D01*
X1218167Y379917D01*
X1218667Y379583D01*
X1219250Y379500D01*
X1219833Y379667D01*
X1220417Y380167D01*
G01X1223350Y380083D02*
X1223767Y379750D01*
X1224350Y379500D01*
X1224850D01*
X1225350Y379667D01*
X1225683Y379917D01*
X1225850Y380250D01*
X1225767Y380750D01*
X1225433Y381000D01*
X1223933Y381500D01*
X1223600Y382083D01*
X1223767Y382500D01*
X1224100Y382750D01*
X1224600Y382833D01*
X1225100Y382750D01*
X1225600Y382500D01*
G01X1230200Y382833D02*
Y379500D01*
G01Y384167D02*
X1230033Y384250D01*
Y384417D01*
X1230200Y384500D01*
X1230367Y384417D01*
Y384250D01*
X1230200Y384167D01*
G01X1234383Y379500D02*
Y382833D01*
G01Y382000D02*
X1234717Y382417D01*
X1235217Y382750D01*
X1235883Y382833D01*
X1236467Y382750D01*
X1236967Y382417D01*
X1237217Y381833D01*
Y379500D01*
G01X1246417Y378000D02*
X1247583Y379167D01*
Y380333D01*
X1246417D01*
Y379167D01*
X1247583D01*
G01Y381167D02*
Y382333D01*
X1246417D01*
Y381167D01*
X1247583D01*
G01X1250767Y379500D02*
Y384500D01*
X1252433D01*
X1253100Y384250D01*
X1253600Y383917D01*
X1254017Y383417D01*
X1254350Y382833D01*
X1254433Y382000D01*
X1254350Y381167D01*
X1254017Y380583D01*
X1253600Y380083D01*
X1253100Y379750D01*
X1252433Y379500D01*
X1250767D01*
G01X1258200D02*
X1257700Y379583D01*
X1257200Y379917D01*
X1256867Y380500D01*
X1256700Y381167D01*
X1256867Y381833D01*
X1257200Y382417D01*
X1257700Y382750D01*
X1258200Y382833D01*
X1258700Y382750D01*
X1259200Y382417D01*
X1259533Y381833D01*
X1259617Y381167D01*
X1259533Y380500D01*
X1259200Y379917D01*
X1258700Y379583D01*
X1258200Y379500D01*
G01X1267983D02*
Y382833D01*
G01Y382000D02*
X1268317Y382417D01*
X1268817Y382750D01*
X1269483Y382833D01*
X1270067Y382750D01*
X1270567Y382417D01*
X1270817Y381833D01*
Y379500D01*
G01X1275000D02*
X1274500Y379583D01*
X1274000Y379917D01*
X1273667Y380500D01*
X1273500Y381167D01*
X1273667Y381833D01*
X1274000Y382417D01*
X1274500Y382750D01*
X1275000Y382833D01*
X1275500Y382750D01*
X1276000Y382417D01*
X1276333Y381833D01*
X1276417Y381167D01*
X1276333Y380500D01*
X1276000Y379917D01*
X1275500Y379583D01*
X1275000Y379500D01*
G01X1280600Y384500D02*
Y379500D01*
G01X1279433Y382833D02*
X1281767D01*
G01X1293300Y379500D02*
Y382833D01*
G01Y382250D02*
X1292967Y382583D01*
X1292467Y382750D01*
X1291883Y382833D01*
X1291300Y382667D01*
X1290800Y382333D01*
X1290467Y381833D01*
X1290300Y381167D01*
X1290467Y380500D01*
X1290800Y380000D01*
X1291300Y379667D01*
X1291883Y379500D01*
X1292467Y379583D01*
X1292967Y379833D01*
X1293300Y380167D01*
G01X1297400Y379500D02*
Y384500D01*
G01X1303000Y379500D02*
Y384500D01*
G01X1308600Y379500D02*
X1308100Y379583D01*
X1307600Y379917D01*
X1307267Y380500D01*
X1307100Y381167D01*
X1307267Y381833D01*
X1307600Y382417D01*
X1308100Y382750D01*
X1308600Y382833D01*
X1309100Y382750D01*
X1309600Y382417D01*
X1309933Y381833D01*
X1310017Y381167D01*
X1309933Y380500D01*
X1309600Y379917D01*
X1309100Y379583D01*
X1308600Y379500D01*
G01X1312117Y382833D02*
X1313117Y379500D01*
X1314200Y382833D01*
X1315283Y379500D01*
X1316283Y382833D01*
G01X1016000Y604500D02*
Y366000D01*
G01X1033500Y413500D02*
Y418500D01*
G01Y416000D02*
X1033917Y416500D01*
X1034417Y416750D01*
X1034917Y416833D01*
X1035667Y416667D01*
X1036167Y416333D01*
X1036500Y415750D01*
Y415083D01*
X1036333Y414417D01*
X1036000Y413917D01*
X1035417Y413583D01*
X1034917Y413500D01*
X1034417Y413583D01*
X1033917Y413833D01*
X1033500Y414250D01*
G01X1039183Y416833D02*
Y414500D01*
X1039517Y413917D01*
X1040017Y413583D01*
X1040600Y413500D01*
X1041183Y413583D01*
X1041683Y413917D01*
X1042017Y414500D01*
G01Y413500D02*
Y416833D01*
G01X1044700Y413500D02*
Y418500D01*
G01Y416000D02*
X1045117Y416500D01*
X1045617Y416750D01*
X1046117Y416833D01*
X1046867Y416667D01*
X1047367Y416333D01*
X1047700Y415750D01*
Y415083D01*
X1047533Y414417D01*
X1047200Y413917D01*
X1046617Y413583D01*
X1046117Y413500D01*
X1045617Y413583D01*
X1045117Y413833D01*
X1044700Y414250D01*
G01X1050300Y413500D02*
Y418500D01*
G01Y416000D02*
X1050717Y416500D01*
X1051217Y416750D01*
X1051717Y416833D01*
X1052467Y416667D01*
X1052967Y416333D01*
X1053300Y415750D01*
Y415083D01*
X1053133Y414417D01*
X1052800Y413917D01*
X1052217Y413583D01*
X1051717Y413500D01*
X1051217Y413583D01*
X1050717Y413833D01*
X1050300Y414250D01*
G01X1057400Y413500D02*
Y418500D01*
G01X1061750Y415750D02*
X1064417D01*
X1064167Y416333D01*
X1063750Y416667D01*
X1063167Y416833D01*
X1062583Y416750D01*
X1062083Y416500D01*
X1061750Y415917D01*
X1061583Y415417D01*
Y414917D01*
X1061750Y414417D01*
X1062167Y413917D01*
X1062667Y413583D01*
X1063250Y413500D01*
X1063833Y413667D01*
X1064417Y414167D01*
G01X1074200Y416833D02*
Y413500D01*
G01Y418167D02*
X1074033Y418250D01*
Y418417D01*
X1074200Y418500D01*
X1074367Y418417D01*
Y418250D01*
X1074200Y418167D01*
G01X1078383Y413500D02*
Y416833D01*
G01Y416000D02*
X1078717Y416417D01*
X1079217Y416750D01*
X1079883Y416833D01*
X1080467Y416750D01*
X1080967Y416417D01*
X1081217Y415833D01*
Y413500D01*
G01X1084150Y414083D02*
X1084567Y413750D01*
X1085150Y413500D01*
X1085650D01*
X1086150Y413667D01*
X1086483Y413917D01*
X1086650Y414250D01*
X1086567Y414750D01*
X1086233Y415000D01*
X1084733Y415500D01*
X1084400Y416083D01*
X1084567Y416500D01*
X1084900Y416750D01*
X1085400Y416833D01*
X1085900Y416750D01*
X1086400Y416500D01*
G01X1091000Y416833D02*
Y413500D01*
G01Y418167D02*
X1090833Y418250D01*
Y418417D01*
X1091000Y418500D01*
X1091167Y418417D01*
Y418250D01*
X1091000Y418167D01*
G01X1098100Y418500D02*
Y413500D01*
G01Y414250D02*
X1097767Y413833D01*
X1097267Y413583D01*
X1096683Y413500D01*
X1096017Y413667D01*
X1095517Y414083D01*
X1095183Y414583D01*
X1095100Y415167D01*
X1095183Y415750D01*
X1095517Y416250D01*
X1096017Y416667D01*
X1096683Y416833D01*
X1097267Y416750D01*
X1097683Y416583D01*
X1098100Y416250D01*
G01X1100950Y415750D02*
X1103617D01*
X1103367Y416333D01*
X1102950Y416667D01*
X1102367Y416833D01*
X1101783Y416750D01*
X1101283Y416500D01*
X1100950Y415917D01*
X1100783Y415417D01*
Y414917D01*
X1100950Y414417D01*
X1101367Y413917D01*
X1101867Y413583D01*
X1102450Y413500D01*
X1103033Y413667D01*
X1103617Y414167D01*
G01X1113400Y418500D02*
Y413500D01*
G01X1112233Y416833D02*
X1114567D01*
G01X1117583Y413500D02*
Y418500D01*
G01Y416083D02*
X1118000Y416500D01*
X1118417Y416750D01*
X1119083Y416833D01*
X1119583Y416750D01*
X1120167Y416417D01*
X1120417Y415917D01*
Y413500D01*
G01X1123350Y415750D02*
X1126017D01*
X1125767Y416333D01*
X1125350Y416667D01*
X1124767Y416833D01*
X1124183Y416750D01*
X1123683Y416500D01*
X1123350Y415917D01*
X1123183Y415417D01*
Y414917D01*
X1123350Y414417D01*
X1123767Y413917D01*
X1124267Y413583D01*
X1124850Y413500D01*
X1125433Y413667D01*
X1126017Y414167D01*
G01X1134633Y413500D02*
Y416833D01*
G01Y416167D02*
X1135050Y416500D01*
X1135467Y416750D01*
X1136050Y416833D01*
X1136467Y416750D01*
X1136967Y416500D01*
G01X1140150Y415750D02*
X1142817D01*
X1142567Y416333D01*
X1142150Y416667D01*
X1141567Y416833D01*
X1140983Y416750D01*
X1140483Y416500D01*
X1140150Y415917D01*
X1139983Y415417D01*
Y414917D01*
X1140150Y414417D01*
X1140567Y413917D01*
X1141067Y413583D01*
X1141650Y413500D01*
X1142233Y413667D01*
X1142817Y414167D01*
G01X1145750Y414083D02*
X1146167Y413750D01*
X1146750Y413500D01*
X1147250D01*
X1147750Y413667D01*
X1148083Y413917D01*
X1148250Y414250D01*
X1148167Y414750D01*
X1147833Y415000D01*
X1146333Y415500D01*
X1146000Y416083D01*
X1146167Y416500D01*
X1146500Y416750D01*
X1147000Y416833D01*
X1147500Y416750D01*
X1148000Y416500D01*
G01X1152600Y416833D02*
Y413500D01*
G01Y418167D02*
X1152433Y418250D01*
Y418417D01*
X1152600Y418500D01*
X1152767Y418417D01*
Y418250D01*
X1152600Y418167D01*
G01X1156783Y413500D02*
Y416833D01*
G01Y416000D02*
X1157117Y416417D01*
X1157617Y416750D01*
X1158283Y416833D01*
X1158867Y416750D01*
X1159367Y416417D01*
X1159617Y415833D01*
Y413500D01*
G01X1163800Y413333D02*
X1163633Y413417D01*
Y413583D01*
X1163800Y413667D01*
X1163967Y413583D01*
Y413417D01*
X1163800Y413333D01*
G01X1023000Y390000D02*
Y395000D01*
X1022000Y394000D01*
G01Y390000D02*
X1024000D01*
G01X1028600Y389833D02*
X1028433Y389917D01*
Y390083D01*
X1028600Y390167D01*
X1028767Y390083D01*
Y389917D01*
X1028600Y389833D01*
G01X1032367Y390000D02*
Y395000D01*
X1034033D01*
X1034700Y394750D01*
X1035200Y394417D01*
X1035617Y393917D01*
X1035950Y393333D01*
X1036033Y392500D01*
X1035950Y391667D01*
X1035617Y391083D01*
X1035200Y390583D01*
X1034700Y390250D01*
X1034033Y390000D01*
X1032367D01*
G01X1039800Y393333D02*
Y390000D01*
G01Y394667D02*
X1039633Y394750D01*
Y394917D01*
X1039800Y395000D01*
X1039967Y394917D01*
Y394750D01*
X1039800Y394667D01*
G01X1042900Y390000D02*
Y393333D01*
G01Y392417D02*
X1043150Y392833D01*
X1043567Y393167D01*
X1044150Y393333D01*
X1044733Y393167D01*
X1045150Y392833D01*
X1045400Y392417D01*
Y390000D01*
G01Y392417D02*
X1045650Y392833D01*
X1046067Y393167D01*
X1046650Y393333D01*
X1047233Y393167D01*
X1047650Y392833D01*
X1047900Y392333D01*
Y390000D01*
G01X1049500Y388333D02*
Y393333D01*
G01Y392583D02*
X1049917Y393000D01*
X1050333Y393250D01*
X1051000Y393333D01*
X1051583Y393250D01*
X1052167Y392833D01*
X1052417Y392250D01*
X1052500Y391667D01*
X1052417Y391083D01*
X1052167Y390500D01*
X1051667Y390167D01*
X1051000Y390000D01*
X1050417Y390083D01*
X1049833Y390333D01*
X1049500Y390667D01*
G01X1056600Y390000D02*
Y395000D01*
G01X1060950Y392250D02*
X1063617D01*
X1063367Y392833D01*
X1062950Y393167D01*
X1062367Y393333D01*
X1061783Y393250D01*
X1061283Y393000D01*
X1060950Y392417D01*
X1060783Y391917D01*
Y391417D01*
X1060950Y390917D01*
X1061367Y390417D01*
X1061867Y390083D01*
X1062450Y390000D01*
X1063033Y390167D01*
X1063617Y390667D01*
G01X1075067Y390000D02*
X1071733Y391667D01*
X1075067Y393333D01*
G01X1084600Y390000D02*
Y395000D01*
X1083600Y394000D01*
G01Y390000D02*
X1085600D01*
G01X1093300D02*
Y393333D01*
G01Y392417D02*
X1093550Y392833D01*
X1093967Y393167D01*
X1094550Y393333D01*
X1095133Y393167D01*
X1095550Y392833D01*
X1095800Y392417D01*
Y390000D01*
G01Y392417D02*
X1096050Y392833D01*
X1096467Y393167D01*
X1097050Y393333D01*
X1097633Y393167D01*
X1098050Y392833D01*
X1098300Y392333D01*
Y390000D01*
G01X1101400Y393333D02*
Y390000D01*
G01Y394667D02*
X1101233Y394750D01*
Y394917D01*
X1101400Y395000D01*
X1101567Y394917D01*
Y394750D01*
X1101400Y394667D01*
G01X1107000Y390000D02*
Y395000D01*
G01X1117617Y388500D02*
X1118783Y389667D01*
Y390833D01*
X1117617D01*
Y389667D01*
X1118783D01*
G01Y391667D02*
Y392833D01*
X1117617D01*
Y391667D01*
X1118783D01*
G01X1023000Y424000D02*
Y429000D01*
X1022000Y428000D01*
G01Y424000D02*
X1024000D01*
G01X1028600Y423833D02*
X1028433Y423917D01*
Y424083D01*
X1028600Y424167D01*
X1028767Y424083D01*
Y423917D01*
X1028600Y423833D01*
G01X1032117Y429000D02*
X1034200Y424000D01*
X1036283Y429000D01*
G01X1039800Y427333D02*
Y424000D01*
G01Y428667D02*
X1039633Y428750D01*
Y428917D01*
X1039800Y429000D01*
X1039967Y428917D01*
Y428750D01*
X1039800Y428667D01*
G01X1046900Y424000D02*
Y427333D01*
G01Y426750D02*
X1046567Y427083D01*
X1046067Y427250D01*
X1045483Y427333D01*
X1044900Y427167D01*
X1044400Y426833D01*
X1044067Y426333D01*
X1043900Y425667D01*
X1044067Y425000D01*
X1044400Y424500D01*
X1044900Y424167D01*
X1045483Y424000D01*
X1046067Y424083D01*
X1046567Y424333D01*
X1046900Y424667D01*
G01X1055350Y424583D02*
X1055767Y424250D01*
X1056350Y424000D01*
X1056850D01*
X1057350Y424167D01*
X1057683Y424417D01*
X1057850Y424750D01*
X1057767Y425250D01*
X1057433Y425500D01*
X1055933Y426000D01*
X1055600Y426583D01*
X1055767Y427000D01*
X1056100Y427250D01*
X1056600Y427333D01*
X1057100Y427250D01*
X1057600Y427000D01*
G01X1060783Y424000D02*
Y429000D01*
G01Y426583D02*
X1061200Y427000D01*
X1061617Y427250D01*
X1062283Y427333D01*
X1062783Y427250D01*
X1063367Y426917D01*
X1063617Y426417D01*
Y424000D01*
G01X1067800D02*
X1067300Y424083D01*
X1066800Y424417D01*
X1066467Y425000D01*
X1066300Y425667D01*
X1066467Y426333D01*
X1066800Y426917D01*
X1067300Y427250D01*
X1067800Y427333D01*
X1068300Y427250D01*
X1068800Y426917D01*
X1069133Y426333D01*
X1069217Y425667D01*
X1069133Y425000D01*
X1068800Y424417D01*
X1068300Y424083D01*
X1067800Y424000D01*
G01X1071983Y427333D02*
Y425000D01*
X1072317Y424417D01*
X1072817Y424083D01*
X1073400Y424000D01*
X1073983Y424083D01*
X1074483Y424417D01*
X1074817Y425000D01*
G01Y424000D02*
Y427333D01*
G01X1079000Y424000D02*
Y429000D01*
G01X1086100D02*
Y424000D01*
G01Y424750D02*
X1085767Y424333D01*
X1085267Y424083D01*
X1084683Y424000D01*
X1084017Y424167D01*
X1083517Y424583D01*
X1083183Y425083D01*
X1083100Y425667D01*
X1083183Y426250D01*
X1083517Y426750D01*
X1084017Y427167D01*
X1084683Y427333D01*
X1085267Y427250D01*
X1085683Y427083D01*
X1086100Y426750D01*
G01X1094300Y424000D02*
Y429000D01*
G01Y426500D02*
X1094717Y427000D01*
X1095217Y427250D01*
X1095717Y427333D01*
X1096467Y427167D01*
X1096967Y426833D01*
X1097300Y426250D01*
Y425583D01*
X1097133Y424917D01*
X1096800Y424417D01*
X1096217Y424083D01*
X1095717Y424000D01*
X1095217Y424083D01*
X1094717Y424333D01*
X1094300Y424750D01*
G01X1100150Y426250D02*
X1102817D01*
X1102567Y426833D01*
X1102150Y427167D01*
X1101567Y427333D01*
X1100983Y427250D01*
X1100483Y427000D01*
X1100150Y426417D01*
X1099983Y425917D01*
Y425417D01*
X1100150Y424917D01*
X1100567Y424417D01*
X1101067Y424083D01*
X1101650Y424000D01*
X1102233Y424167D01*
X1102817Y424667D01*
G01X1111100Y422333D02*
Y427333D01*
G01Y426583D02*
X1111517Y427000D01*
X1111933Y427250D01*
X1112600Y427333D01*
X1113183Y427250D01*
X1113767Y426833D01*
X1114017Y426250D01*
X1114100Y425667D01*
X1114017Y425083D01*
X1113767Y424500D01*
X1113267Y424167D01*
X1112600Y424000D01*
X1112017Y424083D01*
X1111433Y424333D01*
X1111100Y424667D01*
G01X1118200Y424000D02*
Y429000D01*
G01X1122383Y427333D02*
Y425000D01*
X1122717Y424417D01*
X1123217Y424083D01*
X1123800Y424000D01*
X1124383Y424083D01*
X1124883Y424417D01*
X1125217Y425000D01*
G01Y424000D02*
Y427333D01*
G01X1128233Y422750D02*
X1128817Y422417D01*
X1129483Y422333D01*
X1130067Y422417D01*
X1130567Y422833D01*
X1130900Y423417D01*
Y427333D01*
G01Y426667D02*
X1130567Y427000D01*
X1130067Y427250D01*
X1129483Y427333D01*
X1128817Y427167D01*
X1128400Y426833D01*
X1128067Y426250D01*
X1127900Y425667D01*
X1127983Y425167D01*
X1128317Y424583D01*
X1128817Y424167D01*
X1129483Y424000D01*
X1129983Y424083D01*
X1130567Y424417D01*
X1130900Y424750D01*
G01X1133833Y422750D02*
X1134417Y422417D01*
X1135083Y422333D01*
X1135667Y422417D01*
X1136167Y422833D01*
X1136500Y423417D01*
Y427333D01*
G01Y426667D02*
X1136167Y427000D01*
X1135667Y427250D01*
X1135083Y427333D01*
X1134417Y427167D01*
X1134000Y426833D01*
X1133667Y426250D01*
X1133500Y425667D01*
X1133583Y425167D01*
X1133917Y424583D01*
X1134417Y424167D01*
X1135083Y424000D01*
X1135583Y424083D01*
X1136167Y424417D01*
X1136500Y424750D01*
G01X1139350Y426250D02*
X1142017D01*
X1141767Y426833D01*
X1141350Y427167D01*
X1140767Y427333D01*
X1140183Y427250D01*
X1139683Y427000D01*
X1139350Y426417D01*
X1139183Y425917D01*
Y425417D01*
X1139350Y424917D01*
X1139767Y424417D01*
X1140267Y424083D01*
X1140850Y424000D01*
X1141433Y424167D01*
X1142017Y424667D01*
G01X1147700Y429000D02*
Y424000D01*
G01Y424750D02*
X1147367Y424333D01*
X1146867Y424083D01*
X1146283Y424000D01*
X1145617Y424167D01*
X1145117Y424583D01*
X1144783Y425083D01*
X1144700Y425667D01*
X1144783Y426250D01*
X1145117Y426750D01*
X1145617Y427167D01*
X1146283Y427333D01*
X1146867Y427250D01*
X1147283Y427083D01*
X1147700Y426750D01*
G01X1155317Y427333D02*
X1156317Y424000D01*
X1157400Y427333D01*
X1158483Y424000D01*
X1159483Y427333D01*
G01X1163000D02*
Y424000D01*
G01Y428667D02*
X1162833Y428750D01*
Y428917D01*
X1163000Y429000D01*
X1163167Y428917D01*
Y428750D01*
X1163000Y428667D01*
G01X1168600Y429000D02*
Y424000D01*
G01X1167433Y427333D02*
X1169767D01*
G01X1172783Y424000D02*
Y429000D01*
G01Y426583D02*
X1173200Y427000D01*
X1173617Y427250D01*
X1174283Y427333D01*
X1174783Y427250D01*
X1175367Y426917D01*
X1175617Y426417D01*
Y424000D01*
G01X1183733D02*
X1187067Y425667D01*
X1183733Y427333D01*
G01X1189583Y424583D02*
X1190167Y424167D01*
X1190833Y424000D01*
X1191500Y424167D01*
X1192083Y424667D01*
X1192500Y425417D01*
X1192667Y426167D01*
Y427083D01*
X1192500Y427833D01*
X1192083Y428500D01*
X1191583Y428833D01*
X1191000Y429000D01*
X1190333Y428833D01*
X1189833Y428500D01*
X1189500Y428000D01*
X1189333Y427333D01*
X1189500Y426750D01*
X1189917Y426167D01*
X1190417Y425833D01*
X1191000Y425750D01*
X1191667Y425917D01*
X1192167Y426333D01*
X1192667Y427083D01*
G01X1196600Y429000D02*
X1195933Y428833D01*
X1195433Y428417D01*
X1195100Y427917D01*
X1194850Y427250D01*
X1194767Y426500D01*
X1194850Y425750D01*
X1195100Y425083D01*
X1195433Y424583D01*
X1195933Y424167D01*
X1196600Y424000D01*
X1197267Y424167D01*
X1197767Y424583D01*
X1198100Y425083D01*
X1198350Y425750D01*
X1198433Y426500D01*
X1198350Y427250D01*
X1198100Y427917D01*
X1197767Y428417D01*
X1197267Y428833D01*
X1196600Y429000D01*
G01X1200700Y423833D02*
X1203700Y429000D01*
G01X1200700D02*
X1200200Y428833D01*
X1199950Y428583D01*
X1199783Y428083D01*
X1199950Y427583D01*
X1200200Y427333D01*
X1200700Y427167D01*
X1201200Y427333D01*
X1201450Y427583D01*
X1201617Y428083D01*
X1201450Y428583D01*
X1201200Y428833D01*
X1200700Y429000D01*
G01X1203700Y425667D02*
X1203200Y425500D01*
X1202950Y425250D01*
X1202783Y424750D01*
X1202950Y424250D01*
X1203200Y424000D01*
X1203700Y423833D01*
X1204200Y424000D01*
X1204450Y424250D01*
X1204617Y424750D01*
X1204450Y425250D01*
X1204200Y425500D01*
X1203700Y425667D01*
G01X1212233Y424000D02*
Y427333D01*
G01Y426667D02*
X1212650Y427000D01*
X1213067Y427250D01*
X1213650Y427333D01*
X1214067Y427250D01*
X1214567Y427000D01*
G01X1217750Y426250D02*
X1220417D01*
X1220167Y426833D01*
X1219750Y427167D01*
X1219167Y427333D01*
X1218583Y427250D01*
X1218083Y427000D01*
X1217750Y426417D01*
X1217583Y425917D01*
Y425417D01*
X1217750Y424917D01*
X1218167Y424417D01*
X1218667Y424083D01*
X1219250Y424000D01*
X1219833Y424167D01*
X1220417Y424667D01*
G01X1223350Y424583D02*
X1223767Y424250D01*
X1224350Y424000D01*
X1224850D01*
X1225350Y424167D01*
X1225683Y424417D01*
X1225850Y424750D01*
X1225767Y425250D01*
X1225433Y425500D01*
X1223933Y426000D01*
X1223600Y426583D01*
X1223767Y427000D01*
X1224100Y427250D01*
X1224600Y427333D01*
X1225100Y427250D01*
X1225600Y427000D01*
G01X1230200Y427333D02*
Y424000D01*
G01Y428667D02*
X1230033Y428750D01*
Y428917D01*
X1230200Y429000D01*
X1230367Y428917D01*
Y428750D01*
X1230200Y428667D01*
G01X1234383Y424000D02*
Y427333D01*
G01Y426500D02*
X1234717Y426917D01*
X1235217Y427250D01*
X1235883Y427333D01*
X1236467Y427250D01*
X1236967Y426917D01*
X1237217Y426333D01*
Y424000D01*
G01X1246417Y422500D02*
X1247583Y423667D01*
Y424833D01*
X1246417D01*
Y423667D01*
X1247583D01*
G01Y425667D02*
Y426833D01*
X1246417D01*
Y425667D01*
X1247583D01*
G01X1250767Y424000D02*
Y429000D01*
X1252433D01*
X1253100Y428750D01*
X1253600Y428417D01*
X1254017Y427917D01*
X1254350Y427333D01*
X1254433Y426500D01*
X1254350Y425667D01*
X1254017Y425083D01*
X1253600Y424583D01*
X1253100Y424250D01*
X1252433Y424000D01*
X1250767D01*
G01X1258200D02*
X1257700Y424083D01*
X1257200Y424417D01*
X1256867Y425000D01*
X1256700Y425667D01*
X1256867Y426333D01*
X1257200Y426917D01*
X1257700Y427250D01*
X1258200Y427333D01*
X1258700Y427250D01*
X1259200Y426917D01*
X1259533Y426333D01*
X1259617Y425667D01*
X1259533Y425000D01*
X1259200Y424417D01*
X1258700Y424083D01*
X1258200Y424000D01*
G01X1267983D02*
Y427333D01*
G01Y426500D02*
X1268317Y426917D01*
X1268817Y427250D01*
X1269483Y427333D01*
X1270067Y427250D01*
X1270567Y426917D01*
X1270817Y426333D01*
Y424000D01*
G01X1275000D02*
X1274500Y424083D01*
X1274000Y424417D01*
X1273667Y425000D01*
X1273500Y425667D01*
X1273667Y426333D01*
X1274000Y426917D01*
X1274500Y427250D01*
X1275000Y427333D01*
X1275500Y427250D01*
X1276000Y426917D01*
X1276333Y426333D01*
X1276417Y425667D01*
X1276333Y425000D01*
X1276000Y424417D01*
X1275500Y424083D01*
X1275000Y424000D01*
G01X1280600Y429000D02*
Y424000D01*
G01X1279433Y427333D02*
X1281767D01*
G01X1293300Y424000D02*
Y427333D01*
G01Y426750D02*
X1292967Y427083D01*
X1292467Y427250D01*
X1291883Y427333D01*
X1291300Y427167D01*
X1290800Y426833D01*
X1290467Y426333D01*
X1290300Y425667D01*
X1290467Y425000D01*
X1290800Y424500D01*
X1291300Y424167D01*
X1291883Y424000D01*
X1292467Y424083D01*
X1292967Y424333D01*
X1293300Y424667D01*
G01X1297400Y424000D02*
Y429000D01*
G01X1303000Y424000D02*
Y429000D01*
G01X1308600Y424000D02*
X1308100Y424083D01*
X1307600Y424417D01*
X1307267Y425000D01*
X1307100Y425667D01*
X1307267Y426333D01*
X1307600Y426917D01*
X1308100Y427250D01*
X1308600Y427333D01*
X1309100Y427250D01*
X1309600Y426917D01*
X1309933Y426333D01*
X1310017Y425667D01*
X1309933Y425000D01*
X1309600Y424417D01*
X1309100Y424083D01*
X1308600Y424000D01*
G01X1312117Y427333D02*
X1313117Y424000D01*
X1314200Y427333D01*
X1315283Y424000D01*
X1316283Y427333D01*
G01X1025417Y445500D02*
X1027500Y440500D01*
X1029583Y445500D01*
G01X1033100Y443833D02*
Y440500D01*
G01Y445167D02*
X1032933Y445250D01*
Y445417D01*
X1033100Y445500D01*
X1033267Y445417D01*
Y445250D01*
X1033100Y445167D01*
G01X1040200Y440500D02*
Y443833D01*
G01Y443250D02*
X1039867Y443583D01*
X1039367Y443750D01*
X1038783Y443833D01*
X1038200Y443667D01*
X1037700Y443333D01*
X1037367Y442833D01*
X1037200Y442167D01*
X1037367Y441500D01*
X1037700Y441000D01*
X1038200Y440667D01*
X1038783Y440500D01*
X1039367Y440583D01*
X1039867Y440833D01*
X1040200Y441167D01*
G01X1048650Y441083D02*
X1049067Y440750D01*
X1049650Y440500D01*
X1050150D01*
X1050650Y440667D01*
X1050983Y440917D01*
X1051150Y441250D01*
X1051067Y441750D01*
X1050733Y442000D01*
X1049233Y442500D01*
X1048900Y443083D01*
X1049067Y443500D01*
X1049400Y443750D01*
X1049900Y443833D01*
X1050400Y443750D01*
X1050900Y443500D01*
G01X1054083Y440500D02*
Y445500D01*
G01Y443083D02*
X1054500Y443500D01*
X1054917Y443750D01*
X1055583Y443833D01*
X1056083Y443750D01*
X1056667Y443417D01*
X1056917Y442917D01*
Y440500D01*
G01X1061100D02*
X1060600Y440583D01*
X1060100Y440917D01*
X1059767Y441500D01*
X1059600Y442167D01*
X1059767Y442833D01*
X1060100Y443417D01*
X1060600Y443750D01*
X1061100Y443833D01*
X1061600Y443750D01*
X1062100Y443417D01*
X1062433Y442833D01*
X1062517Y442167D01*
X1062433Y441500D01*
X1062100Y440917D01*
X1061600Y440583D01*
X1061100Y440500D01*
G01X1065283Y443833D02*
Y441500D01*
X1065617Y440917D01*
X1066117Y440583D01*
X1066700Y440500D01*
X1067283Y440583D01*
X1067783Y440917D01*
X1068117Y441500D01*
G01Y440500D02*
Y443833D01*
G01X1072300Y440500D02*
Y445500D01*
G01X1079400D02*
Y440500D01*
G01Y441250D02*
X1079067Y440833D01*
X1078567Y440583D01*
X1077983Y440500D01*
X1077317Y440667D01*
X1076817Y441083D01*
X1076483Y441583D01*
X1076400Y442167D01*
X1076483Y442750D01*
X1076817Y443250D01*
X1077317Y443667D01*
X1077983Y443833D01*
X1078567Y443750D01*
X1078983Y443583D01*
X1079400Y443250D01*
G01X1087600Y440500D02*
Y445500D01*
G01Y443000D02*
X1088017Y443500D01*
X1088517Y443750D01*
X1089017Y443833D01*
X1089767Y443667D01*
X1090267Y443333D01*
X1090600Y442750D01*
Y442083D01*
X1090433Y441417D01*
X1090100Y440917D01*
X1089517Y440583D01*
X1089017Y440500D01*
X1088517Y440583D01*
X1088017Y440833D01*
X1087600Y441250D01*
G01X1093450Y442750D02*
X1096117D01*
X1095867Y443333D01*
X1095450Y443667D01*
X1094867Y443833D01*
X1094283Y443750D01*
X1093783Y443500D01*
X1093450Y442917D01*
X1093283Y442417D01*
Y441917D01*
X1093450Y441417D01*
X1093867Y440917D01*
X1094367Y440583D01*
X1094950Y440500D01*
X1095533Y440667D01*
X1096117Y441167D01*
G01X1104400Y438833D02*
Y443833D01*
G01Y443083D02*
X1104817Y443500D01*
X1105233Y443750D01*
X1105900Y443833D01*
X1106483Y443750D01*
X1107067Y443333D01*
X1107317Y442750D01*
X1107400Y442167D01*
X1107317Y441583D01*
X1107067Y441000D01*
X1106567Y440667D01*
X1105900Y440500D01*
X1105317Y440583D01*
X1104733Y440833D01*
X1104400Y441167D01*
G01X1111500Y440500D02*
Y445500D01*
G01X1115683Y443833D02*
Y441500D01*
X1116017Y440917D01*
X1116517Y440583D01*
X1117100Y440500D01*
X1117683Y440583D01*
X1118183Y440917D01*
X1118517Y441500D01*
G01Y440500D02*
Y443833D01*
G01X1121533Y439250D02*
X1122117Y438917D01*
X1122783Y438833D01*
X1123367Y438917D01*
X1123867Y439333D01*
X1124200Y439917D01*
Y443833D01*
G01Y443167D02*
X1123867Y443500D01*
X1123367Y443750D01*
X1122783Y443833D01*
X1122117Y443667D01*
X1121700Y443333D01*
X1121367Y442750D01*
X1121200Y442167D01*
X1121283Y441667D01*
X1121617Y441083D01*
X1122117Y440667D01*
X1122783Y440500D01*
X1123283Y440583D01*
X1123867Y440917D01*
X1124200Y441250D01*
G01X1127133Y439250D02*
X1127717Y438917D01*
X1128383Y438833D01*
X1128967Y438917D01*
X1129467Y439333D01*
X1129800Y439917D01*
Y443833D01*
G01Y443167D02*
X1129467Y443500D01*
X1128967Y443750D01*
X1128383Y443833D01*
X1127717Y443667D01*
X1127300Y443333D01*
X1126967Y442750D01*
X1126800Y442167D01*
X1126883Y441667D01*
X1127217Y441083D01*
X1127717Y440667D01*
X1128383Y440500D01*
X1128883Y440583D01*
X1129467Y440917D01*
X1129800Y441250D01*
G01X1132650Y442750D02*
X1135317D01*
X1135067Y443333D01*
X1134650Y443667D01*
X1134067Y443833D01*
X1133483Y443750D01*
X1132983Y443500D01*
X1132650Y442917D01*
X1132483Y442417D01*
Y441917D01*
X1132650Y441417D01*
X1133067Y440917D01*
X1133567Y440583D01*
X1134150Y440500D01*
X1134733Y440667D01*
X1135317Y441167D01*
G01X1141000Y445500D02*
Y440500D01*
G01Y441250D02*
X1140667Y440833D01*
X1140167Y440583D01*
X1139583Y440500D01*
X1138917Y440667D01*
X1138417Y441083D01*
X1138083Y441583D01*
X1138000Y442167D01*
X1138083Y442750D01*
X1138417Y443250D01*
X1138917Y443667D01*
X1139583Y443833D01*
X1140167Y443750D01*
X1140583Y443583D01*
X1141000Y443250D01*
G01X1148617Y443833D02*
X1149617Y440500D01*
X1150700Y443833D01*
X1151783Y440500D01*
X1152783Y443833D01*
G01X1156300D02*
Y440500D01*
G01Y445167D02*
X1156133Y445250D01*
Y445417D01*
X1156300Y445500D01*
X1156467Y445417D01*
Y445250D01*
X1156300Y445167D01*
G01X1161900Y445500D02*
Y440500D01*
G01X1160733Y443833D02*
X1163067D01*
G01X1166083Y440500D02*
Y445500D01*
G01Y443083D02*
X1166500Y443500D01*
X1166917Y443750D01*
X1167583Y443833D01*
X1168083Y443750D01*
X1168667Y443417D01*
X1168917Y442917D01*
Y440500D01*
G01X1177033D02*
X1180367Y442167D01*
X1177033Y443833D01*
G01X1182883Y441083D02*
X1183467Y440667D01*
X1184133Y440500D01*
X1184800Y440667D01*
X1185383Y441167D01*
X1185800Y441917D01*
X1185967Y442667D01*
Y443583D01*
X1185800Y444333D01*
X1185383Y445000D01*
X1184883Y445333D01*
X1184300Y445500D01*
X1183633Y445333D01*
X1183133Y445000D01*
X1182800Y444500D01*
X1182633Y443833D01*
X1182800Y443250D01*
X1183217Y442667D01*
X1183717Y442333D01*
X1184300Y442250D01*
X1184967Y442417D01*
X1185467Y442833D01*
X1185967Y443583D01*
G01X1189900Y445500D02*
X1189233Y445333D01*
X1188733Y444917D01*
X1188400Y444417D01*
X1188150Y443750D01*
X1188067Y443000D01*
X1188150Y442250D01*
X1188400Y441583D01*
X1188733Y441083D01*
X1189233Y440667D01*
X1189900Y440500D01*
X1190567Y440667D01*
X1191067Y441083D01*
X1191400Y441583D01*
X1191650Y442250D01*
X1191733Y443000D01*
X1191650Y443750D01*
X1191400Y444417D01*
X1191067Y444917D01*
X1190567Y445333D01*
X1189900Y445500D01*
G01X1194000Y440333D02*
X1197000Y445500D01*
G01X1194000D02*
X1193500Y445333D01*
X1193250Y445083D01*
X1193083Y444583D01*
X1193250Y444083D01*
X1193500Y443833D01*
X1194000Y443667D01*
X1194500Y443833D01*
X1194750Y444083D01*
X1194917Y444583D01*
X1194750Y445083D01*
X1194500Y445333D01*
X1194000Y445500D01*
G01X1197000Y442167D02*
X1196500Y442000D01*
X1196250Y441750D01*
X1196083Y441250D01*
X1196250Y440750D01*
X1196500Y440500D01*
X1197000Y440333D01*
X1197500Y440500D01*
X1197750Y440750D01*
X1197917Y441250D01*
X1197750Y441750D01*
X1197500Y442000D01*
X1197000Y442167D01*
G01X1205533Y440500D02*
Y443833D01*
G01Y443167D02*
X1205950Y443500D01*
X1206367Y443750D01*
X1206950Y443833D01*
X1207367Y443750D01*
X1207867Y443500D01*
G01X1211050Y442750D02*
X1213717D01*
X1213467Y443333D01*
X1213050Y443667D01*
X1212467Y443833D01*
X1211883Y443750D01*
X1211383Y443500D01*
X1211050Y442917D01*
X1210883Y442417D01*
Y441917D01*
X1211050Y441417D01*
X1211467Y440917D01*
X1211967Y440583D01*
X1212550Y440500D01*
X1213133Y440667D01*
X1213717Y441167D01*
G01X1216650Y441083D02*
X1217067Y440750D01*
X1217650Y440500D01*
X1218150D01*
X1218650Y440667D01*
X1218983Y440917D01*
X1219150Y441250D01*
X1219067Y441750D01*
X1218733Y442000D01*
X1217233Y442500D01*
X1216900Y443083D01*
X1217067Y443500D01*
X1217400Y443750D01*
X1217900Y443833D01*
X1218400Y443750D01*
X1218900Y443500D01*
G01X1223500Y443833D02*
Y440500D01*
G01Y445167D02*
X1223333Y445250D01*
Y445417D01*
X1223500Y445500D01*
X1223667Y445417D01*
Y445250D01*
X1223500Y445167D01*
G01X1227683Y440500D02*
Y443833D01*
G01Y443000D02*
X1228017Y443417D01*
X1228517Y443750D01*
X1229183Y443833D01*
X1229767Y443750D01*
X1230267Y443417D01*
X1230517Y442833D01*
Y440500D01*
G01X1023917Y466500D02*
X1026000Y461500D01*
X1028083Y466500D01*
G01X1031600Y464833D02*
Y461500D01*
G01Y466167D02*
X1031433Y466250D01*
Y466417D01*
X1031600Y466500D01*
X1031767Y466417D01*
Y466250D01*
X1031600Y466167D01*
G01X1038700Y461500D02*
Y464833D01*
G01Y464250D02*
X1038367Y464583D01*
X1037867Y464750D01*
X1037283Y464833D01*
X1036700Y464667D01*
X1036200Y464333D01*
X1035867Y463833D01*
X1035700Y463167D01*
X1035867Y462500D01*
X1036200Y462000D01*
X1036700Y461667D01*
X1037283Y461500D01*
X1037867Y461583D01*
X1038367Y461833D01*
X1038700Y462167D01*
G01X1047150Y462083D02*
X1047567Y461750D01*
X1048150Y461500D01*
X1048650D01*
X1049150Y461667D01*
X1049483Y461917D01*
X1049650Y462250D01*
X1049567Y462750D01*
X1049233Y463000D01*
X1047733Y463500D01*
X1047400Y464083D01*
X1047567Y464500D01*
X1047900Y464750D01*
X1048400Y464833D01*
X1048900Y464750D01*
X1049400Y464500D01*
G01X1052583Y461500D02*
Y466500D01*
G01Y464083D02*
X1053000Y464500D01*
X1053417Y464750D01*
X1054083Y464833D01*
X1054583Y464750D01*
X1055167Y464417D01*
X1055417Y463917D01*
Y461500D01*
G01X1059600D02*
X1059100Y461583D01*
X1058600Y461917D01*
X1058267Y462500D01*
X1058100Y463167D01*
X1058267Y463833D01*
X1058600Y464417D01*
X1059100Y464750D01*
X1059600Y464833D01*
X1060100Y464750D01*
X1060600Y464417D01*
X1060933Y463833D01*
X1061017Y463167D01*
X1060933Y462500D01*
X1060600Y461917D01*
X1060100Y461583D01*
X1059600Y461500D01*
G01X1063783Y464833D02*
Y462500D01*
X1064117Y461917D01*
X1064617Y461583D01*
X1065200Y461500D01*
X1065783Y461583D01*
X1066283Y461917D01*
X1066617Y462500D01*
G01Y461500D02*
Y464833D01*
G01X1070800Y461500D02*
Y466500D01*
G01X1077900D02*
Y461500D01*
G01Y462250D02*
X1077567Y461833D01*
X1077067Y461583D01*
X1076483Y461500D01*
X1075817Y461667D01*
X1075317Y462083D01*
X1074983Y462583D01*
X1074900Y463167D01*
X1074983Y463750D01*
X1075317Y464250D01*
X1075817Y464667D01*
X1076483Y464833D01*
X1077067Y464750D01*
X1077483Y464583D01*
X1077900Y464250D01*
G01X1086100Y461500D02*
Y466500D01*
G01Y464000D02*
X1086517Y464500D01*
X1087017Y464750D01*
X1087517Y464833D01*
X1088267Y464667D01*
X1088767Y464333D01*
X1089100Y463750D01*
Y463083D01*
X1088933Y462417D01*
X1088600Y461917D01*
X1088017Y461583D01*
X1087517Y461500D01*
X1087017Y461583D01*
X1086517Y461833D01*
X1086100Y462250D01*
G01X1091950Y463750D02*
X1094617D01*
X1094367Y464333D01*
X1093950Y464667D01*
X1093367Y464833D01*
X1092783Y464750D01*
X1092283Y464500D01*
X1091950Y463917D01*
X1091783Y463417D01*
Y462917D01*
X1091950Y462417D01*
X1092367Y461917D01*
X1092867Y461583D01*
X1093450Y461500D01*
X1094033Y461667D01*
X1094617Y462167D01*
G01X1102900Y459833D02*
Y464833D01*
G01Y464083D02*
X1103317Y464500D01*
X1103733Y464750D01*
X1104400Y464833D01*
X1104983Y464750D01*
X1105567Y464333D01*
X1105817Y463750D01*
X1105900Y463167D01*
X1105817Y462583D01*
X1105567Y462000D01*
X1105067Y461667D01*
X1104400Y461500D01*
X1103817Y461583D01*
X1103233Y461833D01*
X1102900Y462167D01*
G01X1110000Y461500D02*
Y466500D01*
G01X1114183Y464833D02*
Y462500D01*
X1114517Y461917D01*
X1115017Y461583D01*
X1115600Y461500D01*
X1116183Y461583D01*
X1116683Y461917D01*
X1117017Y462500D01*
G01Y461500D02*
Y464833D01*
G01X1120033Y460250D02*
X1120617Y459917D01*
X1121283Y459833D01*
X1121867Y459917D01*
X1122367Y460333D01*
X1122700Y460917D01*
Y464833D01*
G01Y464167D02*
X1122367Y464500D01*
X1121867Y464750D01*
X1121283Y464833D01*
X1120617Y464667D01*
X1120200Y464333D01*
X1119867Y463750D01*
X1119700Y463167D01*
X1119783Y462667D01*
X1120117Y462083D01*
X1120617Y461667D01*
X1121283Y461500D01*
X1121783Y461583D01*
X1122367Y461917D01*
X1122700Y462250D01*
G01X1125633Y460250D02*
X1126217Y459917D01*
X1126883Y459833D01*
X1127467Y459917D01*
X1127967Y460333D01*
X1128300Y460917D01*
Y464833D01*
G01Y464167D02*
X1127967Y464500D01*
X1127467Y464750D01*
X1126883Y464833D01*
X1126217Y464667D01*
X1125800Y464333D01*
X1125467Y463750D01*
X1125300Y463167D01*
X1125383Y462667D01*
X1125717Y462083D01*
X1126217Y461667D01*
X1126883Y461500D01*
X1127383Y461583D01*
X1127967Y461917D01*
X1128300Y462250D01*
G01X1131150Y463750D02*
X1133817D01*
X1133567Y464333D01*
X1133150Y464667D01*
X1132567Y464833D01*
X1131983Y464750D01*
X1131483Y464500D01*
X1131150Y463917D01*
X1130983Y463417D01*
Y462917D01*
X1131150Y462417D01*
X1131567Y461917D01*
X1132067Y461583D01*
X1132650Y461500D01*
X1133233Y461667D01*
X1133817Y462167D01*
G01X1139500Y466500D02*
Y461500D01*
G01Y462250D02*
X1139167Y461833D01*
X1138667Y461583D01*
X1138083Y461500D01*
X1137417Y461667D01*
X1136917Y462083D01*
X1136583Y462583D01*
X1136500Y463167D01*
X1136583Y463750D01*
X1136917Y464250D01*
X1137417Y464667D01*
X1138083Y464833D01*
X1138667Y464750D01*
X1139083Y464583D01*
X1139500Y464250D01*
G01X1150200Y461500D02*
Y466500D01*
X1147117Y462917D01*
X1151283D01*
G01X1154800Y466500D02*
X1154133Y466333D01*
X1153633Y465917D01*
X1153300Y465417D01*
X1153050Y464750D01*
X1152967Y464000D01*
X1153050Y463250D01*
X1153300Y462583D01*
X1153633Y462083D01*
X1154133Y461667D01*
X1154800Y461500D01*
X1155467Y461667D01*
X1155967Y462083D01*
X1156300Y462583D01*
X1156550Y463250D01*
X1156633Y464000D01*
X1156550Y464750D01*
X1156300Y465417D01*
X1155967Y465917D01*
X1155467Y466333D01*
X1154800Y466500D01*
G01X1158900Y461333D02*
X1161900Y466500D01*
G01X1158900D02*
X1158400Y466333D01*
X1158150Y466083D01*
X1157983Y465583D01*
X1158150Y465083D01*
X1158400Y464833D01*
X1158900Y464667D01*
X1159400Y464833D01*
X1159650Y465083D01*
X1159817Y465583D01*
X1159650Y466083D01*
X1159400Y466333D01*
X1158900Y466500D01*
G01X1161900Y463167D02*
X1161400Y463000D01*
X1161150Y462750D01*
X1160983Y462250D01*
X1161150Y461750D01*
X1161400Y461500D01*
X1161900Y461333D01*
X1162400Y461500D01*
X1162650Y461750D01*
X1162817Y462250D01*
X1162650Y462750D01*
X1162400Y463000D01*
X1161900Y463167D01*
G01X1169100D02*
X1169933Y464833D01*
X1170767D01*
X1172433Y461500D01*
X1173267D01*
X1174100Y463167D01*
G01X1182800Y461500D02*
Y466500D01*
X1181800Y465500D01*
G01Y461500D02*
X1183800D01*
G01X1188400Y466500D02*
X1187733Y466333D01*
X1187233Y465917D01*
X1186900Y465417D01*
X1186650Y464750D01*
X1186567Y464000D01*
X1186650Y463250D01*
X1186900Y462583D01*
X1187233Y462083D01*
X1187733Y461667D01*
X1188400Y461500D01*
X1189067Y461667D01*
X1189567Y462083D01*
X1189900Y462583D01*
X1190150Y463250D01*
X1190233Y464000D01*
X1190150Y464750D01*
X1189900Y465417D01*
X1189567Y465917D01*
X1189067Y466333D01*
X1188400Y466500D01*
G01X1194000D02*
X1193333Y466333D01*
X1192833Y465917D01*
X1192500Y465417D01*
X1192250Y464750D01*
X1192167Y464000D01*
X1192250Y463250D01*
X1192500Y462583D01*
X1192833Y462083D01*
X1193333Y461667D01*
X1194000Y461500D01*
X1194667Y461667D01*
X1195167Y462083D01*
X1195500Y462583D01*
X1195750Y463250D01*
X1195833Y464000D01*
X1195750Y464750D01*
X1195500Y465417D01*
X1195167Y465917D01*
X1194667Y466333D01*
X1194000Y466500D01*
G01X1198100Y461333D02*
X1201100Y466500D01*
G01X1198100D02*
X1197600Y466333D01*
X1197350Y466083D01*
X1197183Y465583D01*
X1197350Y465083D01*
X1197600Y464833D01*
X1198100Y464667D01*
X1198600Y464833D01*
X1198850Y465083D01*
X1199017Y465583D01*
X1198850Y466083D01*
X1198600Y466333D01*
X1198100Y466500D01*
G01X1201100Y463167D02*
X1200600Y463000D01*
X1200350Y462750D01*
X1200183Y462250D01*
X1200350Y461750D01*
X1200600Y461500D01*
X1201100Y461333D01*
X1201600Y461500D01*
X1201850Y461750D01*
X1202017Y462250D01*
X1201850Y462750D01*
X1201600Y463000D01*
X1201100Y463167D01*
G01X1209550Y462083D02*
X1209967Y461750D01*
X1210550Y461500D01*
X1211050D01*
X1211550Y461667D01*
X1211883Y461917D01*
X1212050Y462250D01*
X1211967Y462750D01*
X1211633Y463000D01*
X1210133Y463500D01*
X1209800Y464083D01*
X1209967Y464500D01*
X1210300Y464750D01*
X1210800Y464833D01*
X1211300Y464750D01*
X1211800Y464500D01*
G01X1216400Y461500D02*
X1215900Y461583D01*
X1215400Y461917D01*
X1215067Y462500D01*
X1214900Y463167D01*
X1215067Y463833D01*
X1215400Y464417D01*
X1215900Y464750D01*
X1216400Y464833D01*
X1216900Y464750D01*
X1217400Y464417D01*
X1217733Y463833D01*
X1217817Y463167D01*
X1217733Y462500D01*
X1217400Y461917D01*
X1216900Y461583D01*
X1216400Y461500D01*
G01X1222000D02*
Y466500D01*
G01X1229100D02*
Y461500D01*
G01Y462250D02*
X1228767Y461833D01*
X1228267Y461583D01*
X1227683Y461500D01*
X1227017Y461667D01*
X1226517Y462083D01*
X1226183Y462583D01*
X1226100Y463167D01*
X1226183Y463750D01*
X1226517Y464250D01*
X1227017Y464667D01*
X1227683Y464833D01*
X1228267Y464750D01*
X1228683Y464583D01*
X1229100Y464250D01*
G01X1231950Y463750D02*
X1234617D01*
X1234367Y464333D01*
X1233950Y464667D01*
X1233367Y464833D01*
X1232783Y464750D01*
X1232283Y464500D01*
X1231950Y463917D01*
X1231783Y463417D01*
Y462917D01*
X1231950Y462417D01*
X1232367Y461917D01*
X1232867Y461583D01*
X1233450Y461500D01*
X1234033Y461667D01*
X1234617Y462167D01*
G01X1237633Y461500D02*
Y464833D01*
G01Y464167D02*
X1238050Y464500D01*
X1238467Y464750D01*
X1239050Y464833D01*
X1239467Y464750D01*
X1239967Y464500D01*
G01X1247500Y461500D02*
Y464833D01*
G01Y463917D02*
X1247750Y464333D01*
X1248167Y464667D01*
X1248750Y464833D01*
X1249333Y464667D01*
X1249750Y464333D01*
X1250000Y463917D01*
Y461500D01*
G01Y463917D02*
X1250250Y464333D01*
X1250667Y464667D01*
X1251250Y464833D01*
X1251833Y464667D01*
X1252250Y464333D01*
X1252500Y463833D01*
Y461500D01*
G01X1257100D02*
Y464833D01*
G01Y464250D02*
X1256767Y464583D01*
X1256267Y464750D01*
X1255683Y464833D01*
X1255100Y464667D01*
X1254600Y464333D01*
X1254267Y463833D01*
X1254100Y463167D01*
X1254267Y462500D01*
X1254600Y462000D01*
X1255100Y461667D01*
X1255683Y461500D01*
X1256267Y461583D01*
X1256767Y461833D01*
X1257100Y462167D01*
G01X1259950Y462083D02*
X1260367Y461750D01*
X1260950Y461500D01*
X1261450D01*
X1261950Y461667D01*
X1262283Y461917D01*
X1262450Y462250D01*
X1262367Y462750D01*
X1262033Y463000D01*
X1260533Y463500D01*
X1260200Y464083D01*
X1260367Y464500D01*
X1260700Y464750D01*
X1261200Y464833D01*
X1261700Y464750D01*
X1262200Y464500D01*
G01X1265383Y461500D02*
Y466500D01*
G01X1268050Y464833D02*
X1265383Y462917D01*
G01X1266467Y463667D02*
X1268217Y461500D01*
G01X1046500Y485833D02*
X1048000Y482500D01*
X1049500Y485833D01*
G01X1053600D02*
Y482500D01*
G01Y487167D02*
X1053433Y487250D01*
Y487417D01*
X1053600Y487500D01*
X1053767Y487417D01*
Y487250D01*
X1053600Y487167D01*
G01X1060700Y482500D02*
Y485833D01*
G01Y485250D02*
X1060367Y485583D01*
X1059867Y485750D01*
X1059283Y485833D01*
X1058700Y485667D01*
X1058200Y485333D01*
X1057867Y484833D01*
X1057700Y484167D01*
X1057867Y483500D01*
X1058200Y483000D01*
X1058700Y482667D01*
X1059283Y482500D01*
X1059867Y482583D01*
X1060367Y482833D01*
X1060700Y483167D01*
G01X1069150Y483083D02*
X1069567Y482750D01*
X1070150Y482500D01*
X1070650D01*
X1071150Y482667D01*
X1071483Y482917D01*
X1071650Y483250D01*
X1071567Y483750D01*
X1071233Y484000D01*
X1069733Y484500D01*
X1069400Y485083D01*
X1069567Y485500D01*
X1069900Y485750D01*
X1070400Y485833D01*
X1070900Y485750D01*
X1071400Y485500D01*
G01X1074583Y482500D02*
Y487500D01*
G01Y485083D02*
X1075000Y485500D01*
X1075417Y485750D01*
X1076083Y485833D01*
X1076583Y485750D01*
X1077167Y485417D01*
X1077417Y484917D01*
Y482500D01*
G01X1083100D02*
Y485833D01*
G01Y485250D02*
X1082767Y485583D01*
X1082267Y485750D01*
X1081683Y485833D01*
X1081100Y485667D01*
X1080600Y485333D01*
X1080267Y484833D01*
X1080100Y484167D01*
X1080267Y483500D01*
X1080600Y483000D01*
X1081100Y482667D01*
X1081683Y482500D01*
X1082267Y482583D01*
X1082767Y482833D01*
X1083100Y483167D01*
G01X1087200Y482500D02*
Y487500D01*
G01X1092800Y482500D02*
Y487500D01*
G01X1102500Y482500D02*
Y487500D01*
G01Y485000D02*
X1102917Y485500D01*
X1103417Y485750D01*
X1103917Y485833D01*
X1104667Y485667D01*
X1105167Y485333D01*
X1105500Y484750D01*
Y484083D01*
X1105333Y483417D01*
X1105000Y482917D01*
X1104417Y482583D01*
X1103917Y482500D01*
X1103417Y482583D01*
X1102917Y482833D01*
X1102500Y483250D01*
G01X1108350Y484750D02*
X1111017D01*
X1110767Y485333D01*
X1110350Y485667D01*
X1109767Y485833D01*
X1109183Y485750D01*
X1108683Y485500D01*
X1108350Y484917D01*
X1108183Y484417D01*
Y483917D01*
X1108350Y483417D01*
X1108767Y482917D01*
X1109267Y482583D01*
X1109850Y482500D01*
X1110433Y482667D01*
X1111017Y483167D01*
G01X1118717Y485833D02*
X1119717Y482500D01*
X1120800Y485833D01*
X1121883Y482500D01*
X1122883Y485833D01*
G01X1126400D02*
Y482500D01*
G01Y487167D02*
X1126233Y487250D01*
Y487417D01*
X1126400Y487500D01*
X1126567Y487417D01*
Y487250D01*
X1126400Y487167D01*
G01X1132000Y487500D02*
Y482500D01*
G01X1130833Y485833D02*
X1133167D01*
G01X1136183Y482500D02*
Y487500D01*
G01Y485083D02*
X1136600Y485500D01*
X1137017Y485750D01*
X1137683Y485833D01*
X1138183Y485750D01*
X1138767Y485417D01*
X1139017Y484917D01*
Y482500D01*
G01X1150467D02*
X1147133Y484167D01*
X1150467Y485833D01*
G01X1160000Y482500D02*
X1160583Y482583D01*
X1161250Y482833D01*
X1161667Y483250D01*
X1161833Y483833D01*
X1161667Y484417D01*
X1161167Y484917D01*
X1160417Y485167D01*
X1159583D01*
X1159083Y485333D01*
X1158667Y485750D01*
X1158500Y486333D01*
X1158750Y486917D01*
X1159333Y487333D01*
X1160000Y487500D01*
X1160667Y487333D01*
X1161250Y486917D01*
X1161500Y486333D01*
X1161333Y485750D01*
X1160917Y485333D01*
X1160417Y485167D01*
X1159583D01*
X1158833Y484917D01*
X1158333Y484417D01*
X1158167Y483833D01*
X1158333Y483250D01*
X1158750Y482833D01*
X1159417Y482583D01*
X1160000Y482500D01*
G01X1165600Y487500D02*
X1164933Y487333D01*
X1164433Y486917D01*
X1164100Y486417D01*
X1163850Y485750D01*
X1163767Y485000D01*
X1163850Y484250D01*
X1164100Y483583D01*
X1164433Y483083D01*
X1164933Y482667D01*
X1165600Y482500D01*
X1166267Y482667D01*
X1166767Y483083D01*
X1167100Y483583D01*
X1167350Y484250D01*
X1167433Y485000D01*
X1167350Y485750D01*
X1167100Y486417D01*
X1166767Y486917D01*
X1166267Y487333D01*
X1165600Y487500D01*
G01X1175300Y482333D02*
X1178300Y487500D01*
G01X1175300D02*
X1174800Y487333D01*
X1174550Y487083D01*
X1174383Y486583D01*
X1174550Y486083D01*
X1174800Y485833D01*
X1175300Y485667D01*
X1175800Y485833D01*
X1176050Y486083D01*
X1176217Y486583D01*
X1176050Y487083D01*
X1175800Y487333D01*
X1175300Y487500D01*
G01X1178300Y484167D02*
X1177800Y484000D01*
X1177550Y483750D01*
X1177383Y483250D01*
X1177550Y482750D01*
X1177800Y482500D01*
X1178300Y482333D01*
X1178800Y482500D01*
X1179050Y482750D01*
X1179217Y483250D01*
X1179050Y483750D01*
X1178800Y484000D01*
X1178300Y484167D01*
G01X1186750Y483083D02*
X1187167Y482750D01*
X1187750Y482500D01*
X1188250D01*
X1188750Y482667D01*
X1189083Y482917D01*
X1189250Y483250D01*
X1189167Y483750D01*
X1188833Y484000D01*
X1187333Y484500D01*
X1187000Y485083D01*
X1187167Y485500D01*
X1187500Y485750D01*
X1188000Y485833D01*
X1188500Y485750D01*
X1189000Y485500D01*
G01X1193600Y482500D02*
X1193100Y482583D01*
X1192600Y482917D01*
X1192267Y483500D01*
X1192100Y484167D01*
X1192267Y484833D01*
X1192600Y485417D01*
X1193100Y485750D01*
X1193600Y485833D01*
X1194100Y485750D01*
X1194600Y485417D01*
X1194933Y484833D01*
X1195017Y484167D01*
X1194933Y483500D01*
X1194600Y482917D01*
X1194100Y482583D01*
X1193600Y482500D01*
G01X1199200D02*
Y487500D01*
G01X1206300D02*
Y482500D01*
G01Y483250D02*
X1205967Y482833D01*
X1205467Y482583D01*
X1204883Y482500D01*
X1204217Y482667D01*
X1203717Y483083D01*
X1203383Y483583D01*
X1203300Y484167D01*
X1203383Y484750D01*
X1203717Y485250D01*
X1204217Y485667D01*
X1204883Y485833D01*
X1205467Y485750D01*
X1205883Y485583D01*
X1206300Y485250D01*
G01X1209150Y484750D02*
X1211817D01*
X1211567Y485333D01*
X1211150Y485667D01*
X1210567Y485833D01*
X1209983Y485750D01*
X1209483Y485500D01*
X1209150Y484917D01*
X1208983Y484417D01*
Y483917D01*
X1209150Y483417D01*
X1209567Y482917D01*
X1210067Y482583D01*
X1210650Y482500D01*
X1211233Y482667D01*
X1211817Y483167D01*
G01X1214833Y482500D02*
Y485833D01*
G01Y485167D02*
X1215250Y485500D01*
X1215667Y485750D01*
X1216250Y485833D01*
X1216667Y485750D01*
X1217167Y485500D01*
G01X1224700Y482500D02*
Y485833D01*
G01Y484917D02*
X1224950Y485333D01*
X1225367Y485667D01*
X1225950Y485833D01*
X1226533Y485667D01*
X1226950Y485333D01*
X1227200Y484917D01*
Y482500D01*
G01Y484917D02*
X1227450Y485333D01*
X1227867Y485667D01*
X1228450Y485833D01*
X1229033Y485667D01*
X1229450Y485333D01*
X1229700Y484833D01*
Y482500D01*
G01X1234300D02*
Y485833D01*
G01Y485250D02*
X1233967Y485583D01*
X1233467Y485750D01*
X1232883Y485833D01*
X1232300Y485667D01*
X1231800Y485333D01*
X1231467Y484833D01*
X1231300Y484167D01*
X1231467Y483500D01*
X1231800Y483000D01*
X1232300Y482667D01*
X1232883Y482500D01*
X1233467Y482583D01*
X1233967Y482833D01*
X1234300Y483167D01*
G01X1237150Y483083D02*
X1237567Y482750D01*
X1238150Y482500D01*
X1238650D01*
X1239150Y482667D01*
X1239483Y482917D01*
X1239650Y483250D01*
X1239567Y483750D01*
X1239233Y484000D01*
X1237733Y484500D01*
X1237400Y485083D01*
X1237567Y485500D01*
X1237900Y485750D01*
X1238400Y485833D01*
X1238900Y485750D01*
X1239400Y485500D01*
G01X1242583Y482500D02*
Y487500D01*
G01X1245250Y485833D02*
X1242583Y483917D01*
G01X1243667Y484667D02*
X1245417Y482500D01*
G01X1035500Y491500D02*
Y496500D01*
G01Y494000D02*
X1035917Y494500D01*
X1036417Y494750D01*
X1036917Y494833D01*
X1037667Y494667D01*
X1038167Y494333D01*
X1038500Y493750D01*
Y493083D01*
X1038333Y492417D01*
X1038000Y491917D01*
X1037417Y491583D01*
X1036917Y491500D01*
X1036417Y491583D01*
X1035917Y491833D01*
X1035500Y492250D01*
G01X1042600Y491333D02*
X1042433Y491417D01*
Y491583D01*
X1042600Y491667D01*
X1042767Y491583D01*
Y491417D01*
X1042600Y491333D01*
G01X1048867Y494167D02*
X1049200Y494417D01*
X1049450Y494833D01*
X1049617Y495417D01*
X1049450Y495917D01*
X1049117Y496250D01*
X1048533Y496500D01*
X1046283D01*
Y491500D01*
X1049033D01*
X1049617Y491833D01*
X1049950Y492333D01*
X1050117Y492917D01*
X1049950Y493500D01*
X1049450Y494000D01*
X1048867Y494167D01*
X1046283D01*
G01X1053800Y491500D02*
X1053300Y491583D01*
X1052800Y491917D01*
X1052467Y492500D01*
X1052300Y493167D01*
X1052467Y493833D01*
X1052800Y494417D01*
X1053300Y494750D01*
X1053800Y494833D01*
X1054300Y494750D01*
X1054800Y494417D01*
X1055133Y493833D01*
X1055217Y493167D01*
X1055133Y492500D01*
X1054800Y491917D01*
X1054300Y491583D01*
X1053800Y491500D01*
G01X1060900D02*
Y494833D01*
G01Y494250D02*
X1060567Y494583D01*
X1060067Y494750D01*
X1059483Y494833D01*
X1058900Y494667D01*
X1058400Y494333D01*
X1058067Y493833D01*
X1057900Y493167D01*
X1058067Y492500D01*
X1058400Y492000D01*
X1058900Y491667D01*
X1059483Y491500D01*
X1060067Y491583D01*
X1060567Y491833D01*
X1060900Y492167D01*
G01X1063833Y491500D02*
Y494833D01*
G01Y494167D02*
X1064250Y494500D01*
X1064667Y494750D01*
X1065250Y494833D01*
X1065667Y494750D01*
X1066167Y494500D01*
G01X1072100Y496500D02*
Y491500D01*
G01Y492250D02*
X1071767Y491833D01*
X1071267Y491583D01*
X1070683Y491500D01*
X1070017Y491667D01*
X1069517Y492083D01*
X1069183Y492583D01*
X1069100Y493167D01*
X1069183Y493750D01*
X1069517Y494250D01*
X1070017Y494667D01*
X1070683Y494833D01*
X1071267Y494750D01*
X1071683Y494583D01*
X1072100Y494250D01*
G01X1081800Y496500D02*
Y491500D01*
G01X1080633Y494833D02*
X1082967D01*
G01X1085983Y491500D02*
Y496500D01*
G01Y494083D02*
X1086400Y494500D01*
X1086817Y494750D01*
X1087483Y494833D01*
X1087983Y494750D01*
X1088567Y494417D01*
X1088817Y493917D01*
Y491500D01*
G01X1093000Y494833D02*
Y491500D01*
G01Y496167D02*
X1092833Y496250D01*
Y496417D01*
X1093000Y496500D01*
X1093167Y496417D01*
Y496250D01*
X1093000Y496167D01*
G01X1099933Y494417D02*
X1099350Y494750D01*
X1098850Y494833D01*
X1098183Y494667D01*
X1097683Y494333D01*
X1097350Y493750D01*
X1097267Y493167D01*
X1097350Y492583D01*
X1097683Y492083D01*
X1098183Y491667D01*
X1098850Y491500D01*
X1099433Y491667D01*
X1099933Y492000D01*
G01X1102783Y491500D02*
Y496500D01*
G01X1105450Y494833D02*
X1102783Y492917D01*
G01X1103867Y493667D02*
X1105617Y491500D01*
G01X1108383D02*
Y494833D01*
G01Y494000D02*
X1108717Y494417D01*
X1109217Y494750D01*
X1109883Y494833D01*
X1110467Y494750D01*
X1110967Y494417D01*
X1111217Y493833D01*
Y491500D01*
G01X1114150Y493750D02*
X1116817D01*
X1116567Y494333D01*
X1116150Y494667D01*
X1115567Y494833D01*
X1114983Y494750D01*
X1114483Y494500D01*
X1114150Y493917D01*
X1113983Y493417D01*
Y492917D01*
X1114150Y492417D01*
X1114567Y491917D01*
X1115067Y491583D01*
X1115650Y491500D01*
X1116233Y491667D01*
X1116817Y492167D01*
G01X1119750Y492083D02*
X1120167Y491750D01*
X1120750Y491500D01*
X1121250D01*
X1121750Y491667D01*
X1122083Y491917D01*
X1122250Y492250D01*
X1122167Y492750D01*
X1121833Y493000D01*
X1120333Y493500D01*
X1120000Y494083D01*
X1120167Y494500D01*
X1120500Y494750D01*
X1121000Y494833D01*
X1121500Y494750D01*
X1122000Y494500D01*
G01X1125350Y492083D02*
X1125767Y491750D01*
X1126350Y491500D01*
X1126850D01*
X1127350Y491667D01*
X1127683Y491917D01*
X1127850Y492250D01*
X1127767Y492750D01*
X1127433Y493000D01*
X1125933Y493500D01*
X1125600Y494083D01*
X1125767Y494500D01*
X1126100Y494750D01*
X1126600Y494833D01*
X1127100Y494750D01*
X1127600Y494500D01*
G01X1139467Y491500D02*
X1136133Y493167D01*
X1139467Y494833D01*
G01X1149000Y496500D02*
X1148333Y496333D01*
X1147833Y495917D01*
X1147500Y495417D01*
X1147250Y494750D01*
X1147167Y494000D01*
X1147250Y493250D01*
X1147500Y492583D01*
X1147833Y492083D01*
X1148333Y491667D01*
X1149000Y491500D01*
X1149667Y491667D01*
X1150167Y492083D01*
X1150500Y492583D01*
X1150750Y493250D01*
X1150833Y494000D01*
X1150750Y494750D01*
X1150500Y495417D01*
X1150167Y495917D01*
X1149667Y496333D01*
X1149000Y496500D01*
G01X1154600Y491333D02*
X1154433Y491417D01*
Y491583D01*
X1154600Y491667D01*
X1154767Y491583D01*
Y491417D01*
X1154600Y491333D01*
G01X1158783Y492083D02*
X1159367Y491667D01*
X1160033Y491500D01*
X1160700Y491667D01*
X1161283Y492167D01*
X1161700Y492917D01*
X1161867Y493667D01*
Y494583D01*
X1161700Y495333D01*
X1161283Y496000D01*
X1160783Y496333D01*
X1160200Y496500D01*
X1159533Y496333D01*
X1159033Y496000D01*
X1158700Y495500D01*
X1158533Y494833D01*
X1158700Y494250D01*
X1159117Y493667D01*
X1159617Y493333D01*
X1160200Y493250D01*
X1160867Y493417D01*
X1161367Y493833D01*
X1161867Y494583D01*
G01X1163300Y491500D02*
Y494833D01*
G01Y493917D02*
X1163550Y494333D01*
X1163967Y494667D01*
X1164550Y494833D01*
X1165133Y494667D01*
X1165550Y494333D01*
X1165800Y493917D01*
Y491500D01*
G01Y493917D02*
X1166050Y494333D01*
X1166467Y494667D01*
X1167050Y494833D01*
X1167633Y494667D01*
X1168050Y494333D01*
X1168300Y493833D01*
Y491500D01*
G01X1168900D02*
Y494833D01*
G01Y493917D02*
X1169150Y494333D01*
X1169567Y494667D01*
X1170150Y494833D01*
X1170733Y494667D01*
X1171150Y494333D01*
X1171400Y493917D01*
Y491500D01*
G01Y493917D02*
X1171650Y494333D01*
X1172067Y494667D01*
X1172650Y494833D01*
X1173233Y494667D01*
X1173650Y494333D01*
X1173900Y493833D01*
Y491500D01*
G01X1177000Y491333D02*
X1176833Y491417D01*
Y491583D01*
X1177000Y491667D01*
X1177167Y491583D01*
Y491417D01*
X1177000Y491333D01*
G01Y493583D02*
X1176833Y493667D01*
Y493833D01*
X1177000Y493917D01*
X1177167Y493833D01*
Y493667D01*
X1177000Y493583D01*
G01X1045500Y504833D02*
X1047000Y501500D01*
X1048500Y504833D01*
G01X1052600D02*
Y501500D01*
G01Y506167D02*
X1052433Y506250D01*
Y506417D01*
X1052600Y506500D01*
X1052767Y506417D01*
Y506250D01*
X1052600Y506167D01*
G01X1059700Y501500D02*
Y504833D01*
G01Y504250D02*
X1059367Y504583D01*
X1058867Y504750D01*
X1058283Y504833D01*
X1057700Y504667D01*
X1057200Y504333D01*
X1056867Y503833D01*
X1056700Y503167D01*
X1056867Y502500D01*
X1057200Y502000D01*
X1057700Y501667D01*
X1058283Y501500D01*
X1058867Y501583D01*
X1059367Y501833D01*
X1059700Y502167D01*
G01X1068150Y502083D02*
X1068567Y501750D01*
X1069150Y501500D01*
X1069650D01*
X1070150Y501667D01*
X1070483Y501917D01*
X1070650Y502250D01*
X1070567Y502750D01*
X1070233Y503000D01*
X1068733Y503500D01*
X1068400Y504083D01*
X1068567Y504500D01*
X1068900Y504750D01*
X1069400Y504833D01*
X1069900Y504750D01*
X1070400Y504500D01*
G01X1073583Y501500D02*
Y506500D01*
G01Y504083D02*
X1074000Y504500D01*
X1074417Y504750D01*
X1075083Y504833D01*
X1075583Y504750D01*
X1076167Y504417D01*
X1076417Y503917D01*
Y501500D01*
G01X1082100D02*
Y504833D01*
G01Y504250D02*
X1081767Y504583D01*
X1081267Y504750D01*
X1080683Y504833D01*
X1080100Y504667D01*
X1079600Y504333D01*
X1079267Y503833D01*
X1079100Y503167D01*
X1079267Y502500D01*
X1079600Y502000D01*
X1080100Y501667D01*
X1080683Y501500D01*
X1081267Y501583D01*
X1081767Y501833D01*
X1082100Y502167D01*
G01X1086200Y501500D02*
Y506500D01*
G01X1091800Y501500D02*
Y506500D01*
G01X1101500Y501500D02*
Y506500D01*
G01Y504000D02*
X1101917Y504500D01*
X1102417Y504750D01*
X1102917Y504833D01*
X1103667Y504667D01*
X1104167Y504333D01*
X1104500Y503750D01*
Y503083D01*
X1104333Y502417D01*
X1104000Y501917D01*
X1103417Y501583D01*
X1102917Y501500D01*
X1102417Y501583D01*
X1101917Y501833D01*
X1101500Y502250D01*
G01X1107350Y503750D02*
X1110017D01*
X1109767Y504333D01*
X1109350Y504667D01*
X1108767Y504833D01*
X1108183Y504750D01*
X1107683Y504500D01*
X1107350Y503917D01*
X1107183Y503417D01*
Y502917D01*
X1107350Y502417D01*
X1107767Y501917D01*
X1108267Y501583D01*
X1108850Y501500D01*
X1109433Y501667D01*
X1110017Y502167D01*
G01X1118300Y499833D02*
Y504833D01*
G01Y504083D02*
X1118717Y504500D01*
X1119133Y504750D01*
X1119800Y504833D01*
X1120383Y504750D01*
X1120967Y504333D01*
X1121217Y503750D01*
X1121300Y503167D01*
X1121217Y502583D01*
X1120967Y502000D01*
X1120467Y501667D01*
X1119800Y501500D01*
X1119217Y501583D01*
X1118633Y501833D01*
X1118300Y502167D01*
G01X1125400Y501500D02*
Y506500D01*
G01X1129583Y504833D02*
Y502500D01*
X1129917Y501917D01*
X1130417Y501583D01*
X1131000Y501500D01*
X1131583Y501583D01*
X1132083Y501917D01*
X1132417Y502500D01*
G01Y501500D02*
Y504833D01*
G01X1135433Y500250D02*
X1136017Y499917D01*
X1136683Y499833D01*
X1137267Y499917D01*
X1137767Y500333D01*
X1138100Y500917D01*
Y504833D01*
G01Y504167D02*
X1137767Y504500D01*
X1137267Y504750D01*
X1136683Y504833D01*
X1136017Y504667D01*
X1135600Y504333D01*
X1135267Y503750D01*
X1135100Y503167D01*
X1135183Y502667D01*
X1135517Y502083D01*
X1136017Y501667D01*
X1136683Y501500D01*
X1137183Y501583D01*
X1137767Y501917D01*
X1138100Y502250D01*
G01X1141033Y500250D02*
X1141617Y499917D01*
X1142283Y499833D01*
X1142867Y499917D01*
X1143367Y500333D01*
X1143700Y500917D01*
Y504833D01*
G01Y504167D02*
X1143367Y504500D01*
X1142867Y504750D01*
X1142283Y504833D01*
X1141617Y504667D01*
X1141200Y504333D01*
X1140867Y503750D01*
X1140700Y503167D01*
X1140783Y502667D01*
X1141117Y502083D01*
X1141617Y501667D01*
X1142283Y501500D01*
X1142783Y501583D01*
X1143367Y501917D01*
X1143700Y502250D01*
G01X1146550Y503750D02*
X1149217D01*
X1148967Y504333D01*
X1148550Y504667D01*
X1147967Y504833D01*
X1147383Y504750D01*
X1146883Y504500D01*
X1146550Y503917D01*
X1146383Y503417D01*
Y502917D01*
X1146550Y502417D01*
X1146967Y501917D01*
X1147467Y501583D01*
X1148050Y501500D01*
X1148633Y501667D01*
X1149217Y502167D01*
G01X1154900Y506500D02*
Y501500D01*
G01Y502250D02*
X1154567Y501833D01*
X1154067Y501583D01*
X1153483Y501500D01*
X1152817Y501667D01*
X1152317Y502083D01*
X1151983Y502583D01*
X1151900Y503167D01*
X1151983Y503750D01*
X1152317Y504250D01*
X1152817Y504667D01*
X1153483Y504833D01*
X1154067Y504750D01*
X1154483Y504583D01*
X1154900Y504250D01*
G01X1162517Y504833D02*
X1163517Y501500D01*
X1164600Y504833D01*
X1165683Y501500D01*
X1166683Y504833D01*
G01X1170200D02*
Y501500D01*
G01Y506167D02*
X1170033Y506250D01*
Y506417D01*
X1170200Y506500D01*
X1170367Y506417D01*
Y506250D01*
X1170200Y506167D01*
G01X1175800Y506500D02*
Y501500D01*
G01X1174633Y504833D02*
X1176967D01*
G01X1179983Y501500D02*
Y506500D01*
G01Y504083D02*
X1180400Y504500D01*
X1180817Y504750D01*
X1181483Y504833D01*
X1181983Y504750D01*
X1182567Y504417D01*
X1182817Y503917D01*
Y501500D01*
G01X1194267D02*
X1190933Y503167D01*
X1194267Y504833D01*
G01X1201967Y502250D02*
X1202467Y501833D01*
X1203050Y501583D01*
X1203800Y501500D01*
X1204550Y501667D01*
X1205133Y502000D01*
X1205550Y502583D01*
X1205633Y503250D01*
X1205467Y503917D01*
X1205050Y504333D01*
X1204467Y504667D01*
X1203883Y504750D01*
X1203300Y504667D01*
X1202550Y504333D01*
X1202800Y506500D01*
X1205050D01*
G01X1209400D02*
X1208733Y506333D01*
X1208233Y505917D01*
X1207900Y505417D01*
X1207650Y504750D01*
X1207567Y504000D01*
X1207650Y503250D01*
X1207900Y502583D01*
X1208233Y502083D01*
X1208733Y501667D01*
X1209400Y501500D01*
X1210067Y501667D01*
X1210567Y502083D01*
X1210900Y502583D01*
X1211150Y503250D01*
X1211233Y504000D01*
X1211150Y504750D01*
X1210900Y505417D01*
X1210567Y505917D01*
X1210067Y506333D01*
X1209400Y506500D01*
G01X1219100Y501333D02*
X1222100Y506500D01*
G01X1219100D02*
X1218600Y506333D01*
X1218350Y506083D01*
X1218183Y505583D01*
X1218350Y505083D01*
X1218600Y504833D01*
X1219100Y504667D01*
X1219600Y504833D01*
X1219850Y505083D01*
X1220017Y505583D01*
X1219850Y506083D01*
X1219600Y506333D01*
X1219100Y506500D01*
G01X1222100Y503167D02*
X1221600Y503000D01*
X1221350Y502750D01*
X1221183Y502250D01*
X1221350Y501750D01*
X1221600Y501500D01*
X1222100Y501333D01*
X1222600Y501500D01*
X1222850Y501750D01*
X1223017Y502250D01*
X1222850Y502750D01*
X1222600Y503000D01*
X1222100Y503167D01*
G01X1230550Y502083D02*
X1230967Y501750D01*
X1231550Y501500D01*
X1232050D01*
X1232550Y501667D01*
X1232883Y501917D01*
X1233050Y502250D01*
X1232967Y502750D01*
X1232633Y503000D01*
X1231133Y503500D01*
X1230800Y504083D01*
X1230967Y504500D01*
X1231300Y504750D01*
X1231800Y504833D01*
X1232300Y504750D01*
X1232800Y504500D01*
G01X1237400Y501500D02*
X1236900Y501583D01*
X1236400Y501917D01*
X1236067Y502500D01*
X1235900Y503167D01*
X1236067Y503833D01*
X1236400Y504417D01*
X1236900Y504750D01*
X1237400Y504833D01*
X1237900Y504750D01*
X1238400Y504417D01*
X1238733Y503833D01*
X1238817Y503167D01*
X1238733Y502500D01*
X1238400Y501917D01*
X1237900Y501583D01*
X1237400Y501500D01*
G01X1243000D02*
Y506500D01*
G01X1250100D02*
Y501500D01*
G01Y502250D02*
X1249767Y501833D01*
X1249267Y501583D01*
X1248683Y501500D01*
X1248017Y501667D01*
X1247517Y502083D01*
X1247183Y502583D01*
X1247100Y503167D01*
X1247183Y503750D01*
X1247517Y504250D01*
X1248017Y504667D01*
X1248683Y504833D01*
X1249267Y504750D01*
X1249683Y504583D01*
X1250100Y504250D01*
G01X1252950Y503750D02*
X1255617D01*
X1255367Y504333D01*
X1254950Y504667D01*
X1254367Y504833D01*
X1253783Y504750D01*
X1253283Y504500D01*
X1252950Y503917D01*
X1252783Y503417D01*
Y502917D01*
X1252950Y502417D01*
X1253367Y501917D01*
X1253867Y501583D01*
X1254450Y501500D01*
X1255033Y501667D01*
X1255617Y502167D01*
G01X1258633Y501500D02*
Y504833D01*
G01Y504167D02*
X1259050Y504500D01*
X1259467Y504750D01*
X1260050Y504833D01*
X1260467Y504750D01*
X1260967Y504500D01*
G01X1268500Y501500D02*
Y504833D01*
G01Y503917D02*
X1268750Y504333D01*
X1269167Y504667D01*
X1269750Y504833D01*
X1270333Y504667D01*
X1270750Y504333D01*
X1271000Y503917D01*
Y501500D01*
G01Y503917D02*
X1271250Y504333D01*
X1271667Y504667D01*
X1272250Y504833D01*
X1272833Y504667D01*
X1273250Y504333D01*
X1273500Y503833D01*
Y501500D01*
G01X1278100D02*
Y504833D01*
G01Y504250D02*
X1277767Y504583D01*
X1277267Y504750D01*
X1276683Y504833D01*
X1276100Y504667D01*
X1275600Y504333D01*
X1275267Y503833D01*
X1275100Y503167D01*
X1275267Y502500D01*
X1275600Y502000D01*
X1276100Y501667D01*
X1276683Y501500D01*
X1277267Y501583D01*
X1277767Y501833D01*
X1278100Y502167D01*
G01X1280950Y502083D02*
X1281367Y501750D01*
X1281950Y501500D01*
X1282450D01*
X1282950Y501667D01*
X1283283Y501917D01*
X1283450Y502250D01*
X1283367Y502750D01*
X1283033Y503000D01*
X1281533Y503500D01*
X1281200Y504083D01*
X1281367Y504500D01*
X1281700Y504750D01*
X1282200Y504833D01*
X1282700Y504750D01*
X1283200Y504500D01*
G01X1286383Y501500D02*
Y506500D01*
G01X1289050Y504833D02*
X1286383Y502917D01*
G01X1287467Y503667D02*
X1289217Y501500D01*
G01X1293233Y500583D02*
X1293567Y501667D01*
G01X1038500Y510500D02*
Y513833D01*
G01Y513250D02*
X1038167Y513583D01*
X1037667Y513750D01*
X1037083Y513833D01*
X1036500Y513667D01*
X1036000Y513333D01*
X1035667Y512833D01*
X1035500Y512167D01*
X1035667Y511500D01*
X1036000Y511000D01*
X1036500Y510667D01*
X1037083Y510500D01*
X1037667Y510583D01*
X1038167Y510833D01*
X1038500Y511167D01*
G01X1042600Y510333D02*
X1042433Y510417D01*
Y510583D01*
X1042600Y510667D01*
X1042767Y510583D01*
Y510417D01*
X1042600Y510333D01*
G01X1048867Y513167D02*
X1049200Y513417D01*
X1049450Y513833D01*
X1049617Y514417D01*
X1049450Y514917D01*
X1049117Y515250D01*
X1048533Y515500D01*
X1046283D01*
Y510500D01*
X1049033D01*
X1049617Y510833D01*
X1049950Y511333D01*
X1050117Y511917D01*
X1049950Y512500D01*
X1049450Y513000D01*
X1048867Y513167D01*
X1046283D01*
G01X1053800Y510500D02*
X1053300Y510583D01*
X1052800Y510917D01*
X1052467Y511500D01*
X1052300Y512167D01*
X1052467Y512833D01*
X1052800Y513417D01*
X1053300Y513750D01*
X1053800Y513833D01*
X1054300Y513750D01*
X1054800Y513417D01*
X1055133Y512833D01*
X1055217Y512167D01*
X1055133Y511500D01*
X1054800Y510917D01*
X1054300Y510583D01*
X1053800Y510500D01*
G01X1060900D02*
Y513833D01*
G01Y513250D02*
X1060567Y513583D01*
X1060067Y513750D01*
X1059483Y513833D01*
X1058900Y513667D01*
X1058400Y513333D01*
X1058067Y512833D01*
X1057900Y512167D01*
X1058067Y511500D01*
X1058400Y511000D01*
X1058900Y510667D01*
X1059483Y510500D01*
X1060067Y510583D01*
X1060567Y510833D01*
X1060900Y511167D01*
G01X1063833Y510500D02*
Y513833D01*
G01Y513167D02*
X1064250Y513500D01*
X1064667Y513750D01*
X1065250Y513833D01*
X1065667Y513750D01*
X1066167Y513500D01*
G01X1072100Y515500D02*
Y510500D01*
G01Y511250D02*
X1071767Y510833D01*
X1071267Y510583D01*
X1070683Y510500D01*
X1070017Y510667D01*
X1069517Y511083D01*
X1069183Y511583D01*
X1069100Y512167D01*
X1069183Y512750D01*
X1069517Y513250D01*
X1070017Y513667D01*
X1070683Y513833D01*
X1071267Y513750D01*
X1071683Y513583D01*
X1072100Y513250D01*
G01X1081800Y515500D02*
Y510500D01*
G01X1080633Y513833D02*
X1082967D01*
G01X1085983Y510500D02*
Y515500D01*
G01Y513083D02*
X1086400Y513500D01*
X1086817Y513750D01*
X1087483Y513833D01*
X1087983Y513750D01*
X1088567Y513417D01*
X1088817Y512917D01*
Y510500D01*
G01X1093000Y513833D02*
Y510500D01*
G01Y515167D02*
X1092833Y515250D01*
Y515417D01*
X1093000Y515500D01*
X1093167Y515417D01*
Y515250D01*
X1093000Y515167D01*
G01X1099933Y513417D02*
X1099350Y513750D01*
X1098850Y513833D01*
X1098183Y513667D01*
X1097683Y513333D01*
X1097350Y512750D01*
X1097267Y512167D01*
X1097350Y511583D01*
X1097683Y511083D01*
X1098183Y510667D01*
X1098850Y510500D01*
X1099433Y510667D01*
X1099933Y511000D01*
G01X1102783Y510500D02*
Y515500D01*
G01X1105450Y513833D02*
X1102783Y511917D01*
G01X1103867Y512667D02*
X1105617Y510500D01*
G01X1108383D02*
Y513833D01*
G01Y513000D02*
X1108717Y513417D01*
X1109217Y513750D01*
X1109883Y513833D01*
X1110467Y513750D01*
X1110967Y513417D01*
X1111217Y512833D01*
Y510500D01*
G01X1114150Y512750D02*
X1116817D01*
X1116567Y513333D01*
X1116150Y513667D01*
X1115567Y513833D01*
X1114983Y513750D01*
X1114483Y513500D01*
X1114150Y512917D01*
X1113983Y512417D01*
Y511917D01*
X1114150Y511417D01*
X1114567Y510917D01*
X1115067Y510583D01*
X1115650Y510500D01*
X1116233Y510667D01*
X1116817Y511167D01*
G01X1119750Y511083D02*
X1120167Y510750D01*
X1120750Y510500D01*
X1121250D01*
X1121750Y510667D01*
X1122083Y510917D01*
X1122250Y511250D01*
X1122167Y511750D01*
X1121833Y512000D01*
X1120333Y512500D01*
X1120000Y513083D01*
X1120167Y513500D01*
X1120500Y513750D01*
X1121000Y513833D01*
X1121500Y513750D01*
X1122000Y513500D01*
G01X1125350Y511083D02*
X1125767Y510750D01*
X1126350Y510500D01*
X1126850D01*
X1127350Y510667D01*
X1127683Y510917D01*
X1127850Y511250D01*
X1127767Y511750D01*
X1127433Y512000D01*
X1125933Y512500D01*
X1125600Y513083D01*
X1125767Y513500D01*
X1126100Y513750D01*
X1126600Y513833D01*
X1127100Y513750D01*
X1127600Y513500D01*
G01X1130533Y510500D02*
X1133867Y512167D01*
X1130533Y513833D01*
G01X1136717Y511417D02*
X1138883D01*
G01Y512917D02*
X1136717D01*
G01X1149000Y515500D02*
X1148333Y515333D01*
X1147833Y514917D01*
X1147500Y514417D01*
X1147250Y513750D01*
X1147167Y513000D01*
X1147250Y512250D01*
X1147500Y511583D01*
X1147833Y511083D01*
X1148333Y510667D01*
X1149000Y510500D01*
X1149667Y510667D01*
X1150167Y511083D01*
X1150500Y511583D01*
X1150750Y512250D01*
X1150833Y513000D01*
X1150750Y513750D01*
X1150500Y514417D01*
X1150167Y514917D01*
X1149667Y515333D01*
X1149000Y515500D01*
G01X1154600Y510333D02*
X1154433Y510417D01*
Y510583D01*
X1154600Y510667D01*
X1154767Y510583D01*
Y510417D01*
X1154600Y510333D01*
G01X1158783Y511083D02*
X1159367Y510667D01*
X1160033Y510500D01*
X1160700Y510667D01*
X1161283Y511167D01*
X1161700Y511917D01*
X1161867Y512667D01*
Y513583D01*
X1161700Y514333D01*
X1161283Y515000D01*
X1160783Y515333D01*
X1160200Y515500D01*
X1159533Y515333D01*
X1159033Y515000D01*
X1158700Y514500D01*
X1158533Y513833D01*
X1158700Y513250D01*
X1159117Y512667D01*
X1159617Y512333D01*
X1160200Y512250D01*
X1160867Y512417D01*
X1161367Y512833D01*
X1161867Y513583D01*
G01X1163300Y510500D02*
Y513833D01*
G01Y512917D02*
X1163550Y513333D01*
X1163967Y513667D01*
X1164550Y513833D01*
X1165133Y513667D01*
X1165550Y513333D01*
X1165800Y512917D01*
Y510500D01*
G01Y512917D02*
X1166050Y513333D01*
X1166467Y513667D01*
X1167050Y513833D01*
X1167633Y513667D01*
X1168050Y513333D01*
X1168300Y512833D01*
Y510500D01*
G01X1171400Y510333D02*
X1171233Y510417D01*
Y510583D01*
X1171400Y510667D01*
X1171567Y510583D01*
Y510417D01*
X1171400Y510333D01*
G01Y512583D02*
X1171233Y512667D01*
Y512833D01*
X1171400Y512917D01*
X1171567Y512833D01*
Y512667D01*
X1171400Y512583D01*
G01X1034250Y520500D02*
Y525500D01*
G01X1037750D02*
Y520500D01*
G01Y523000D02*
X1034250D01*
G01X1043100Y520500D02*
Y523833D01*
G01Y523250D02*
X1042767Y523583D01*
X1042267Y523750D01*
X1041683Y523833D01*
X1041100Y523667D01*
X1040600Y523333D01*
X1040267Y522833D01*
X1040100Y522167D01*
X1040267Y521500D01*
X1040600Y521000D01*
X1041100Y520667D01*
X1041683Y520500D01*
X1042267Y520583D01*
X1042767Y520833D01*
X1043100Y521167D01*
G01X1047200Y520500D02*
Y525500D01*
G01X1052300Y520500D02*
Y524750D01*
X1052467Y525167D01*
X1052800Y525417D01*
X1053300Y525500D01*
X1053800Y525333D01*
X1054050Y524917D01*
G01X1053050Y523500D02*
X1051383D01*
G01X1057317Y522167D02*
X1059483D01*
G01X1062500Y518833D02*
Y523833D01*
G01Y523083D02*
X1062917Y523500D01*
X1063333Y523750D01*
X1064000Y523833D01*
X1064583Y523750D01*
X1065167Y523333D01*
X1065417Y522750D01*
X1065500Y522167D01*
X1065417Y521583D01*
X1065167Y521000D01*
X1064667Y520667D01*
X1064000Y520500D01*
X1063417Y520583D01*
X1062833Y520833D01*
X1062500Y521167D01*
G01X1069600Y520500D02*
Y525500D01*
G01X1073783Y523833D02*
Y521500D01*
X1074117Y520917D01*
X1074617Y520583D01*
X1075200Y520500D01*
X1075783Y520583D01*
X1076283Y520917D01*
X1076617Y521500D01*
G01Y520500D02*
Y523833D01*
G01X1079633Y519250D02*
X1080217Y518917D01*
X1080883Y518833D01*
X1081467Y518917D01*
X1081967Y519333D01*
X1082300Y519917D01*
Y523833D01*
G01Y523167D02*
X1081967Y523500D01*
X1081467Y523750D01*
X1080883Y523833D01*
X1080217Y523667D01*
X1079800Y523333D01*
X1079467Y522750D01*
X1079300Y522167D01*
X1079383Y521667D01*
X1079717Y521083D01*
X1080217Y520667D01*
X1080883Y520500D01*
X1081383Y520583D01*
X1081967Y520917D01*
X1082300Y521250D01*
G01X1085233Y519250D02*
X1085817Y518917D01*
X1086483Y518833D01*
X1087067Y518917D01*
X1087567Y519333D01*
X1087900Y519917D01*
Y523833D01*
G01Y523167D02*
X1087567Y523500D01*
X1087067Y523750D01*
X1086483Y523833D01*
X1085817Y523667D01*
X1085400Y523333D01*
X1085067Y522750D01*
X1084900Y522167D01*
X1084983Y521667D01*
X1085317Y521083D01*
X1085817Y520667D01*
X1086483Y520500D01*
X1086983Y520583D01*
X1087567Y520917D01*
X1087900Y521250D01*
G01X1092000Y523833D02*
Y520500D01*
G01Y525167D02*
X1091833Y525250D01*
Y525417D01*
X1092000Y525500D01*
X1092167Y525417D01*
Y525250D01*
X1092000Y525167D01*
G01X1096183Y520500D02*
Y523833D01*
G01Y523000D02*
X1096517Y523417D01*
X1097017Y523750D01*
X1097683Y523833D01*
X1098267Y523750D01*
X1098767Y523417D01*
X1099017Y522833D01*
Y520500D01*
G01X1102033Y519250D02*
X1102617Y518917D01*
X1103283Y518833D01*
X1103867Y518917D01*
X1104367Y519333D01*
X1104700Y519917D01*
Y523833D01*
G01Y523167D02*
X1104367Y523500D01*
X1103867Y523750D01*
X1103283Y523833D01*
X1102617Y523667D01*
X1102200Y523333D01*
X1101867Y522750D01*
X1101700Y522167D01*
X1101783Y521667D01*
X1102117Y521083D01*
X1102617Y520667D01*
X1103283Y520500D01*
X1103783Y520583D01*
X1104367Y520917D01*
X1104700Y521250D01*
G01X1114400Y520333D02*
X1114233Y520417D01*
Y520583D01*
X1114400Y520667D01*
X1114567Y520583D01*
Y520417D01*
X1114400Y520333D01*
G01Y522583D02*
X1114233Y522667D01*
Y522833D01*
X1114400Y522917D01*
X1114567Y522833D01*
Y522667D01*
X1114400Y522583D01*
G01X1125600Y525500D02*
Y520500D01*
G01X1124433Y523833D02*
X1126767D01*
G01X1129783Y520500D02*
Y525500D01*
G01Y523083D02*
X1130200Y523500D01*
X1130617Y523750D01*
X1131283Y523833D01*
X1131783Y523750D01*
X1132367Y523417D01*
X1132617Y522917D01*
Y520500D01*
G01X1135550Y522750D02*
X1138217D01*
X1137967Y523333D01*
X1137550Y523667D01*
X1136967Y523833D01*
X1136383Y523750D01*
X1135883Y523500D01*
X1135550Y522917D01*
X1135383Y522417D01*
Y521917D01*
X1135550Y521417D01*
X1135967Y520917D01*
X1136467Y520583D01*
X1137050Y520500D01*
X1137633Y520667D01*
X1138217Y521167D01*
G01X1146500Y518833D02*
Y523833D01*
G01Y523083D02*
X1146917Y523500D01*
X1147333Y523750D01*
X1148000Y523833D01*
X1148583Y523750D01*
X1149167Y523333D01*
X1149417Y522750D01*
X1149500Y522167D01*
X1149417Y521583D01*
X1149167Y521000D01*
X1148667Y520667D01*
X1148000Y520500D01*
X1147417Y520583D01*
X1146833Y520833D01*
X1146500Y521167D01*
G01X1153600Y520500D02*
Y525500D01*
G01X1157783Y523833D02*
Y521500D01*
X1158117Y520917D01*
X1158617Y520583D01*
X1159200Y520500D01*
X1159783Y520583D01*
X1160283Y520917D01*
X1160617Y521500D01*
G01Y520500D02*
Y523833D01*
G01X1163633Y519250D02*
X1164217Y518917D01*
X1164883Y518833D01*
X1165467Y518917D01*
X1165967Y519333D01*
X1166300Y519917D01*
Y523833D01*
G01Y523167D02*
X1165967Y523500D01*
X1165467Y523750D01*
X1164883Y523833D01*
X1164217Y523667D01*
X1163800Y523333D01*
X1163467Y522750D01*
X1163300Y522167D01*
X1163383Y521667D01*
X1163717Y521083D01*
X1164217Y520667D01*
X1164883Y520500D01*
X1165383Y520583D01*
X1165967Y520917D01*
X1166300Y521250D01*
G01X1169233Y519250D02*
X1169817Y518917D01*
X1170483Y518833D01*
X1171067Y518917D01*
X1171567Y519333D01*
X1171900Y519917D01*
Y523833D01*
G01Y523167D02*
X1171567Y523500D01*
X1171067Y523750D01*
X1170483Y523833D01*
X1169817Y523667D01*
X1169400Y523333D01*
X1169067Y522750D01*
X1168900Y522167D01*
X1168983Y521667D01*
X1169317Y521083D01*
X1169817Y520667D01*
X1170483Y520500D01*
X1170983Y520583D01*
X1171567Y520917D01*
X1171900Y521250D01*
G01X1176000Y523833D02*
Y520500D01*
G01Y525167D02*
X1175833Y525250D01*
Y525417D01*
X1176000Y525500D01*
X1176167Y525417D01*
Y525250D01*
X1176000Y525167D01*
G01X1180183Y520500D02*
Y523833D01*
G01Y523000D02*
X1180517Y523417D01*
X1181017Y523750D01*
X1181683Y523833D01*
X1182267Y523750D01*
X1182767Y523417D01*
X1183017Y522833D01*
Y520500D01*
G01X1186033Y519250D02*
X1186617Y518917D01*
X1187283Y518833D01*
X1187867Y518917D01*
X1188367Y519333D01*
X1188700Y519917D01*
Y523833D01*
G01Y523167D02*
X1188367Y523500D01*
X1187867Y523750D01*
X1187283Y523833D01*
X1186617Y523667D01*
X1186200Y523333D01*
X1185867Y522750D01*
X1185700Y522167D01*
X1185783Y521667D01*
X1186117Y521083D01*
X1186617Y520667D01*
X1187283Y520500D01*
X1187783Y520583D01*
X1188367Y520917D01*
X1188700Y521250D01*
G01X1197233Y520500D02*
Y523833D01*
G01Y523167D02*
X1197650Y523500D01*
X1198067Y523750D01*
X1198650Y523833D01*
X1199067Y523750D01*
X1199567Y523500D01*
G01X1205500Y520500D02*
Y523833D01*
G01Y523250D02*
X1205167Y523583D01*
X1204667Y523750D01*
X1204083Y523833D01*
X1203500Y523667D01*
X1203000Y523333D01*
X1202667Y522833D01*
X1202500Y522167D01*
X1202667Y521500D01*
X1203000Y521000D01*
X1203500Y520667D01*
X1204083Y520500D01*
X1204667Y520583D01*
X1205167Y520833D01*
X1205500Y521167D01*
G01X1209600Y525500D02*
Y520500D01*
G01X1208433Y523833D02*
X1210767D01*
G01X1215200D02*
Y520500D01*
G01Y525167D02*
X1215033Y525250D01*
Y525417D01*
X1215200Y525500D01*
X1215367Y525417D01*
Y525250D01*
X1215200Y525167D01*
G01X1220800Y520500D02*
X1220300Y520583D01*
X1219800Y520917D01*
X1219467Y521500D01*
X1219300Y522167D01*
X1219467Y522833D01*
X1219800Y523417D01*
X1220300Y523750D01*
X1220800Y523833D01*
X1221300Y523750D01*
X1221800Y523417D01*
X1222133Y522833D01*
X1222217Y522167D01*
X1222133Y521500D01*
X1221800Y520917D01*
X1221300Y520583D01*
X1220800Y520500D01*
G01X1230500Y518833D02*
Y523833D01*
G01Y523083D02*
X1230917Y523500D01*
X1231333Y523750D01*
X1232000Y523833D01*
X1232583Y523750D01*
X1233167Y523333D01*
X1233417Y522750D01*
X1233500Y522167D01*
X1233417Y521583D01*
X1233167Y521000D01*
X1232667Y520667D01*
X1232000Y520500D01*
X1231417Y520583D01*
X1230833Y520833D01*
X1230500Y521167D01*
G01X1236350Y522750D02*
X1239017D01*
X1238767Y523333D01*
X1238350Y523667D01*
X1237767Y523833D01*
X1237183Y523750D01*
X1236683Y523500D01*
X1236350Y522917D01*
X1236183Y522417D01*
Y521917D01*
X1236350Y521417D01*
X1236767Y520917D01*
X1237267Y520583D01*
X1237850Y520500D01*
X1238433Y520667D01*
X1239017Y521167D01*
G01X1242033Y520500D02*
Y523833D01*
G01Y523167D02*
X1242450Y523500D01*
X1242867Y523750D01*
X1243450Y523833D01*
X1243867Y523750D01*
X1244367Y523500D01*
G01X1253900Y520500D02*
Y524750D01*
X1254067Y525167D01*
X1254400Y525417D01*
X1254900Y525500D01*
X1255400Y525333D01*
X1255650Y524917D01*
G01X1254650Y523500D02*
X1252983D01*
G01X1260000Y520500D02*
X1259500Y520583D01*
X1259000Y520917D01*
X1258667Y521500D01*
X1258500Y522167D01*
X1258667Y522833D01*
X1259000Y523417D01*
X1259500Y523750D01*
X1260000Y523833D01*
X1260500Y523750D01*
X1261000Y523417D01*
X1261333Y522833D01*
X1261417Y522167D01*
X1261333Y521500D01*
X1261000Y520917D01*
X1260500Y520583D01*
X1260000Y520500D01*
G01X1265600D02*
Y525500D01*
G01X1271200Y520500D02*
Y525500D01*
G01X1276800Y520500D02*
X1276300Y520583D01*
X1275800Y520917D01*
X1275467Y521500D01*
X1275300Y522167D01*
X1275467Y522833D01*
X1275800Y523417D01*
X1276300Y523750D01*
X1276800Y523833D01*
X1277300Y523750D01*
X1277800Y523417D01*
X1278133Y522833D01*
X1278217Y522167D01*
X1278133Y521500D01*
X1277800Y520917D01*
X1277300Y520583D01*
X1276800Y520500D01*
G01X1280317Y523833D02*
X1281317Y520500D01*
X1282400Y523833D01*
X1283483Y520500D01*
X1284483Y523833D01*
G01X1288000D02*
Y520500D01*
G01Y525167D02*
X1287833Y525250D01*
Y525417D01*
X1288000Y525500D01*
X1288167Y525417D01*
Y525250D01*
X1288000Y525167D01*
G01X1292183Y520500D02*
Y523833D01*
G01Y523000D02*
X1292517Y523417D01*
X1293017Y523750D01*
X1293683Y523833D01*
X1294267Y523750D01*
X1294767Y523417D01*
X1295017Y522833D01*
Y520500D01*
G01X1298033Y519250D02*
X1298617Y518917D01*
X1299283Y518833D01*
X1299867Y518917D01*
X1300367Y519333D01*
X1300700Y519917D01*
Y523833D01*
G01Y523167D02*
X1300367Y523500D01*
X1299867Y523750D01*
X1299283Y523833D01*
X1298617Y523667D01*
X1298200Y523333D01*
X1297867Y522750D01*
X1297700Y522167D01*
X1297783Y521667D01*
X1298117Y521083D01*
X1298617Y520667D01*
X1299283Y520500D01*
X1299783Y520583D01*
X1300367Y520917D01*
X1300700Y521250D01*
G01X1304800Y520333D02*
X1304633Y520417D01*
Y520583D01*
X1304800Y520667D01*
X1304967Y520583D01*
Y520417D01*
X1304800Y520333D01*
G01Y522583D02*
X1304633Y522667D01*
Y522833D01*
X1304800Y522917D01*
X1304967Y522833D01*
Y522667D01*
X1304800Y522583D01*
G01X1033500Y529500D02*
Y534500D01*
G01Y532000D02*
X1033917Y532500D01*
X1034417Y532750D01*
X1034917Y532833D01*
X1035667Y532667D01*
X1036167Y532333D01*
X1036500Y531750D01*
Y531083D01*
X1036333Y530417D01*
X1036000Y529917D01*
X1035417Y529583D01*
X1034917Y529500D01*
X1034417Y529583D01*
X1033917Y529833D01*
X1033500Y530250D01*
G01X1039350Y531750D02*
X1042017D01*
X1041767Y532333D01*
X1041350Y532667D01*
X1040767Y532833D01*
X1040183Y532750D01*
X1039683Y532500D01*
X1039350Y531917D01*
X1039183Y531417D01*
Y530917D01*
X1039350Y530417D01*
X1039767Y529917D01*
X1040267Y529583D01*
X1040850Y529500D01*
X1041433Y529667D01*
X1042017Y530167D01*
G01X1051300Y529500D02*
Y533750D01*
X1051467Y534167D01*
X1051800Y534417D01*
X1052300Y534500D01*
X1052800Y534333D01*
X1053050Y533917D01*
G01X1052050Y532500D02*
X1050383D01*
G01X1056233Y529500D02*
Y532833D01*
G01Y532167D02*
X1056650Y532500D01*
X1057067Y532750D01*
X1057650Y532833D01*
X1058067Y532750D01*
X1058567Y532500D01*
G01X1061750Y531750D02*
X1064417D01*
X1064167Y532333D01*
X1063750Y532667D01*
X1063167Y532833D01*
X1062583Y532750D01*
X1062083Y532500D01*
X1061750Y531917D01*
X1061583Y531417D01*
Y530917D01*
X1061750Y530417D01*
X1062167Y529917D01*
X1062667Y529583D01*
X1063250Y529500D01*
X1063833Y529667D01*
X1064417Y530167D01*
G01X1067350Y531750D02*
X1070017D01*
X1069767Y532333D01*
X1069350Y532667D01*
X1068767Y532833D01*
X1068183Y532750D01*
X1067683Y532500D01*
X1067350Y531917D01*
X1067183Y531417D01*
Y530917D01*
X1067350Y530417D01*
X1067767Y529917D01*
X1068267Y529583D01*
X1068850Y529500D01*
X1069433Y529667D01*
X1070017Y530167D01*
G01X1079300Y529500D02*
Y533750D01*
X1079467Y534167D01*
X1079800Y534417D01*
X1080300Y534500D01*
X1080800Y534333D01*
X1081050Y533917D01*
G01X1080050Y532500D02*
X1078383D01*
G01X1084233Y529500D02*
Y532833D01*
G01Y532167D02*
X1084650Y532500D01*
X1085067Y532750D01*
X1085650Y532833D01*
X1086067Y532750D01*
X1086567Y532500D01*
G01X1091000Y529500D02*
X1090500Y529583D01*
X1090000Y529917D01*
X1089667Y530500D01*
X1089500Y531167D01*
X1089667Y531833D01*
X1090000Y532417D01*
X1090500Y532750D01*
X1091000Y532833D01*
X1091500Y532750D01*
X1092000Y532417D01*
X1092333Y531833D01*
X1092417Y531167D01*
X1092333Y530500D01*
X1092000Y529917D01*
X1091500Y529583D01*
X1091000Y529500D01*
G01X1094100D02*
Y532833D01*
G01Y531917D02*
X1094350Y532333D01*
X1094767Y532667D01*
X1095350Y532833D01*
X1095933Y532667D01*
X1096350Y532333D01*
X1096600Y531917D01*
Y529500D01*
G01Y531917D02*
X1096850Y532333D01*
X1097267Y532667D01*
X1097850Y532833D01*
X1098433Y532667D01*
X1098850Y532333D01*
X1099100Y531833D01*
Y529500D01*
G01X1106550Y530083D02*
X1106967Y529750D01*
X1107550Y529500D01*
X1108050D01*
X1108550Y529667D01*
X1108883Y529917D01*
X1109050Y530250D01*
X1108967Y530750D01*
X1108633Y531000D01*
X1107133Y531500D01*
X1106800Y532083D01*
X1106967Y532500D01*
X1107300Y532750D01*
X1107800Y532833D01*
X1108300Y532750D01*
X1108800Y532500D01*
G01X1113400Y529500D02*
X1112900Y529583D01*
X1112400Y529917D01*
X1112067Y530500D01*
X1111900Y531167D01*
X1112067Y531833D01*
X1112400Y532417D01*
X1112900Y532750D01*
X1113400Y532833D01*
X1113900Y532750D01*
X1114400Y532417D01*
X1114733Y531833D01*
X1114817Y531167D01*
X1114733Y530500D01*
X1114400Y529917D01*
X1113900Y529583D01*
X1113400Y529500D01*
G01X1119000D02*
Y534500D01*
G01X1126100D02*
Y529500D01*
G01Y530250D02*
X1125767Y529833D01*
X1125267Y529583D01*
X1124683Y529500D01*
X1124017Y529667D01*
X1123517Y530083D01*
X1123183Y530583D01*
X1123100Y531167D01*
X1123183Y531750D01*
X1123517Y532250D01*
X1124017Y532667D01*
X1124683Y532833D01*
X1125267Y532750D01*
X1125683Y532583D01*
X1126100Y532250D01*
G01X1128950Y531750D02*
X1131617D01*
X1131367Y532333D01*
X1130950Y532667D01*
X1130367Y532833D01*
X1129783Y532750D01*
X1129283Y532500D01*
X1128950Y531917D01*
X1128783Y531417D01*
Y530917D01*
X1128950Y530417D01*
X1129367Y529917D01*
X1129867Y529583D01*
X1130450Y529500D01*
X1131033Y529667D01*
X1131617Y530167D01*
G01X1134633Y529500D02*
Y532833D01*
G01Y532167D02*
X1135050Y532500D01*
X1135467Y532750D01*
X1136050Y532833D01*
X1136467Y532750D01*
X1136967Y532500D01*
G01X1144500Y529500D02*
Y532833D01*
G01Y531917D02*
X1144750Y532333D01*
X1145167Y532667D01*
X1145750Y532833D01*
X1146333Y532667D01*
X1146750Y532333D01*
X1147000Y531917D01*
Y529500D01*
G01Y531917D02*
X1147250Y532333D01*
X1147667Y532667D01*
X1148250Y532833D01*
X1148833Y532667D01*
X1149250Y532333D01*
X1149500Y531833D01*
Y529500D01*
G01X1154100D02*
Y532833D01*
G01Y532250D02*
X1153767Y532583D01*
X1153267Y532750D01*
X1152683Y532833D01*
X1152100Y532667D01*
X1151600Y532333D01*
X1151267Y531833D01*
X1151100Y531167D01*
X1151267Y530500D01*
X1151600Y530000D01*
X1152100Y529667D01*
X1152683Y529500D01*
X1153267Y529583D01*
X1153767Y529833D01*
X1154100Y530167D01*
G01X1156950Y530083D02*
X1157367Y529750D01*
X1157950Y529500D01*
X1158450D01*
X1158950Y529667D01*
X1159283Y529917D01*
X1159450Y530250D01*
X1159367Y530750D01*
X1159033Y531000D01*
X1157533Y531500D01*
X1157200Y532083D01*
X1157367Y532500D01*
X1157700Y532750D01*
X1158200Y532833D01*
X1158700Y532750D01*
X1159200Y532500D01*
G01X1162383Y529500D02*
Y534500D01*
G01X1165050Y532833D02*
X1162383Y530917D01*
G01X1163467Y531667D02*
X1165217Y529500D01*
G01X1169400Y529333D02*
X1169233Y529417D01*
Y529583D01*
X1169400Y529667D01*
X1169567Y529583D01*
Y529417D01*
X1169400Y529333D01*
G01X1020417Y542667D02*
X1020917Y543167D01*
X1021500Y543417D01*
X1022167Y543500D01*
X1023000Y543333D01*
X1023583Y542917D01*
X1023750Y542417D01*
X1023667Y541917D01*
X1023333Y541500D01*
X1021667Y540667D01*
X1020917Y540083D01*
X1020417Y539250D01*
X1020250Y538500D01*
X1023750D01*
G01X1027600Y538333D02*
X1027433Y538417D01*
Y538583D01*
X1027600Y538667D01*
X1027767Y538583D01*
Y538417D01*
X1027600Y538333D01*
G01X1033200Y543500D02*
Y538500D01*
G01X1031283Y543500D02*
X1035117D01*
G01X1037383Y538500D02*
Y543500D01*
G01Y541083D02*
X1037800Y541500D01*
X1038217Y541750D01*
X1038883Y541833D01*
X1039383Y541750D01*
X1039967Y541417D01*
X1040217Y540917D01*
Y538500D01*
G01X1043150Y540750D02*
X1045817D01*
X1045567Y541333D01*
X1045150Y541667D01*
X1044567Y541833D01*
X1043983Y541750D01*
X1043483Y541500D01*
X1043150Y540917D01*
X1042983Y540417D01*
Y539917D01*
X1043150Y539417D01*
X1043567Y538917D01*
X1044067Y538583D01*
X1044650Y538500D01*
X1045233Y538667D01*
X1045817Y539167D01*
G01X1054350Y539083D02*
X1054767Y538750D01*
X1055350Y538500D01*
X1055850D01*
X1056350Y538667D01*
X1056683Y538917D01*
X1056850Y539250D01*
X1056767Y539750D01*
X1056433Y540000D01*
X1054933Y540500D01*
X1054600Y541083D01*
X1054767Y541500D01*
X1055100Y541750D01*
X1055600Y541833D01*
X1056100Y541750D01*
X1056600Y541500D01*
G01X1061200Y541833D02*
Y538500D01*
G01Y543167D02*
X1061033Y543250D01*
Y543417D01*
X1061200Y543500D01*
X1061367Y543417D01*
Y543250D01*
X1061200Y543167D01*
G01X1068300Y543500D02*
Y538500D01*
G01Y539250D02*
X1067967Y538833D01*
X1067467Y538583D01*
X1066883Y538500D01*
X1066217Y538667D01*
X1065717Y539083D01*
X1065383Y539583D01*
X1065300Y540167D01*
X1065383Y540750D01*
X1065717Y541250D01*
X1066217Y541667D01*
X1066883Y541833D01*
X1067467Y541750D01*
X1067883Y541583D01*
X1068300Y541250D01*
G01X1071150Y540750D02*
X1073817D01*
X1073567Y541333D01*
X1073150Y541667D01*
X1072567Y541833D01*
X1071983Y541750D01*
X1071483Y541500D01*
X1071150Y540917D01*
X1070983Y540417D01*
Y539917D01*
X1071150Y539417D01*
X1071567Y538917D01*
X1072067Y538583D01*
X1072650Y538500D01*
X1073233Y538667D01*
X1073817Y539167D01*
G01X1081517Y541833D02*
X1082517Y538500D01*
X1083600Y541833D01*
X1084683Y538500D01*
X1085683Y541833D01*
G01X1089200D02*
Y538500D01*
G01Y543167D02*
X1089033Y543250D01*
Y543417D01*
X1089200Y543500D01*
X1089367Y543417D01*
Y543250D01*
X1089200Y543167D01*
G01X1094800Y543500D02*
Y538500D01*
G01X1093633Y541833D02*
X1095967D01*
G01X1098983Y538500D02*
Y543500D01*
G01Y541083D02*
X1099400Y541500D01*
X1099817Y541750D01*
X1100483Y541833D01*
X1100983Y541750D01*
X1101567Y541417D01*
X1101817Y540917D01*
Y538500D01*
G01X1110350Y539083D02*
X1110767Y538750D01*
X1111350Y538500D01*
X1111850D01*
X1112350Y538667D01*
X1112683Y538917D01*
X1112850Y539250D01*
X1112767Y539750D01*
X1112433Y540000D01*
X1110933Y540500D01*
X1110600Y541083D01*
X1110767Y541500D01*
X1111100Y541750D01*
X1111600Y541833D01*
X1112100Y541750D01*
X1112600Y541500D01*
G01X1117200Y538500D02*
X1116700Y538583D01*
X1116200Y538917D01*
X1115867Y539500D01*
X1115700Y540167D01*
X1115867Y540833D01*
X1116200Y541417D01*
X1116700Y541750D01*
X1117200Y541833D01*
X1117700Y541750D01*
X1118200Y541417D01*
X1118533Y540833D01*
X1118617Y540167D01*
X1118533Y539500D01*
X1118200Y538917D01*
X1117700Y538583D01*
X1117200Y538500D01*
G01X1122800D02*
Y543500D01*
G01X1129900D02*
Y538500D01*
G01Y539250D02*
X1129567Y538833D01*
X1129067Y538583D01*
X1128483Y538500D01*
X1127817Y538667D01*
X1127317Y539083D01*
X1126983Y539583D01*
X1126900Y540167D01*
X1126983Y540750D01*
X1127317Y541250D01*
X1127817Y541667D01*
X1128483Y541833D01*
X1129067Y541750D01*
X1129483Y541583D01*
X1129900Y541250D01*
G01X1132750Y540750D02*
X1135417D01*
X1135167Y541333D01*
X1134750Y541667D01*
X1134167Y541833D01*
X1133583Y541750D01*
X1133083Y541500D01*
X1132750Y540917D01*
X1132583Y540417D01*
Y539917D01*
X1132750Y539417D01*
X1133167Y538917D01*
X1133667Y538583D01*
X1134250Y538500D01*
X1134833Y538667D01*
X1135417Y539167D01*
G01X1138433Y538500D02*
Y541833D01*
G01Y541167D02*
X1138850Y541500D01*
X1139267Y541750D01*
X1139850Y541833D01*
X1140267Y541750D01*
X1140767Y541500D01*
G01X1148300Y538500D02*
Y541833D01*
G01Y540917D02*
X1148550Y541333D01*
X1148967Y541667D01*
X1149550Y541833D01*
X1150133Y541667D01*
X1150550Y541333D01*
X1150800Y540917D01*
Y538500D01*
G01Y540917D02*
X1151050Y541333D01*
X1151467Y541667D01*
X1152050Y541833D01*
X1152633Y541667D01*
X1153050Y541333D01*
X1153300Y540833D01*
Y538500D01*
G01X1157900D02*
Y541833D01*
G01Y541250D02*
X1157567Y541583D01*
X1157067Y541750D01*
X1156483Y541833D01*
X1155900Y541667D01*
X1155400Y541333D01*
X1155067Y540833D01*
X1154900Y540167D01*
X1155067Y539500D01*
X1155400Y539000D01*
X1155900Y538667D01*
X1156483Y538500D01*
X1157067Y538583D01*
X1157567Y538833D01*
X1157900Y539167D01*
G01X1160750Y539083D02*
X1161167Y538750D01*
X1161750Y538500D01*
X1162250D01*
X1162750Y538667D01*
X1163083Y538917D01*
X1163250Y539250D01*
X1163167Y539750D01*
X1162833Y540000D01*
X1161333Y540500D01*
X1161000Y541083D01*
X1161167Y541500D01*
X1161500Y541750D01*
X1162000Y541833D01*
X1162500Y541750D01*
X1163000Y541500D01*
G01X1166183Y538500D02*
Y543500D01*
G01X1168850Y541833D02*
X1166183Y539917D01*
G01X1167267Y540667D02*
X1169017Y538500D01*
G01X1177300Y536833D02*
Y541833D01*
G01Y541083D02*
X1177717Y541500D01*
X1178133Y541750D01*
X1178800Y541833D01*
X1179383Y541750D01*
X1179967Y541333D01*
X1180217Y540750D01*
X1180300Y540167D01*
X1180217Y539583D01*
X1179967Y539000D01*
X1179467Y538667D01*
X1178800Y538500D01*
X1178217Y538583D01*
X1177633Y538833D01*
X1177300Y539167D01*
G01X1185900Y538500D02*
Y541833D01*
G01Y541250D02*
X1185567Y541583D01*
X1185067Y541750D01*
X1184483Y541833D01*
X1183900Y541667D01*
X1183400Y541333D01*
X1183067Y540833D01*
X1182900Y540167D01*
X1183067Y539500D01*
X1183400Y539000D01*
X1183900Y538667D01*
X1184483Y538500D01*
X1185067Y538583D01*
X1185567Y538833D01*
X1185900Y539167D01*
G01X1191500Y543500D02*
Y538500D01*
G01Y539250D02*
X1191167Y538833D01*
X1190667Y538583D01*
X1190083Y538500D01*
X1189417Y538667D01*
X1188917Y539083D01*
X1188583Y539583D01*
X1188500Y540167D01*
X1188583Y540750D01*
X1188917Y541250D01*
X1189417Y541667D01*
X1190083Y541833D01*
X1190667Y541750D01*
X1191083Y541583D01*
X1191500Y541250D01*
G01X1195433Y537583D02*
X1195767Y538667D01*
G01X1206800Y543500D02*
Y538500D01*
G01X1205633Y541833D02*
X1207967D01*
G01X1210983Y538500D02*
Y543500D01*
G01Y541083D02*
X1211400Y541500D01*
X1211817Y541750D01*
X1212483Y541833D01*
X1212983Y541750D01*
X1213567Y541417D01*
X1213817Y540917D01*
Y538500D01*
G01X1216750Y540750D02*
X1219417D01*
X1219167Y541333D01*
X1218750Y541667D01*
X1218167Y541833D01*
X1217583Y541750D01*
X1217083Y541500D01*
X1216750Y540917D01*
X1216583Y540417D01*
Y539917D01*
X1216750Y539417D01*
X1217167Y538917D01*
X1217667Y538583D01*
X1218250Y538500D01*
X1218833Y538667D01*
X1219417Y539167D01*
G01X1230700Y538500D02*
Y541833D01*
G01Y541250D02*
X1230367Y541583D01*
X1229867Y541750D01*
X1229283Y541833D01*
X1228700Y541667D01*
X1228200Y541333D01*
X1227867Y540833D01*
X1227700Y540167D01*
X1227867Y539500D01*
X1228200Y539000D01*
X1228700Y538667D01*
X1229283Y538500D01*
X1229867Y538583D01*
X1230367Y538833D01*
X1230700Y539167D01*
G01X1233383Y538500D02*
Y541833D01*
G01Y541000D02*
X1233717Y541417D01*
X1234217Y541750D01*
X1234883Y541833D01*
X1235467Y541750D01*
X1235967Y541417D01*
X1236217Y540833D01*
Y538500D01*
G01X1238983D02*
Y541833D01*
G01Y541000D02*
X1239317Y541417D01*
X1239817Y541750D01*
X1240483Y541833D01*
X1241067Y541750D01*
X1241567Y541417D01*
X1241817Y540833D01*
Y538500D01*
G01X1244583Y541833D02*
Y539500D01*
X1244917Y538917D01*
X1245417Y538583D01*
X1246000Y538500D01*
X1246583Y538583D01*
X1247083Y538917D01*
X1247417Y539500D01*
G01Y538500D02*
Y541833D01*
G01X1253100Y538500D02*
Y541833D01*
G01Y541250D02*
X1252767Y541583D01*
X1252267Y541750D01*
X1251683Y541833D01*
X1251100Y541667D01*
X1250600Y541333D01*
X1250267Y540833D01*
X1250100Y540167D01*
X1250267Y539500D01*
X1250600Y539000D01*
X1251100Y538667D01*
X1251683Y538500D01*
X1252267Y538583D01*
X1252767Y538833D01*
X1253100Y539167D01*
G01X1257200Y538500D02*
Y543500D01*
G01X1267233Y538500D02*
Y541833D01*
G01Y541167D02*
X1267650Y541500D01*
X1268067Y541750D01*
X1268650Y541833D01*
X1269067Y541750D01*
X1269567Y541500D01*
G01X1274000Y541833D02*
Y538500D01*
G01Y543167D02*
X1273833Y543250D01*
Y543417D01*
X1274000Y543500D01*
X1274167Y543417D01*
Y543250D01*
X1274000Y543167D01*
G01X1278183Y538500D02*
Y541833D01*
G01Y541000D02*
X1278517Y541417D01*
X1279017Y541750D01*
X1279683Y541833D01*
X1280267Y541750D01*
X1280767Y541417D01*
X1281017Y540833D01*
Y538500D01*
G01X1284033Y537250D02*
X1284617Y536917D01*
X1285283Y536833D01*
X1285867Y536917D01*
X1286367Y537333D01*
X1286700Y537917D01*
Y541833D01*
G01Y541167D02*
X1286367Y541500D01*
X1285867Y541750D01*
X1285283Y541833D01*
X1284617Y541667D01*
X1284200Y541333D01*
X1283867Y540750D01*
X1283700Y540167D01*
X1283783Y539667D01*
X1284117Y539083D01*
X1284617Y538667D01*
X1285283Y538500D01*
X1285783Y538583D01*
X1286367Y538917D01*
X1286700Y539250D01*
G01X1295150Y539083D02*
X1295567Y538750D01*
X1296150Y538500D01*
X1296650D01*
X1297150Y538667D01*
X1297483Y538917D01*
X1297650Y539250D01*
X1297567Y539750D01*
X1297233Y540000D01*
X1295733Y540500D01*
X1295400Y541083D01*
X1295567Y541500D01*
X1295900Y541750D01*
X1296400Y541833D01*
X1296900Y541750D01*
X1297400Y541500D01*
G01X1300583Y538500D02*
Y543500D01*
G01Y541083D02*
X1301000Y541500D01*
X1301417Y541750D01*
X1302083Y541833D01*
X1302583Y541750D01*
X1303167Y541417D01*
X1303417Y540917D01*
Y538500D01*
G01X1307600D02*
X1307100Y538583D01*
X1306600Y538917D01*
X1306267Y539500D01*
X1306100Y540167D01*
X1306267Y540833D01*
X1306600Y541417D01*
X1307100Y541750D01*
X1307600Y541833D01*
X1308100Y541750D01*
X1308600Y541417D01*
X1308933Y540833D01*
X1309017Y540167D01*
X1308933Y539500D01*
X1308600Y538917D01*
X1308100Y538583D01*
X1307600Y538500D01*
G01X1311783Y541833D02*
Y539500D01*
X1312117Y538917D01*
X1312617Y538583D01*
X1313200Y538500D01*
X1313783Y538583D01*
X1314283Y538917D01*
X1314617Y539500D01*
G01Y538500D02*
Y541833D01*
G01X1318800Y538500D02*
Y543500D01*
G01X1325900D02*
Y538500D01*
G01Y539250D02*
X1325567Y538833D01*
X1325067Y538583D01*
X1324483Y538500D01*
X1323817Y538667D01*
X1323317Y539083D01*
X1322983Y539583D01*
X1322900Y540167D01*
X1322983Y540750D01*
X1323317Y541250D01*
X1323817Y541667D01*
X1324483Y541833D01*
X1325067Y541750D01*
X1325483Y541583D01*
X1325900Y541250D01*
G01X1032500Y552500D02*
Y557500D01*
G01Y555000D02*
X1032917Y555500D01*
X1033417Y555750D01*
X1033917Y555833D01*
X1034667Y555667D01*
X1035167Y555333D01*
X1035500Y554750D01*
Y554083D01*
X1035333Y553417D01*
X1035000Y552917D01*
X1034417Y552583D01*
X1033917Y552500D01*
X1033417Y552583D01*
X1032917Y552833D01*
X1032500Y553250D01*
G01X1038350Y554750D02*
X1041017D01*
X1040767Y555333D01*
X1040350Y555667D01*
X1039767Y555833D01*
X1039183Y555750D01*
X1038683Y555500D01*
X1038350Y554917D01*
X1038183Y554417D01*
Y553917D01*
X1038350Y553417D01*
X1038767Y552917D01*
X1039267Y552583D01*
X1039850Y552500D01*
X1040433Y552667D01*
X1041017Y553167D01*
G01X1050800Y557500D02*
Y552500D01*
G01X1049633Y555833D02*
X1051967D01*
G01X1055150Y554750D02*
X1057817D01*
X1057567Y555333D01*
X1057150Y555667D01*
X1056567Y555833D01*
X1055983Y555750D01*
X1055483Y555500D01*
X1055150Y554917D01*
X1054983Y554417D01*
Y553917D01*
X1055150Y553417D01*
X1055567Y552917D01*
X1056067Y552583D01*
X1056650Y552500D01*
X1057233Y552667D01*
X1057817Y553167D01*
G01X1060583Y552500D02*
Y555833D01*
G01Y555000D02*
X1060917Y555417D01*
X1061417Y555750D01*
X1062083Y555833D01*
X1062667Y555750D01*
X1063167Y555417D01*
X1063417Y554833D01*
Y552500D01*
G01X1067600Y557500D02*
Y552500D01*
G01X1066433Y555833D02*
X1068767D01*
G01X1071950Y554750D02*
X1074617D01*
X1074367Y555333D01*
X1073950Y555667D01*
X1073367Y555833D01*
X1072783Y555750D01*
X1072283Y555500D01*
X1071950Y554917D01*
X1071783Y554417D01*
Y553917D01*
X1071950Y553417D01*
X1072367Y552917D01*
X1072867Y552583D01*
X1073450Y552500D01*
X1074033Y552667D01*
X1074617Y553167D01*
G01X1080300Y557500D02*
Y552500D01*
G01Y553250D02*
X1079967Y552833D01*
X1079467Y552583D01*
X1078883Y552500D01*
X1078217Y552667D01*
X1077717Y553083D01*
X1077383Y553583D01*
X1077300Y554167D01*
X1077383Y554750D01*
X1077717Y555250D01*
X1078217Y555667D01*
X1078883Y555833D01*
X1079467Y555750D01*
X1079883Y555583D01*
X1080300Y555250D01*
G01X1087917Y555833D02*
X1088917Y552500D01*
X1090000Y555833D01*
X1091083Y552500D01*
X1092083Y555833D01*
G01X1095600D02*
Y552500D01*
G01Y557167D02*
X1095433Y557250D01*
Y557417D01*
X1095600Y557500D01*
X1095767Y557417D01*
Y557250D01*
X1095600Y557167D01*
G01X1101200Y557500D02*
Y552500D01*
G01X1100033Y555833D02*
X1102367D01*
G01X1105383Y552500D02*
Y557500D01*
G01Y555083D02*
X1105800Y555500D01*
X1106217Y555750D01*
X1106883Y555833D01*
X1107383Y555750D01*
X1107967Y555417D01*
X1108217Y554917D01*
Y552500D01*
G01X1116750Y553083D02*
X1117167Y552750D01*
X1117750Y552500D01*
X1118250D01*
X1118750Y552667D01*
X1119083Y552917D01*
X1119250Y553250D01*
X1119167Y553750D01*
X1118833Y554000D01*
X1117333Y554500D01*
X1117000Y555083D01*
X1117167Y555500D01*
X1117500Y555750D01*
X1118000Y555833D01*
X1118500Y555750D01*
X1119000Y555500D01*
G01X1123600Y552500D02*
X1123100Y552583D01*
X1122600Y552917D01*
X1122267Y553500D01*
X1122100Y554167D01*
X1122267Y554833D01*
X1122600Y555417D01*
X1123100Y555750D01*
X1123600Y555833D01*
X1124100Y555750D01*
X1124600Y555417D01*
X1124933Y554833D01*
X1125017Y554167D01*
X1124933Y553500D01*
X1124600Y552917D01*
X1124100Y552583D01*
X1123600Y552500D01*
G01X1129200D02*
Y557500D01*
G01X1136300D02*
Y552500D01*
G01Y553250D02*
X1135967Y552833D01*
X1135467Y552583D01*
X1134883Y552500D01*
X1134217Y552667D01*
X1133717Y553083D01*
X1133383Y553583D01*
X1133300Y554167D01*
X1133383Y554750D01*
X1133717Y555250D01*
X1134217Y555667D01*
X1134883Y555833D01*
X1135467Y555750D01*
X1135883Y555583D01*
X1136300Y555250D01*
G01X1139150Y554750D02*
X1141817D01*
X1141567Y555333D01*
X1141150Y555667D01*
X1140567Y555833D01*
X1139983Y555750D01*
X1139483Y555500D01*
X1139150Y554917D01*
X1138983Y554417D01*
Y553917D01*
X1139150Y553417D01*
X1139567Y552917D01*
X1140067Y552583D01*
X1140650Y552500D01*
X1141233Y552667D01*
X1141817Y553167D01*
G01X1144833Y552500D02*
Y555833D01*
G01Y555167D02*
X1145250Y555500D01*
X1145667Y555750D01*
X1146250Y555833D01*
X1146667Y555750D01*
X1147167Y555500D01*
G01X1154700Y552500D02*
Y555833D01*
G01Y554917D02*
X1154950Y555333D01*
X1155367Y555667D01*
X1155950Y555833D01*
X1156533Y555667D01*
X1156950Y555333D01*
X1157200Y554917D01*
Y552500D01*
G01Y554917D02*
X1157450Y555333D01*
X1157867Y555667D01*
X1158450Y555833D01*
X1159033Y555667D01*
X1159450Y555333D01*
X1159700Y554833D01*
Y552500D01*
G01X1164300D02*
Y555833D01*
G01Y555250D02*
X1163967Y555583D01*
X1163467Y555750D01*
X1162883Y555833D01*
X1162300Y555667D01*
X1161800Y555333D01*
X1161467Y554833D01*
X1161300Y554167D01*
X1161467Y553500D01*
X1161800Y553000D01*
X1162300Y552667D01*
X1162883Y552500D01*
X1163467Y552583D01*
X1163967Y552833D01*
X1164300Y553167D01*
G01X1167150Y553083D02*
X1167567Y552750D01*
X1168150Y552500D01*
X1168650D01*
X1169150Y552667D01*
X1169483Y552917D01*
X1169650Y553250D01*
X1169567Y553750D01*
X1169233Y554000D01*
X1167733Y554500D01*
X1167400Y555083D01*
X1167567Y555500D01*
X1167900Y555750D01*
X1168400Y555833D01*
X1168900Y555750D01*
X1169400Y555500D01*
G01X1172583Y552500D02*
Y557500D01*
G01X1175250Y555833D02*
X1172583Y553917D01*
G01X1173667Y554667D02*
X1175417Y552500D01*
G01X1179600Y552333D02*
X1179433Y552417D01*
Y552583D01*
X1179600Y552667D01*
X1179767Y552583D01*
Y552417D01*
X1179600Y552333D01*
G01X1034000Y566500D02*
Y561500D01*
G01X1032833Y564833D02*
X1035167D01*
G01X1039600Y561500D02*
X1039100Y561583D01*
X1038600Y561917D01*
X1038267Y562500D01*
X1038100Y563167D01*
X1038267Y563833D01*
X1038600Y564417D01*
X1039100Y564750D01*
X1039600Y564833D01*
X1040100Y564750D01*
X1040600Y564417D01*
X1040933Y563833D01*
X1041017Y563167D01*
X1040933Y562500D01*
X1040600Y561917D01*
X1040100Y561583D01*
X1039600Y561500D01*
G01X1049300D02*
Y566500D01*
G01Y564000D02*
X1049717Y564500D01*
X1050217Y564750D01*
X1050717Y564833D01*
X1051467Y564667D01*
X1051967Y564333D01*
X1052300Y563750D01*
Y563083D01*
X1052133Y562417D01*
X1051800Y561917D01*
X1051217Y561583D01*
X1050717Y561500D01*
X1050217Y561583D01*
X1049717Y561833D01*
X1049300Y562250D01*
G01X1055150Y563750D02*
X1057817D01*
X1057567Y564333D01*
X1057150Y564667D01*
X1056567Y564833D01*
X1055983Y564750D01*
X1055483Y564500D01*
X1055150Y563917D01*
X1054983Y563417D01*
Y562917D01*
X1055150Y562417D01*
X1055567Y561917D01*
X1056067Y561583D01*
X1056650Y561500D01*
X1057233Y561667D01*
X1057817Y562167D01*
G01X1068933Y564417D02*
X1068350Y564750D01*
X1067850Y564833D01*
X1067183Y564667D01*
X1066683Y564333D01*
X1066350Y563750D01*
X1066267Y563167D01*
X1066350Y562583D01*
X1066683Y562083D01*
X1067183Y561667D01*
X1067850Y561500D01*
X1068433Y561667D01*
X1068933Y562000D01*
G01X1073200Y561500D02*
X1072700Y561583D01*
X1072200Y561917D01*
X1071867Y562500D01*
X1071700Y563167D01*
X1071867Y563833D01*
X1072200Y564417D01*
X1072700Y564750D01*
X1073200Y564833D01*
X1073700Y564750D01*
X1074200Y564417D01*
X1074533Y563833D01*
X1074617Y563167D01*
X1074533Y562500D01*
X1074200Y561917D01*
X1073700Y561583D01*
X1073200Y561500D01*
G01X1077300Y564833D02*
X1078800Y561500D01*
X1080300Y564833D01*
G01X1083150Y563750D02*
X1085817D01*
X1085567Y564333D01*
X1085150Y564667D01*
X1084567Y564833D01*
X1083983Y564750D01*
X1083483Y564500D01*
X1083150Y563917D01*
X1082983Y563417D01*
Y562917D01*
X1083150Y562417D01*
X1083567Y561917D01*
X1084067Y561583D01*
X1084650Y561500D01*
X1085233Y561667D01*
X1085817Y562167D01*
G01X1088833Y561500D02*
Y564833D01*
G01Y564167D02*
X1089250Y564500D01*
X1089667Y564750D01*
X1090250Y564833D01*
X1090667Y564750D01*
X1091167Y564500D01*
G01X1094350Y563750D02*
X1097017D01*
X1096767Y564333D01*
X1096350Y564667D01*
X1095767Y564833D01*
X1095183Y564750D01*
X1094683Y564500D01*
X1094350Y563917D01*
X1094183Y563417D01*
Y562917D01*
X1094350Y562417D01*
X1094767Y561917D01*
X1095267Y561583D01*
X1095850Y561500D01*
X1096433Y561667D01*
X1097017Y562167D01*
G01X1102700Y566500D02*
Y561500D01*
G01Y562250D02*
X1102367Y561833D01*
X1101867Y561583D01*
X1101283Y561500D01*
X1100617Y561667D01*
X1100117Y562083D01*
X1099783Y562583D01*
X1099700Y563167D01*
X1099783Y563750D01*
X1100117Y564250D01*
X1100617Y564667D01*
X1101283Y564833D01*
X1101867Y564750D01*
X1102283Y564583D01*
X1102700Y564250D01*
G01X1110900Y561500D02*
Y566500D01*
G01Y564000D02*
X1111317Y564500D01*
X1111817Y564750D01*
X1112317Y564833D01*
X1113067Y564667D01*
X1113567Y564333D01*
X1113900Y563750D01*
Y563083D01*
X1113733Y562417D01*
X1113400Y561917D01*
X1112817Y561583D01*
X1112317Y561500D01*
X1111817Y561583D01*
X1111317Y561833D01*
X1110900Y562250D01*
G01X1116250Y560000D02*
X1116750Y559833D01*
X1117417Y560000D01*
X1117833Y560333D01*
X1118167Y560750D01*
X1118667Y562083D01*
X1119750Y564833D01*
G01X1117083D02*
X1118667Y562083D01*
G01X1127950D02*
X1128367Y561750D01*
X1128950Y561500D01*
X1129450D01*
X1129950Y561667D01*
X1130283Y561917D01*
X1130450Y562250D01*
X1130367Y562750D01*
X1130033Y563000D01*
X1128533Y563500D01*
X1128200Y564083D01*
X1128367Y564500D01*
X1128700Y564750D01*
X1129200Y564833D01*
X1129700Y564750D01*
X1130200Y564500D01*
G01X1134800Y561500D02*
X1134300Y561583D01*
X1133800Y561917D01*
X1133467Y562500D01*
X1133300Y563167D01*
X1133467Y563833D01*
X1133800Y564417D01*
X1134300Y564750D01*
X1134800Y564833D01*
X1135300Y564750D01*
X1135800Y564417D01*
X1136133Y563833D01*
X1136217Y563167D01*
X1136133Y562500D01*
X1135800Y561917D01*
X1135300Y561583D01*
X1134800Y561500D01*
G01X1140400D02*
Y566500D01*
G01X1147500D02*
Y561500D01*
G01Y562250D02*
X1147167Y561833D01*
X1146667Y561583D01*
X1146083Y561500D01*
X1145417Y561667D01*
X1144917Y562083D01*
X1144583Y562583D01*
X1144500Y563167D01*
X1144583Y563750D01*
X1144917Y564250D01*
X1145417Y564667D01*
X1146083Y564833D01*
X1146667Y564750D01*
X1147083Y564583D01*
X1147500Y564250D01*
G01X1150350Y563750D02*
X1153017D01*
X1152767Y564333D01*
X1152350Y564667D01*
X1151767Y564833D01*
X1151183Y564750D01*
X1150683Y564500D01*
X1150350Y563917D01*
X1150183Y563417D01*
Y562917D01*
X1150350Y562417D01*
X1150767Y561917D01*
X1151267Y561583D01*
X1151850Y561500D01*
X1152433Y561667D01*
X1153017Y562167D01*
G01X1156033Y561500D02*
Y564833D01*
G01Y564167D02*
X1156450Y564500D01*
X1156867Y564750D01*
X1157450Y564833D01*
X1157867Y564750D01*
X1158367Y564500D01*
G01X1165900Y561500D02*
Y564833D01*
G01Y563917D02*
X1166150Y564333D01*
X1166567Y564667D01*
X1167150Y564833D01*
X1167733Y564667D01*
X1168150Y564333D01*
X1168400Y563917D01*
Y561500D01*
G01Y563917D02*
X1168650Y564333D01*
X1169067Y564667D01*
X1169650Y564833D01*
X1170233Y564667D01*
X1170650Y564333D01*
X1170900Y563833D01*
Y561500D01*
G01X1175500D02*
Y564833D01*
G01Y564250D02*
X1175167Y564583D01*
X1174667Y564750D01*
X1174083Y564833D01*
X1173500Y564667D01*
X1173000Y564333D01*
X1172667Y563833D01*
X1172500Y563167D01*
X1172667Y562500D01*
X1173000Y562000D01*
X1173500Y561667D01*
X1174083Y561500D01*
X1174667Y561583D01*
X1175167Y561833D01*
X1175500Y562167D01*
G01X1178350Y562083D02*
X1178767Y561750D01*
X1179350Y561500D01*
X1179850D01*
X1180350Y561667D01*
X1180683Y561917D01*
X1180850Y562250D01*
X1180767Y562750D01*
X1180433Y563000D01*
X1178933Y563500D01*
X1178600Y564083D01*
X1178767Y564500D01*
X1179100Y564750D01*
X1179600Y564833D01*
X1180100Y564750D01*
X1180600Y564500D01*
G01X1183783Y561500D02*
Y566500D01*
G01X1186450Y564833D02*
X1183783Y562917D01*
G01X1184867Y563667D02*
X1186617Y561500D01*
G01X1197900D02*
Y564833D01*
G01Y564250D02*
X1197567Y564583D01*
X1197067Y564750D01*
X1196483Y564833D01*
X1195900Y564667D01*
X1195400Y564333D01*
X1195067Y563833D01*
X1194900Y563167D01*
X1195067Y562500D01*
X1195400Y562000D01*
X1195900Y561667D01*
X1196483Y561500D01*
X1197067Y561583D01*
X1197567Y561833D01*
X1197900Y562167D01*
G01X1200583Y561500D02*
Y564833D01*
G01Y564000D02*
X1200917Y564417D01*
X1201417Y564750D01*
X1202083Y564833D01*
X1202667Y564750D01*
X1203167Y564417D01*
X1203417Y563833D01*
Y561500D01*
G01X1209100Y566500D02*
Y561500D01*
G01Y562250D02*
X1208767Y561833D01*
X1208267Y561583D01*
X1207683Y561500D01*
X1207017Y561667D01*
X1206517Y562083D01*
X1206183Y562583D01*
X1206100Y563167D01*
X1206183Y563750D01*
X1206517Y564250D01*
X1207017Y564667D01*
X1207683Y564833D01*
X1208267Y564750D01*
X1208683Y564583D01*
X1209100Y564250D01*
G01X1217383Y561500D02*
Y566500D01*
G01Y564083D02*
X1217800Y564500D01*
X1218217Y564750D01*
X1218883Y564833D01*
X1219383Y564750D01*
X1219967Y564417D01*
X1220217Y563917D01*
Y561500D01*
G01X1224400D02*
X1223900Y561583D01*
X1223400Y561917D01*
X1223067Y562500D01*
X1222900Y563167D01*
X1223067Y563833D01*
X1223400Y564417D01*
X1223900Y564750D01*
X1224400Y564833D01*
X1224900Y564750D01*
X1225400Y564417D01*
X1225733Y563833D01*
X1225817Y563167D01*
X1225733Y562500D01*
X1225400Y561917D01*
X1224900Y561583D01*
X1224400Y561500D01*
G01X1230000D02*
Y566500D01*
G01X1234350Y563750D02*
X1237017D01*
X1236767Y564333D01*
X1236350Y564667D01*
X1235767Y564833D01*
X1235183Y564750D01*
X1234683Y564500D01*
X1234350Y563917D01*
X1234183Y563417D01*
Y562917D01*
X1234350Y562417D01*
X1234767Y561917D01*
X1235267Y561583D01*
X1235850Y561500D01*
X1236433Y561667D01*
X1237017Y562167D01*
G01X1248300Y561500D02*
Y564833D01*
G01Y564250D02*
X1247967Y564583D01*
X1247467Y564750D01*
X1246883Y564833D01*
X1246300Y564667D01*
X1245800Y564333D01*
X1245467Y563833D01*
X1245300Y563167D01*
X1245467Y562500D01*
X1245800Y562000D01*
X1246300Y561667D01*
X1246883Y561500D01*
X1247467Y561583D01*
X1247967Y561833D01*
X1248300Y562167D01*
G01X1252400Y561500D02*
Y566500D01*
G01X1256750Y562083D02*
X1257167Y561750D01*
X1257750Y561500D01*
X1258250D01*
X1258750Y561667D01*
X1259083Y561917D01*
X1259250Y562250D01*
X1259167Y562750D01*
X1258833Y563000D01*
X1257333Y563500D01*
X1257000Y564083D01*
X1257167Y564500D01*
X1257500Y564750D01*
X1258000Y564833D01*
X1258500Y564750D01*
X1259000Y564500D01*
G01X1263600Y561500D02*
X1263100Y561583D01*
X1262600Y561917D01*
X1262267Y562500D01*
X1262100Y563167D01*
X1262267Y563833D01*
X1262600Y564417D01*
X1263100Y564750D01*
X1263600Y564833D01*
X1264100Y564750D01*
X1264600Y564417D01*
X1264933Y563833D01*
X1265017Y563167D01*
X1264933Y562500D01*
X1264600Y561917D01*
X1264100Y561583D01*
X1263600Y561500D01*
G01X1273383D02*
Y564833D01*
G01Y564000D02*
X1273717Y564417D01*
X1274217Y564750D01*
X1274883Y564833D01*
X1275467Y564750D01*
X1275967Y564417D01*
X1276217Y563833D01*
Y561500D01*
G01X1279150Y563750D02*
X1281817D01*
X1281567Y564333D01*
X1281150Y564667D01*
X1280567Y564833D01*
X1279983Y564750D01*
X1279483Y564500D01*
X1279150Y563917D01*
X1278983Y563417D01*
Y562917D01*
X1279150Y562417D01*
X1279567Y561917D01*
X1280067Y561583D01*
X1280650Y561500D01*
X1281233Y561667D01*
X1281817Y562167D01*
G01X1284750Y563750D02*
X1287417D01*
X1287167Y564333D01*
X1286750Y564667D01*
X1286167Y564833D01*
X1285583Y564750D01*
X1285083Y564500D01*
X1284750Y563917D01*
X1284583Y563417D01*
Y562917D01*
X1284750Y562417D01*
X1285167Y561917D01*
X1285667Y561583D01*
X1286250Y561500D01*
X1286833Y561667D01*
X1287417Y562167D01*
G01X1293100Y566500D02*
Y561500D01*
G01Y562250D02*
X1292767Y561833D01*
X1292267Y561583D01*
X1291683Y561500D01*
X1291017Y561667D01*
X1290517Y562083D01*
X1290183Y562583D01*
X1290100Y563167D01*
X1290183Y563750D01*
X1290517Y564250D01*
X1291017Y564667D01*
X1291683Y564833D01*
X1292267Y564750D01*
X1292683Y564583D01*
X1293100Y564250D01*
G01X1302800Y566500D02*
Y561500D01*
G01X1301633Y564833D02*
X1303967D01*
G01X1308400Y561500D02*
X1307900Y561583D01*
X1307400Y561917D01*
X1307067Y562500D01*
X1306900Y563167D01*
X1307067Y563833D01*
X1307400Y564417D01*
X1307900Y564750D01*
X1308400Y564833D01*
X1308900Y564750D01*
X1309400Y564417D01*
X1309733Y563833D01*
X1309817Y563167D01*
X1309733Y562500D01*
X1309400Y561917D01*
X1308900Y561583D01*
X1308400Y561500D01*
G01X1022000Y569500D02*
Y574500D01*
X1021000Y573500D01*
G01Y569500D02*
X1023000D01*
G01X1027600Y569333D02*
X1027433Y569417D01*
Y569583D01*
X1027600Y569667D01*
X1027767Y569583D01*
Y569417D01*
X1027600Y569333D01*
G01X1033200Y574500D02*
Y569500D01*
G01X1031283Y574500D02*
X1035117D01*
G01X1037383Y569500D02*
Y574500D01*
G01Y572083D02*
X1037800Y572500D01*
X1038217Y572750D01*
X1038883Y572833D01*
X1039383Y572750D01*
X1039967Y572417D01*
X1040217Y571917D01*
Y569500D01*
G01X1043150Y571750D02*
X1045817D01*
X1045567Y572333D01*
X1045150Y572667D01*
X1044567Y572833D01*
X1043983Y572750D01*
X1043483Y572500D01*
X1043150Y571917D01*
X1042983Y571417D01*
Y570917D01*
X1043150Y570417D01*
X1043567Y569917D01*
X1044067Y569583D01*
X1044650Y569500D01*
X1045233Y569667D01*
X1045817Y570167D01*
G01X1054350Y570083D02*
X1054767Y569750D01*
X1055350Y569500D01*
X1055850D01*
X1056350Y569667D01*
X1056683Y569917D01*
X1056850Y570250D01*
X1056767Y570750D01*
X1056433Y571000D01*
X1054933Y571500D01*
X1054600Y572083D01*
X1054767Y572500D01*
X1055100Y572750D01*
X1055600Y572833D01*
X1056100Y572750D01*
X1056600Y572500D01*
G01X1061200Y572833D02*
Y569500D01*
G01Y574167D02*
X1061033Y574250D01*
Y574417D01*
X1061200Y574500D01*
X1061367Y574417D01*
Y574250D01*
X1061200Y574167D01*
G01X1068300Y574500D02*
Y569500D01*
G01Y570250D02*
X1067967Y569833D01*
X1067467Y569583D01*
X1066883Y569500D01*
X1066217Y569667D01*
X1065717Y570083D01*
X1065383Y570583D01*
X1065300Y571167D01*
X1065383Y571750D01*
X1065717Y572250D01*
X1066217Y572667D01*
X1066883Y572833D01*
X1067467Y572750D01*
X1067883Y572583D01*
X1068300Y572250D01*
G01X1071150Y571750D02*
X1073817D01*
X1073567Y572333D01*
X1073150Y572667D01*
X1072567Y572833D01*
X1071983Y572750D01*
X1071483Y572500D01*
X1071150Y571917D01*
X1070983Y571417D01*
Y570917D01*
X1071150Y570417D01*
X1071567Y569917D01*
X1072067Y569583D01*
X1072650Y569500D01*
X1073233Y569667D01*
X1073817Y570167D01*
G01X1081517Y572833D02*
X1082517Y569500D01*
X1083600Y572833D01*
X1084683Y569500D01*
X1085683Y572833D01*
G01X1089200D02*
Y569500D01*
G01Y574167D02*
X1089033Y574250D01*
Y574417D01*
X1089200Y574500D01*
X1089367Y574417D01*
Y574250D01*
X1089200Y574167D01*
G01X1094800Y574500D02*
Y569500D01*
G01X1093633Y572833D02*
X1095967D01*
G01X1098983Y569500D02*
Y574500D01*
G01Y572083D02*
X1099400Y572500D01*
X1099817Y572750D01*
X1100483Y572833D01*
X1100983Y572750D01*
X1101567Y572417D01*
X1101817Y571917D01*
Y569500D01*
G01X1106000D02*
X1105500Y569583D01*
X1105000Y569917D01*
X1104667Y570500D01*
X1104500Y571167D01*
X1104667Y571833D01*
X1105000Y572417D01*
X1105500Y572750D01*
X1106000Y572833D01*
X1106500Y572750D01*
X1107000Y572417D01*
X1107333Y571833D01*
X1107417Y571167D01*
X1107333Y570500D01*
X1107000Y569917D01*
X1106500Y569583D01*
X1106000Y569500D01*
G01X1110183Y572833D02*
Y570500D01*
X1110517Y569917D01*
X1111017Y569583D01*
X1111600Y569500D01*
X1112183Y569583D01*
X1112683Y569917D01*
X1113017Y570500D01*
G01Y569500D02*
Y572833D01*
G01X1117200Y574500D02*
Y569500D01*
G01X1116033Y572833D02*
X1118367D01*
G01X1127150Y570083D02*
X1127567Y569750D01*
X1128150Y569500D01*
X1128650D01*
X1129150Y569667D01*
X1129483Y569917D01*
X1129650Y570250D01*
X1129567Y570750D01*
X1129233Y571000D01*
X1127733Y571500D01*
X1127400Y572083D01*
X1127567Y572500D01*
X1127900Y572750D01*
X1128400Y572833D01*
X1128900Y572750D01*
X1129400Y572500D01*
G01X1134000Y569500D02*
X1133500Y569583D01*
X1133000Y569917D01*
X1132667Y570500D01*
X1132500Y571167D01*
X1132667Y571833D01*
X1133000Y572417D01*
X1133500Y572750D01*
X1134000Y572833D01*
X1134500Y572750D01*
X1135000Y572417D01*
X1135333Y571833D01*
X1135417Y571167D01*
X1135333Y570500D01*
X1135000Y569917D01*
X1134500Y569583D01*
X1134000Y569500D01*
G01X1139600D02*
Y574500D01*
G01X1146700D02*
Y569500D01*
G01Y570250D02*
X1146367Y569833D01*
X1145867Y569583D01*
X1145283Y569500D01*
X1144617Y569667D01*
X1144117Y570083D01*
X1143783Y570583D01*
X1143700Y571167D01*
X1143783Y571750D01*
X1144117Y572250D01*
X1144617Y572667D01*
X1145283Y572833D01*
X1145867Y572750D01*
X1146283Y572583D01*
X1146700Y572250D01*
G01X1149550Y571750D02*
X1152217D01*
X1151967Y572333D01*
X1151550Y572667D01*
X1150967Y572833D01*
X1150383Y572750D01*
X1149883Y572500D01*
X1149550Y571917D01*
X1149383Y571417D01*
Y570917D01*
X1149550Y570417D01*
X1149967Y569917D01*
X1150467Y569583D01*
X1151050Y569500D01*
X1151633Y569667D01*
X1152217Y570167D01*
G01X1155233Y569500D02*
Y572833D01*
G01Y572167D02*
X1155650Y572500D01*
X1156067Y572750D01*
X1156650Y572833D01*
X1157067Y572750D01*
X1157567Y572500D01*
G01X1165100Y569500D02*
Y572833D01*
G01Y571917D02*
X1165350Y572333D01*
X1165767Y572667D01*
X1166350Y572833D01*
X1166933Y572667D01*
X1167350Y572333D01*
X1167600Y571917D01*
Y569500D01*
G01Y571917D02*
X1167850Y572333D01*
X1168267Y572667D01*
X1168850Y572833D01*
X1169433Y572667D01*
X1169850Y572333D01*
X1170100Y571833D01*
Y569500D01*
G01X1174700D02*
Y572833D01*
G01Y572250D02*
X1174367Y572583D01*
X1173867Y572750D01*
X1173283Y572833D01*
X1172700Y572667D01*
X1172200Y572333D01*
X1171867Y571833D01*
X1171700Y571167D01*
X1171867Y570500D01*
X1172200Y570000D01*
X1172700Y569667D01*
X1173283Y569500D01*
X1173867Y569583D01*
X1174367Y569833D01*
X1174700Y570167D01*
G01X1177550Y570083D02*
X1177967Y569750D01*
X1178550Y569500D01*
X1179050D01*
X1179550Y569667D01*
X1179883Y569917D01*
X1180050Y570250D01*
X1179967Y570750D01*
X1179633Y571000D01*
X1178133Y571500D01*
X1177800Y572083D01*
X1177967Y572500D01*
X1178300Y572750D01*
X1178800Y572833D01*
X1179300Y572750D01*
X1179800Y572500D01*
G01X1182983Y569500D02*
Y574500D01*
G01X1185650Y572833D02*
X1182983Y570917D01*
G01X1184067Y571667D02*
X1185817Y569500D01*
G01X1194100Y567833D02*
Y572833D01*
G01Y572083D02*
X1194517Y572500D01*
X1194933Y572750D01*
X1195600Y572833D01*
X1196183Y572750D01*
X1196767Y572333D01*
X1197017Y571750D01*
X1197100Y571167D01*
X1197017Y570583D01*
X1196767Y570000D01*
X1196267Y569667D01*
X1195600Y569500D01*
X1195017Y569583D01*
X1194433Y569833D01*
X1194100Y570167D01*
G01X1202700Y569500D02*
Y572833D01*
G01Y572250D02*
X1202367Y572583D01*
X1201867Y572750D01*
X1201283Y572833D01*
X1200700Y572667D01*
X1200200Y572333D01*
X1199867Y571833D01*
X1199700Y571167D01*
X1199867Y570500D01*
X1200200Y570000D01*
X1200700Y569667D01*
X1201283Y569500D01*
X1201867Y569583D01*
X1202367Y569833D01*
X1202700Y570167D01*
G01X1208300Y574500D02*
Y569500D01*
G01Y570250D02*
X1207967Y569833D01*
X1207467Y569583D01*
X1206883Y569500D01*
X1206217Y569667D01*
X1205717Y570083D01*
X1205383Y570583D01*
X1205300Y571167D01*
X1205383Y571750D01*
X1205717Y572250D01*
X1206217Y572667D01*
X1206883Y572833D01*
X1207467Y572750D01*
X1207883Y572583D01*
X1208300Y572250D01*
G01X1217833Y568583D02*
X1218167Y569667D01*
G01X1230700Y569500D02*
Y572833D01*
G01Y572250D02*
X1230367Y572583D01*
X1229867Y572750D01*
X1229283Y572833D01*
X1228700Y572667D01*
X1228200Y572333D01*
X1227867Y571833D01*
X1227700Y571167D01*
X1227867Y570500D01*
X1228200Y570000D01*
X1228700Y569667D01*
X1229283Y569500D01*
X1229867Y569583D01*
X1230367Y569833D01*
X1230700Y570167D01*
G01X1233383Y569500D02*
Y572833D01*
G01Y572000D02*
X1233717Y572417D01*
X1234217Y572750D01*
X1234883Y572833D01*
X1235467Y572750D01*
X1235967Y572417D01*
X1236217Y571833D01*
Y569500D01*
G01X1238983D02*
Y572833D01*
G01Y572000D02*
X1239317Y572417D01*
X1239817Y572750D01*
X1240483Y572833D01*
X1241067Y572750D01*
X1241567Y572417D01*
X1241817Y571833D01*
Y569500D01*
G01X1244583Y572833D02*
Y570500D01*
X1244917Y569917D01*
X1245417Y569583D01*
X1246000Y569500D01*
X1246583Y569583D01*
X1247083Y569917D01*
X1247417Y570500D01*
G01Y569500D02*
Y572833D01*
G01X1253100Y569500D02*
Y572833D01*
G01Y572250D02*
X1252767Y572583D01*
X1252267Y572750D01*
X1251683Y572833D01*
X1251100Y572667D01*
X1250600Y572333D01*
X1250267Y571833D01*
X1250100Y571167D01*
X1250267Y570500D01*
X1250600Y570000D01*
X1251100Y569667D01*
X1251683Y569500D01*
X1252267Y569583D01*
X1252767Y569833D01*
X1253100Y570167D01*
G01X1257200Y569500D02*
Y574500D01*
G01X1267233Y569500D02*
Y572833D01*
G01Y572167D02*
X1267650Y572500D01*
X1268067Y572750D01*
X1268650Y572833D01*
X1269067Y572750D01*
X1269567Y572500D01*
G01X1274000Y572833D02*
Y569500D01*
G01Y574167D02*
X1273833Y574250D01*
Y574417D01*
X1274000Y574500D01*
X1274167Y574417D01*
Y574250D01*
X1274000Y574167D01*
G01X1278183Y569500D02*
Y572833D01*
G01Y572000D02*
X1278517Y572417D01*
X1279017Y572750D01*
X1279683Y572833D01*
X1280267Y572750D01*
X1280767Y572417D01*
X1281017Y571833D01*
Y569500D01*
G01X1284033Y568250D02*
X1284617Y567917D01*
X1285283Y567833D01*
X1285867Y567917D01*
X1286367Y568333D01*
X1286700Y568917D01*
Y572833D01*
G01Y572167D02*
X1286367Y572500D01*
X1285867Y572750D01*
X1285283Y572833D01*
X1284617Y572667D01*
X1284200Y572333D01*
X1283867Y571750D01*
X1283700Y571167D01*
X1283783Y570667D01*
X1284117Y570083D01*
X1284617Y569667D01*
X1285283Y569500D01*
X1285783Y569583D01*
X1286367Y569917D01*
X1286700Y570250D01*
G01X1294983Y569500D02*
Y572833D01*
G01Y572000D02*
X1295317Y572417D01*
X1295817Y572750D01*
X1296483Y572833D01*
X1297067Y572750D01*
X1297567Y572417D01*
X1297817Y571833D01*
Y569500D01*
G01X1300750Y571750D02*
X1303417D01*
X1303167Y572333D01*
X1302750Y572667D01*
X1302167Y572833D01*
X1301583Y572750D01*
X1301083Y572500D01*
X1300750Y571917D01*
X1300583Y571417D01*
Y570917D01*
X1300750Y570417D01*
X1301167Y569917D01*
X1301667Y569583D01*
X1302250Y569500D01*
X1302833Y569667D01*
X1303417Y570167D01*
G01X1306350Y571750D02*
X1309017D01*
X1308767Y572333D01*
X1308350Y572667D01*
X1307767Y572833D01*
X1307183Y572750D01*
X1306683Y572500D01*
X1306350Y571917D01*
X1306183Y571417D01*
Y570917D01*
X1306350Y570417D01*
X1306767Y569917D01*
X1307267Y569583D01*
X1307850Y569500D01*
X1308433Y569667D01*
X1309017Y570167D01*
G01X1314700Y574500D02*
Y569500D01*
G01Y570250D02*
X1314367Y569833D01*
X1313867Y569583D01*
X1313283Y569500D01*
X1312617Y569667D01*
X1312117Y570083D01*
X1311783Y570583D01*
X1311700Y571167D01*
X1311783Y571750D01*
X1312117Y572250D01*
X1312617Y572667D01*
X1313283Y572833D01*
X1313867Y572750D01*
X1314283Y572583D01*
X1314700Y572250D01*
G01X1012083Y730500D02*
Y733833D01*
G01Y733000D02*
X1012417Y733417D01*
X1012917Y733750D01*
X1013583Y733833D01*
X1014167Y733750D01*
X1014667Y733417D01*
X1014917Y732833D01*
Y730500D01*
G01X1019100D02*
X1018600Y730583D01*
X1018100Y730917D01*
X1017767Y731500D01*
X1017600Y732167D01*
X1017767Y732833D01*
X1018100Y733417D01*
X1018600Y733750D01*
X1019100Y733833D01*
X1019600Y733750D01*
X1020100Y733417D01*
X1020433Y732833D01*
X1020517Y732167D01*
X1020433Y731500D01*
X1020100Y730917D01*
X1019600Y730583D01*
X1019100Y730500D01*
G01X1028800Y728833D02*
Y733833D01*
G01Y733083D02*
X1029217Y733500D01*
X1029633Y733750D01*
X1030300Y733833D01*
X1030883Y733750D01*
X1031467Y733333D01*
X1031717Y732750D01*
X1031800Y732167D01*
X1031717Y731583D01*
X1031467Y731000D01*
X1030967Y730667D01*
X1030300Y730500D01*
X1029717Y730583D01*
X1029133Y730833D01*
X1028800Y731167D01*
G01X1035900Y730500D02*
Y735500D01*
G01X1040083Y733833D02*
Y731500D01*
X1040417Y730917D01*
X1040917Y730583D01*
X1041500Y730500D01*
X1042083Y730583D01*
X1042583Y730917D01*
X1042917Y731500D01*
G01Y730500D02*
Y733833D01*
G01X1045933Y729250D02*
X1046517Y728917D01*
X1047183Y728833D01*
X1047767Y728917D01*
X1048267Y729333D01*
X1048600Y729917D01*
Y733833D01*
G01Y733167D02*
X1048267Y733500D01*
X1047767Y733750D01*
X1047183Y733833D01*
X1046517Y733667D01*
X1046100Y733333D01*
X1045767Y732750D01*
X1045600Y732167D01*
X1045683Y731667D01*
X1046017Y731083D01*
X1046517Y730667D01*
X1047183Y730500D01*
X1047683Y730583D01*
X1048267Y730917D01*
X1048600Y731250D01*
G01X1051533Y729250D02*
X1052117Y728917D01*
X1052783Y728833D01*
X1053367Y728917D01*
X1053867Y729333D01*
X1054200Y729917D01*
Y733833D01*
G01Y733167D02*
X1053867Y733500D01*
X1053367Y733750D01*
X1052783Y733833D01*
X1052117Y733667D01*
X1051700Y733333D01*
X1051367Y732750D01*
X1051200Y732167D01*
X1051283Y731667D01*
X1051617Y731083D01*
X1052117Y730667D01*
X1052783Y730500D01*
X1053283Y730583D01*
X1053867Y730917D01*
X1054200Y731250D01*
G01X1058300Y733833D02*
Y730500D01*
G01Y735167D02*
X1058133Y735250D01*
Y735417D01*
X1058300Y735500D01*
X1058467Y735417D01*
Y735250D01*
X1058300Y735167D01*
G01X1062483Y730500D02*
Y733833D01*
G01Y733000D02*
X1062817Y733417D01*
X1063317Y733750D01*
X1063983Y733833D01*
X1064567Y733750D01*
X1065067Y733417D01*
X1065317Y732833D01*
Y730500D01*
G01X1068333Y729250D02*
X1068917Y728917D01*
X1069583Y728833D01*
X1070167Y728917D01*
X1070667Y729333D01*
X1071000Y729917D01*
Y733833D01*
G01Y733167D02*
X1070667Y733500D01*
X1070167Y733750D01*
X1069583Y733833D01*
X1068917Y733667D01*
X1068500Y733333D01*
X1068167Y732750D01*
X1068000Y732167D01*
X1068083Y731667D01*
X1068417Y731083D01*
X1068917Y730667D01*
X1069583Y730500D01*
X1070083Y730583D01*
X1070667Y730917D01*
X1071000Y731250D01*
G01X1087667Y124000D02*
Y129000D01*
X1089333D01*
X1090000Y128750D01*
X1090500Y128417D01*
X1090917Y127917D01*
X1091250Y127333D01*
X1091333Y126500D01*
X1091250Y125667D01*
X1090917Y125083D01*
X1090500Y124583D01*
X1090000Y124250D01*
X1089333Y124000D01*
X1087667D01*
G01X1093933D02*
Y127333D01*
G01Y126667D02*
X1094350Y127000D01*
X1094767Y127250D01*
X1095350Y127333D01*
X1095767Y127250D01*
X1096267Y127000D01*
G01X1100700Y127333D02*
Y124000D01*
G01Y128667D02*
X1100533Y128750D01*
Y128917D01*
X1100700Y129000D01*
X1100867Y128917D01*
Y128750D01*
X1100700Y128667D01*
G01X1106300Y124000D02*
Y129000D01*
G01X1111900Y124000D02*
Y129000D01*
G01X1121517Y124000D02*
Y129000D01*
X1124683D01*
G01X1123517Y126583D02*
X1121517D01*
G01X1127533Y124000D02*
Y127333D01*
G01Y126667D02*
X1127950Y127000D01*
X1128367Y127250D01*
X1128950Y127333D01*
X1129367Y127250D01*
X1129867Y127000D01*
G01X1134300Y124000D02*
X1133800Y124083D01*
X1133300Y124417D01*
X1132967Y125000D01*
X1132800Y125667D01*
X1132967Y126333D01*
X1133300Y126917D01*
X1133800Y127250D01*
X1134300Y127333D01*
X1134800Y127250D01*
X1135300Y126917D01*
X1135633Y126333D01*
X1135717Y125667D01*
X1135633Y125000D01*
X1135300Y124417D01*
X1134800Y124083D01*
X1134300Y124000D01*
G01X1137400D02*
Y127333D01*
G01Y126417D02*
X1137650Y126833D01*
X1138067Y127167D01*
X1138650Y127333D01*
X1139233Y127167D01*
X1139650Y126833D01*
X1139900Y126417D01*
Y124000D01*
G01Y126417D02*
X1140150Y126833D01*
X1140567Y127167D01*
X1141150Y127333D01*
X1141733Y127167D01*
X1142150Y126833D01*
X1142400Y126333D01*
Y124000D01*
G01X1167483Y122333D02*
X1166650Y123167D01*
X1166233Y124000D01*
Y127333D01*
X1166650Y128167D01*
X1167483Y129000D01*
G01X1174167Y126667D02*
X1174500Y126917D01*
X1174750Y127333D01*
X1174917Y127917D01*
X1174750Y128417D01*
X1174417Y128750D01*
X1173833Y129000D01*
X1171583D01*
Y124000D01*
X1174333D01*
X1174917Y124333D01*
X1175250Y124833D01*
X1175417Y125417D01*
X1175250Y126000D01*
X1174750Y126500D01*
X1174167Y126667D01*
X1171583D01*
G01X1179100Y124000D02*
X1178433Y124083D01*
X1177850Y124417D01*
X1177350Y124917D01*
X1177017Y125500D01*
X1176850Y126167D01*
Y126833D01*
X1177017Y127500D01*
X1177350Y128083D01*
X1177850Y128583D01*
X1178433Y128917D01*
X1179100Y129000D01*
X1179767Y128917D01*
X1180350Y128583D01*
X1180850Y128083D01*
X1181183Y127500D01*
X1181350Y126833D01*
Y126167D01*
X1181183Y125500D01*
X1180850Y124917D01*
X1180350Y124417D01*
X1179767Y124083D01*
X1179100Y124000D01*
G01X1184700Y129000D02*
Y124000D01*
G01X1182783Y129000D02*
X1186617D01*
G01X1190300D02*
Y124000D01*
G01X1188383Y129000D02*
X1192217D01*
G01X1195900Y124000D02*
X1195233Y124083D01*
X1194650Y124417D01*
X1194150Y124917D01*
X1193817Y125500D01*
X1193650Y126167D01*
Y126833D01*
X1193817Y127500D01*
X1194150Y128083D01*
X1194650Y128583D01*
X1195233Y128917D01*
X1195900Y129000D01*
X1196567Y128917D01*
X1197150Y128583D01*
X1197650Y128083D01*
X1197983Y127500D01*
X1198150Y126833D01*
Y126167D01*
X1197983Y125500D01*
X1197650Y124917D01*
X1197150Y124417D01*
X1196567Y124083D01*
X1195900Y124000D01*
G01X1199333D02*
Y129000D01*
X1201500Y124833D01*
X1203667Y129000D01*
Y124000D01*
G01X1207517Y122333D02*
X1208350Y123167D01*
X1208767Y124000D01*
Y127333D01*
X1208350Y128167D01*
X1207517Y129000D01*
G01X1218300D02*
Y124000D01*
G01X1217133Y127333D02*
X1219467D01*
G01X1223900Y124000D02*
X1223400Y124083D01*
X1222900Y124417D01*
X1222567Y125000D01*
X1222400Y125667D01*
X1222567Y126333D01*
X1222900Y126917D01*
X1223400Y127250D01*
X1223900Y127333D01*
X1224400Y127250D01*
X1224900Y126917D01*
X1225233Y126333D01*
X1225317Y125667D01*
X1225233Y125000D01*
X1224900Y124417D01*
X1224400Y124083D01*
X1223900Y124000D01*
G01X1233433Y129000D02*
Y124000D01*
X1236767D01*
G01X1239450Y127333D02*
X1241950Y124000D01*
G01Y127333D02*
X1239450Y124000D01*
G01X1136167Y157700D02*
Y162700D01*
X1137833D01*
X1138500Y162450D01*
X1139000Y162117D01*
X1139417Y161617D01*
X1139750Y161033D01*
X1139833Y160200D01*
X1139750Y159367D01*
X1139417Y158783D01*
X1139000Y158283D01*
X1138500Y157950D01*
X1137833Y157700D01*
X1136167D01*
G01X1142017Y161867D02*
X1142517Y162367D01*
X1143100Y162617D01*
X1143767Y162700D01*
X1144600Y162533D01*
X1145183Y162117D01*
X1145350Y161617D01*
X1145267Y161117D01*
X1144933Y160700D01*
X1143267Y159867D01*
X1142517Y159283D01*
X1142017Y158450D01*
X1141850Y157700D01*
X1145350D01*
G01X1089493Y104700D02*
Y99700D01*
X1092827D01*
G01X1095510Y103033D02*
X1098010Y99700D01*
G01Y103033D02*
X1095510Y99700D01*
G01X1102360Y99533D02*
X1102193Y99617D01*
Y99783D01*
X1102360Y99867D01*
X1102527Y99783D01*
Y99617D01*
X1102360Y99533D01*
G01Y101783D02*
X1102193Y101867D01*
Y102033D01*
X1102360Y102117D01*
X1102527Y102033D01*
Y101867D01*
X1102360Y101783D01*
G01X1111060Y99700D02*
Y103033D01*
G01Y102117D02*
X1111310Y102533D01*
X1111727Y102867D01*
X1112310Y103033D01*
X1112893Y102867D01*
X1113310Y102533D01*
X1113560Y102117D01*
Y99700D01*
G01Y102117D02*
X1113810Y102533D01*
X1114227Y102867D01*
X1114810Y103033D01*
X1115393Y102867D01*
X1115810Y102533D01*
X1116060Y102033D01*
Y99700D01*
G01X1117743Y103033D02*
Y100700D01*
X1118077Y100117D01*
X1118577Y99783D01*
X1119160Y99700D01*
X1119743Y99783D01*
X1120243Y100117D01*
X1120577Y100700D01*
G01Y99700D02*
Y103033D01*
G01X1123510Y100283D02*
X1123927Y99950D01*
X1124510Y99700D01*
X1125010D01*
X1125510Y99867D01*
X1125843Y100117D01*
X1126010Y100450D01*
X1125927Y100950D01*
X1125593Y101200D01*
X1124093Y101700D01*
X1123760Y102283D01*
X1123927Y102700D01*
X1124260Y102950D01*
X1124760Y103033D01*
X1125260Y102950D01*
X1125760Y102700D01*
G01X1130360Y104700D02*
Y99700D01*
G01X1129193Y103033D02*
X1131527D01*
G01X1140060Y99700D02*
Y104700D01*
G01Y102200D02*
X1140477Y102700D01*
X1140977Y102950D01*
X1141477Y103033D01*
X1142227Y102867D01*
X1142727Y102533D01*
X1143060Y101950D01*
Y101283D01*
X1142893Y100617D01*
X1142560Y100117D01*
X1141977Y99783D01*
X1141477Y99700D01*
X1140977Y99783D01*
X1140477Y100033D01*
X1140060Y100450D01*
G01X1145910Y101950D02*
X1148577D01*
X1148327Y102533D01*
X1147910Y102867D01*
X1147327Y103033D01*
X1146743Y102950D01*
X1146243Y102700D01*
X1145910Y102117D01*
X1145743Y101617D01*
Y101117D01*
X1145910Y100617D01*
X1146327Y100117D01*
X1146827Y99783D01*
X1147410Y99700D01*
X1147993Y99867D01*
X1148577Y100367D01*
G01X1156860Y99700D02*
Y104700D01*
G01Y102200D02*
X1157277Y102700D01*
X1157777Y102950D01*
X1158277Y103033D01*
X1159027Y102867D01*
X1159527Y102533D01*
X1159860Y101950D01*
Y101283D01*
X1159693Y100617D01*
X1159360Y100117D01*
X1158777Y99783D01*
X1158277Y99700D01*
X1157777Y99783D01*
X1157277Y100033D01*
X1156860Y100450D01*
G01X1162793Y99700D02*
Y103033D01*
G01Y102367D02*
X1163210Y102700D01*
X1163627Y102950D01*
X1164210Y103033D01*
X1164627Y102950D01*
X1165127Y102700D01*
G01X1169560Y99700D02*
X1169060Y99783D01*
X1168560Y100117D01*
X1168227Y100700D01*
X1168060Y101367D01*
X1168227Y102033D01*
X1168560Y102617D01*
X1169060Y102950D01*
X1169560Y103033D01*
X1170060Y102950D01*
X1170560Y102617D01*
X1170893Y102033D01*
X1170977Y101367D01*
X1170893Y100700D01*
X1170560Y100117D01*
X1170060Y99783D01*
X1169560Y99700D01*
G01X1173743D02*
Y104700D01*
G01X1176410Y103033D02*
X1173743Y101117D01*
G01X1174827Y101867D02*
X1176577Y99700D01*
G01X1179510Y101950D02*
X1182177D01*
X1181927Y102533D01*
X1181510Y102867D01*
X1180927Y103033D01*
X1180343Y102950D01*
X1179843Y102700D01*
X1179510Y102117D01*
X1179343Y101617D01*
Y101117D01*
X1179510Y100617D01*
X1179927Y100117D01*
X1180427Y99783D01*
X1181010Y99700D01*
X1181593Y99867D01*
X1182177Y100367D01*
G01X1184943Y99700D02*
Y103033D01*
G01Y102200D02*
X1185277Y102617D01*
X1185777Y102950D01*
X1186443Y103033D01*
X1187027Y102950D01*
X1187527Y102617D01*
X1187777Y102033D01*
Y99700D01*
G01X1197560D02*
Y104700D01*
G01X1204660Y99700D02*
Y103033D01*
G01Y102450D02*
X1204327Y102783D01*
X1203827Y102950D01*
X1203243Y103033D01*
X1202660Y102867D01*
X1202160Y102533D01*
X1201827Y102033D01*
X1201660Y101367D01*
X1201827Y100700D01*
X1202160Y100200D01*
X1202660Y99867D01*
X1203243Y99700D01*
X1203827Y99783D01*
X1204327Y100033D01*
X1204660Y100367D01*
G01X1207010Y98200D02*
X1207510Y98033D01*
X1208177Y98200D01*
X1208593Y98533D01*
X1208927Y98950D01*
X1209427Y100283D01*
X1210510Y103033D01*
G01X1207843D02*
X1209427Y100283D01*
G01X1213110Y101950D02*
X1215777D01*
X1215527Y102533D01*
X1215110Y102867D01*
X1214527Y103033D01*
X1213943Y102950D01*
X1213443Y102700D01*
X1213110Y102117D01*
X1212943Y101617D01*
Y101117D01*
X1213110Y100617D01*
X1213527Y100117D01*
X1214027Y99783D01*
X1214610Y99700D01*
X1215193Y99867D01*
X1215777Y100367D01*
G01X1218793Y99700D02*
Y103033D01*
G01Y102367D02*
X1219210Y102700D01*
X1219627Y102950D01*
X1220210Y103033D01*
X1220627Y102950D01*
X1221127Y102700D01*
G01X1088893Y117200D02*
Y112200D01*
X1092227D01*
G01X1094743D02*
Y115533D01*
G01Y114700D02*
X1095077Y115117D01*
X1095577Y115450D01*
X1096243Y115533D01*
X1096827Y115450D01*
X1097327Y115117D01*
X1097577Y114533D01*
Y112200D01*
G01X1101760Y112033D02*
X1101593Y112117D01*
Y112283D01*
X1101760Y112367D01*
X1101927Y112283D01*
Y112117D01*
X1101760Y112033D01*
G01Y114283D02*
X1101593Y114367D01*
Y114533D01*
X1101760Y114617D01*
X1101927Y114533D01*
Y114367D01*
X1101760Y114283D01*
G01X1114293Y115117D02*
X1113710Y115450D01*
X1113210Y115533D01*
X1112543Y115367D01*
X1112043Y115033D01*
X1111710Y114450D01*
X1111627Y113867D01*
X1111710Y113283D01*
X1112043Y112783D01*
X1112543Y112367D01*
X1113210Y112200D01*
X1113793Y112367D01*
X1114293Y112700D01*
G01X1120060Y112200D02*
Y115533D01*
G01Y114950D02*
X1119727Y115283D01*
X1119227Y115450D01*
X1118643Y115533D01*
X1118060Y115367D01*
X1117560Y115033D01*
X1117227Y114533D01*
X1117060Y113867D01*
X1117227Y113200D01*
X1117560Y112700D01*
X1118060Y112367D01*
X1118643Y112200D01*
X1119227Y112283D01*
X1119727Y112533D01*
X1120060Y112867D01*
G01X1122743Y112200D02*
Y115533D01*
G01Y114700D02*
X1123077Y115117D01*
X1123577Y115450D01*
X1124243Y115533D01*
X1124827Y115450D01*
X1125327Y115117D01*
X1125577Y114533D01*
Y112200D01*
G01X1129760Y115533D02*
X1130593Y116575D01*
Y117200D01*
X1129968D01*
Y116575D01*
X1130593D01*
G01X1135360Y117200D02*
Y112200D01*
G01X1134193Y115533D02*
X1136527D01*
G01X1145060Y112200D02*
Y117200D01*
G01Y114700D02*
X1145477Y115200D01*
X1145977Y115450D01*
X1146477Y115533D01*
X1147227Y115367D01*
X1147727Y115033D01*
X1148060Y114450D01*
Y113783D01*
X1147893Y113117D01*
X1147560Y112617D01*
X1146977Y112283D01*
X1146477Y112200D01*
X1145977Y112283D01*
X1145477Y112533D01*
X1145060Y112950D01*
G01X1150910Y114450D02*
X1153577D01*
X1153327Y115033D01*
X1152910Y115367D01*
X1152327Y115533D01*
X1151743Y115450D01*
X1151243Y115200D01*
X1150910Y114617D01*
X1150743Y114117D01*
Y113617D01*
X1150910Y113117D01*
X1151327Y112617D01*
X1151827Y112283D01*
X1152410Y112200D01*
X1152993Y112367D01*
X1153577Y112867D01*
G01X1161860Y112200D02*
Y117200D01*
G01Y114700D02*
X1162277Y115200D01*
X1162777Y115450D01*
X1163277Y115533D01*
X1164027Y115367D01*
X1164527Y115033D01*
X1164860Y114450D01*
Y113783D01*
X1164693Y113117D01*
X1164360Y112617D01*
X1163777Y112283D01*
X1163277Y112200D01*
X1162777Y112283D01*
X1162277Y112533D01*
X1161860Y112950D01*
G01X1167793Y112200D02*
Y115533D01*
G01Y114867D02*
X1168210Y115200D01*
X1168627Y115450D01*
X1169210Y115533D01*
X1169627Y115450D01*
X1170127Y115200D01*
G01X1174560Y112200D02*
X1174060Y112283D01*
X1173560Y112617D01*
X1173227Y113200D01*
X1173060Y113867D01*
X1173227Y114533D01*
X1173560Y115117D01*
X1174060Y115450D01*
X1174560Y115533D01*
X1175060Y115450D01*
X1175560Y115117D01*
X1175893Y114533D01*
X1175977Y113867D01*
X1175893Y113200D01*
X1175560Y112617D01*
X1175060Y112283D01*
X1174560Y112200D01*
G01X1178743D02*
Y117200D01*
G01X1181410Y115533D02*
X1178743Y113617D01*
G01X1179827Y114367D02*
X1181577Y112200D01*
G01X1184510Y114450D02*
X1187177D01*
X1186927Y115033D01*
X1186510Y115367D01*
X1185927Y115533D01*
X1185343Y115450D01*
X1184843Y115200D01*
X1184510Y114617D01*
X1184343Y114117D01*
Y113617D01*
X1184510Y113117D01*
X1184927Y112617D01*
X1185427Y112283D01*
X1186010Y112200D01*
X1186593Y112367D01*
X1187177Y112867D01*
G01X1189943Y112200D02*
Y115533D01*
G01Y114700D02*
X1190277Y115117D01*
X1190777Y115450D01*
X1191443Y115533D01*
X1192027Y115450D01*
X1192527Y115117D01*
X1192777Y114533D01*
Y112200D01*
G01X1202560D02*
Y117200D01*
G01X1209660Y112200D02*
Y115533D01*
G01Y114950D02*
X1209327Y115283D01*
X1208827Y115450D01*
X1208243Y115533D01*
X1207660Y115367D01*
X1207160Y115033D01*
X1206827Y114533D01*
X1206660Y113867D01*
X1206827Y113200D01*
X1207160Y112700D01*
X1207660Y112367D01*
X1208243Y112200D01*
X1208827Y112283D01*
X1209327Y112533D01*
X1209660Y112867D01*
G01X1212010Y110700D02*
X1212510Y110533D01*
X1213177Y110700D01*
X1213593Y111033D01*
X1213927Y111450D01*
X1214427Y112783D01*
X1215510Y115533D01*
G01X1212843D02*
X1214427Y112783D01*
G01X1218110Y114450D02*
X1220777D01*
X1220527Y115033D01*
X1220110Y115367D01*
X1219527Y115533D01*
X1218943Y115450D01*
X1218443Y115200D01*
X1218110Y114617D01*
X1217943Y114117D01*
Y113617D01*
X1218110Y113117D01*
X1218527Y112617D01*
X1219027Y112283D01*
X1219610Y112200D01*
X1220193Y112367D01*
X1220777Y112867D01*
G01X1223793Y112200D02*
Y115533D01*
G01Y114867D02*
X1224210Y115200D01*
X1224627Y115450D01*
X1225210Y115533D01*
X1225627Y115450D01*
X1226127Y115200D01*
G01X1135167Y315700D02*
Y320700D01*
X1136833D01*
X1137500Y320450D01*
X1138000Y320117D01*
X1138417Y319617D01*
X1138750Y319033D01*
X1138833Y318200D01*
X1138750Y317367D01*
X1138417Y316783D01*
X1138000Y316283D01*
X1137500Y315950D01*
X1136833Y315700D01*
X1135167D01*
G01X1142600D02*
Y320700D01*
X1141600Y319700D01*
G01Y315700D02*
X1143600D01*
G01X1136833Y619917D02*
X1136250Y620250D01*
X1135750Y620333D01*
X1135083Y620167D01*
X1134583Y619833D01*
X1134250Y619250D01*
X1134167Y618667D01*
X1134250Y618083D01*
X1134583Y617583D01*
X1135083Y617167D01*
X1135750Y617000D01*
X1136333Y617167D01*
X1136833Y617500D01*
G01X1141100Y617000D02*
X1140600Y617083D01*
X1140100Y617417D01*
X1139767Y618000D01*
X1139600Y618667D01*
X1139767Y619333D01*
X1140100Y619917D01*
X1140600Y620250D01*
X1141100Y620333D01*
X1141600Y620250D01*
X1142100Y619917D01*
X1142433Y619333D01*
X1142517Y618667D01*
X1142433Y618000D01*
X1142100Y617417D01*
X1141600Y617083D01*
X1141100Y617000D01*
G01X1145200Y615333D02*
Y620333D01*
G01Y619583D02*
X1145617Y620000D01*
X1146033Y620250D01*
X1146700Y620333D01*
X1147283Y620250D01*
X1147867Y619833D01*
X1148117Y619250D01*
X1148200Y618667D01*
X1148117Y618083D01*
X1147867Y617500D01*
X1147367Y617167D01*
X1146700Y617000D01*
X1146117Y617083D01*
X1145533Y617333D01*
X1145200Y617667D01*
G01X1150800Y615333D02*
Y620333D01*
G01Y619583D02*
X1151217Y620000D01*
X1151633Y620250D01*
X1152300Y620333D01*
X1152883Y620250D01*
X1153467Y619833D01*
X1153717Y619250D01*
X1153800Y618667D01*
X1153717Y618083D01*
X1153467Y617500D01*
X1152967Y617167D01*
X1152300Y617000D01*
X1151717Y617083D01*
X1151133Y617333D01*
X1150800Y617667D01*
G01X1156650Y619250D02*
X1159317D01*
X1159067Y619833D01*
X1158650Y620167D01*
X1158067Y620333D01*
X1157483Y620250D01*
X1156983Y620000D01*
X1156650Y619417D01*
X1156483Y618917D01*
Y618417D01*
X1156650Y617917D01*
X1157067Y617417D01*
X1157567Y617083D01*
X1158150Y617000D01*
X1158733Y617167D01*
X1159317Y617667D01*
G01X1162333Y617000D02*
Y620333D01*
G01Y619667D02*
X1162750Y620000D01*
X1163167Y620250D01*
X1163750Y620333D01*
X1164167Y620250D01*
X1164667Y620000D01*
G01X1109833Y590500D02*
Y595500D01*
X1111833D01*
X1112500Y595250D01*
X1113000Y594667D01*
X1113167Y594000D01*
X1113000Y593333D01*
X1112583Y592833D01*
X1111833Y592583D01*
X1109833D01*
G01X1117100Y590500D02*
Y595500D01*
G01X1121283Y593833D02*
Y591500D01*
X1121617Y590917D01*
X1122117Y590583D01*
X1122700Y590500D01*
X1123283Y590583D01*
X1123783Y590917D01*
X1124117Y591500D01*
G01Y590500D02*
Y593833D01*
G01X1127133Y589250D02*
X1127717Y588917D01*
X1128383Y588833D01*
X1128967Y588917D01*
X1129467Y589333D01*
X1129800Y589917D01*
Y593833D01*
G01Y593167D02*
X1129467Y593500D01*
X1128967Y593750D01*
X1128383Y593833D01*
X1127717Y593667D01*
X1127300Y593333D01*
X1126967Y592750D01*
X1126800Y592167D01*
X1126883Y591667D01*
X1127217Y591083D01*
X1127717Y590667D01*
X1128383Y590500D01*
X1128883Y590583D01*
X1129467Y590917D01*
X1129800Y591250D01*
G01X1132733Y589250D02*
X1133317Y588917D01*
X1133983Y588833D01*
X1134567Y588917D01*
X1135067Y589333D01*
X1135400Y589917D01*
Y593833D01*
G01Y593167D02*
X1135067Y593500D01*
X1134567Y593750D01*
X1133983Y593833D01*
X1133317Y593667D01*
X1132900Y593333D01*
X1132567Y592750D01*
X1132400Y592167D01*
X1132483Y591667D01*
X1132817Y591083D01*
X1133317Y590667D01*
X1133983Y590500D01*
X1134483Y590583D01*
X1135067Y590917D01*
X1135400Y591250D01*
G01X1139500Y593833D02*
Y590500D01*
G01Y595167D02*
X1139333Y595250D01*
Y595417D01*
X1139500Y595500D01*
X1139667Y595417D01*
Y595250D01*
X1139500Y595167D01*
G01X1143683Y590500D02*
Y593833D01*
G01Y593000D02*
X1144017Y593417D01*
X1144517Y593750D01*
X1145183Y593833D01*
X1145767Y593750D01*
X1146267Y593417D01*
X1146517Y592833D01*
Y590500D01*
G01X1149533Y589250D02*
X1150117Y588917D01*
X1150783Y588833D01*
X1151367Y588917D01*
X1151867Y589333D01*
X1152200Y589917D01*
Y593833D01*
G01Y593167D02*
X1151867Y593500D01*
X1151367Y593750D01*
X1150783Y593833D01*
X1150117Y593667D01*
X1149700Y593333D01*
X1149367Y592750D01*
X1149200Y592167D01*
X1149283Y591667D01*
X1149617Y591083D01*
X1150117Y590667D01*
X1150783Y590500D01*
X1151283Y590583D01*
X1151867Y590917D01*
X1152200Y591250D01*
G01X1163233Y593417D02*
X1162650Y593750D01*
X1162150Y593833D01*
X1161483Y593667D01*
X1160983Y593333D01*
X1160650Y592750D01*
X1160567Y592167D01*
X1160650Y591583D01*
X1160983Y591083D01*
X1161483Y590667D01*
X1162150Y590500D01*
X1162733Y590667D01*
X1163233Y591000D01*
G01X1166333Y590500D02*
Y593833D01*
G01Y593167D02*
X1166750Y593500D01*
X1167167Y593750D01*
X1167750Y593833D01*
X1168167Y593750D01*
X1168667Y593500D01*
G01X1173100Y593833D02*
Y590500D01*
G01Y595167D02*
X1172933Y595250D01*
Y595417D01*
X1173100Y595500D01*
X1173267Y595417D01*
Y595250D01*
X1173100Y595167D01*
G01X1178700Y595500D02*
Y590500D01*
G01X1177533Y593833D02*
X1179867D01*
G01X1183050Y592750D02*
X1185717D01*
X1185467Y593333D01*
X1185050Y593667D01*
X1184467Y593833D01*
X1183883Y593750D01*
X1183383Y593500D01*
X1183050Y592917D01*
X1182883Y592417D01*
Y591917D01*
X1183050Y591417D01*
X1183467Y590917D01*
X1183967Y590583D01*
X1184550Y590500D01*
X1185133Y590667D01*
X1185717Y591167D01*
G01X1188733Y590500D02*
Y593833D01*
G01Y593167D02*
X1189150Y593500D01*
X1189567Y593750D01*
X1190150Y593833D01*
X1190567Y593750D01*
X1191067Y593500D01*
G01X1195500Y593833D02*
Y590500D01*
G01Y595167D02*
X1195333Y595250D01*
Y595417D01*
X1195500Y595500D01*
X1195667Y595417D01*
Y595250D01*
X1195500Y595167D01*
G01X1202600Y590500D02*
Y593833D01*
G01Y593250D02*
X1202267Y593583D01*
X1201767Y593750D01*
X1201183Y593833D01*
X1200600Y593667D01*
X1200100Y593333D01*
X1199767Y592833D01*
X1199600Y592167D01*
X1199767Y591500D01*
X1200100Y591000D01*
X1200600Y590667D01*
X1201183Y590500D01*
X1201767Y590583D01*
X1202267Y590833D01*
X1202600Y591167D01*
G01X1106417Y735500D02*
X1108500Y730500D01*
X1110583Y735500D01*
G01X1113100D02*
X1115100D01*
G01X1114100D02*
Y730500D01*
G01X1113100D02*
X1115100D01*
G01X1118033D02*
Y735500D01*
X1120033D01*
X1120700Y735250D01*
X1121200Y734667D01*
X1121367Y734000D01*
X1121200Y733333D01*
X1120783Y732833D01*
X1120033Y732583D01*
X1118033D01*
G01X1184667Y150367D02*
X1185000Y150617D01*
X1185250Y151033D01*
X1185417Y151617D01*
X1185250Y152117D01*
X1184917Y152450D01*
X1184333Y152700D01*
X1182083D01*
Y147700D01*
X1184833D01*
X1185417Y148033D01*
X1185750Y148533D01*
X1185917Y149117D01*
X1185750Y149700D01*
X1185250Y150200D01*
X1184667Y150367D01*
X1182083D01*
G01X1187517Y147700D02*
X1189600Y152700D01*
X1191683Y147700D01*
G01X1190933Y149450D02*
X1188267D01*
G01X1197033Y152283D02*
X1196533Y152533D01*
X1195950Y152700D01*
X1195283D01*
X1194533Y152450D01*
X1193950Y152033D01*
X1193533Y151533D01*
X1193200Y150700D01*
X1193117Y149950D01*
X1193283Y149200D01*
X1193533Y148700D01*
X1194033Y148200D01*
X1194617Y147867D01*
X1195200Y147700D01*
X1195783D01*
X1196367Y147867D01*
X1196867Y148117D01*
X1197283Y148450D01*
G01X1198967Y147700D02*
Y152700D01*
G01X1202133D02*
X1198967Y149617D01*
G01X1202633Y147700D02*
X1200383Y151033D01*
G01X1210167Y147700D02*
Y152700D01*
X1211833D01*
X1212500Y152450D01*
X1213000Y152117D01*
X1213417Y151617D01*
X1213750Y151033D01*
X1213833Y150200D01*
X1213750Y149367D01*
X1213417Y148783D01*
X1213000Y148283D01*
X1212500Y147950D01*
X1211833Y147700D01*
X1210167D01*
G01X1215933D02*
Y152700D01*
X1218017D01*
X1218683Y152450D01*
X1219100Y152117D01*
X1219267Y151450D01*
X1219100Y150783D01*
X1218600Y150367D01*
X1218017Y150117D01*
X1215933D01*
G01X1218017D02*
X1219267Y147700D01*
G01X1222200Y152700D02*
X1224200D01*
G01X1223200D02*
Y147700D01*
G01X1222200D02*
X1224200D01*
G01X1227133Y152700D02*
Y147700D01*
X1230467D01*
G01X1232733Y152700D02*
Y147700D01*
X1236067D01*
G01X1259900D02*
Y151033D01*
G01Y150117D02*
X1260150Y150533D01*
X1260567Y150867D01*
X1261150Y151033D01*
X1261733Y150867D01*
X1262150Y150533D01*
X1262400Y150117D01*
Y147700D01*
G01Y150117D02*
X1262650Y150533D01*
X1263067Y150867D01*
X1263650Y151033D01*
X1264233Y150867D01*
X1264650Y150533D01*
X1264900Y150033D01*
Y147700D01*
G01X1268000Y151033D02*
Y147700D01*
G01Y152367D02*
X1267833Y152450D01*
Y152617D01*
X1268000Y152700D01*
X1268167Y152617D01*
Y152450D01*
X1268000Y152367D01*
G01X1273600Y147700D02*
Y152700D01*
G01X1277950Y148283D02*
X1278367Y147950D01*
X1278950Y147700D01*
X1279450D01*
X1279950Y147867D01*
X1280283Y148117D01*
X1280450Y148450D01*
X1280367Y148950D01*
X1280033Y149200D01*
X1278533Y149700D01*
X1278200Y150283D01*
X1278367Y150700D01*
X1278700Y150950D01*
X1279200Y151033D01*
X1279700Y150950D01*
X1280200Y150700D01*
G01X1284383Y146033D02*
X1283550Y146867D01*
X1283133Y147700D01*
Y151033D01*
X1283550Y151867D01*
X1284383Y152700D01*
G01X1288483Y147700D02*
Y152700D01*
X1292317Y147700D01*
Y152700D01*
G01X1294333Y147700D02*
Y152700D01*
X1296333D01*
X1297000Y152450D01*
X1297500Y151867D01*
X1297667Y151200D01*
X1297500Y150533D01*
X1297083Y150033D01*
X1296333Y149783D01*
X1294333D01*
G01X1301600Y152700D02*
Y147700D01*
G01X1299683Y152700D02*
X1303517D01*
G01X1305450Y147700D02*
Y152700D01*
G01X1308950D02*
Y147700D01*
G01Y150200D02*
X1305450D01*
G01X1313217Y146033D02*
X1314050Y146867D01*
X1314467Y147700D01*
Y151033D01*
X1314050Y151867D01*
X1313217Y152700D01*
G01X1218250Y281583D02*
X1218667Y281250D01*
X1219250Y281000D01*
X1219750D01*
X1220250Y281167D01*
X1220583Y281417D01*
X1220750Y281750D01*
X1220667Y282250D01*
X1220333Y282500D01*
X1218833Y283000D01*
X1218500Y283583D01*
X1218667Y284000D01*
X1219000Y284250D01*
X1219500Y284333D01*
X1220000Y284250D01*
X1220500Y284000D01*
G01X1225100Y286000D02*
Y281000D01*
G01X1223933Y284333D02*
X1226267D01*
G01X1229283D02*
Y282000D01*
X1229617Y281417D01*
X1230117Y281083D01*
X1230700Y281000D01*
X1231283Y281083D01*
X1231783Y281417D01*
X1232117Y282000D01*
G01Y281000D02*
Y284333D01*
G01X1234800Y281000D02*
Y286000D01*
G01Y283500D02*
X1235217Y284000D01*
X1235717Y284250D01*
X1236217Y284333D01*
X1236967Y284167D01*
X1237467Y283833D01*
X1237800Y283250D01*
Y282583D01*
X1237633Y281917D01*
X1237300Y281417D01*
X1236717Y281083D01*
X1236217Y281000D01*
X1235717Y281083D01*
X1235217Y281333D01*
X1234800Y281750D01*
G01X1247500Y281000D02*
Y286000D01*
G01X1251850Y283250D02*
X1254517D01*
X1254267Y283833D01*
X1253850Y284167D01*
X1253267Y284333D01*
X1252683Y284250D01*
X1252183Y284000D01*
X1251850Y283417D01*
X1251683Y282917D01*
Y282417D01*
X1251850Y281917D01*
X1252267Y281417D01*
X1252767Y281083D01*
X1253350Y281000D01*
X1253933Y281167D01*
X1254517Y281667D01*
G01X1257283Y281000D02*
Y284333D01*
G01Y283500D02*
X1257617Y283917D01*
X1258117Y284250D01*
X1258783Y284333D01*
X1259367Y284250D01*
X1259867Y283917D01*
X1260117Y283333D01*
Y281000D01*
G01X1263133Y279750D02*
X1263717Y279417D01*
X1264383Y279333D01*
X1264967Y279417D01*
X1265467Y279833D01*
X1265800Y280417D01*
Y284333D01*
G01Y283667D02*
X1265467Y284000D01*
X1264967Y284250D01*
X1264383Y284333D01*
X1263717Y284167D01*
X1263300Y283833D01*
X1262967Y283250D01*
X1262800Y282667D01*
X1262883Y282167D01*
X1263217Y281583D01*
X1263717Y281167D01*
X1264383Y281000D01*
X1264883Y281083D01*
X1265467Y281417D01*
X1265800Y281750D01*
G01X1269900Y286000D02*
Y281000D01*
G01X1268733Y284333D02*
X1271067D01*
G01X1274083Y281000D02*
Y286000D01*
G01Y283583D02*
X1274500Y284000D01*
X1274917Y284250D01*
X1275583Y284333D01*
X1276083Y284250D01*
X1276667Y283917D01*
X1276917Y283417D01*
Y281000D01*
G01X1280017Y281917D02*
X1282183D01*
G01Y283417D02*
X1280017D01*
G01X1285117Y283083D02*
X1285700Y283667D01*
X1286200Y284000D01*
X1286867Y284167D01*
X1287450Y284000D01*
X1287867Y283667D01*
X1288200Y283167D01*
X1288283Y282583D01*
X1288200Y282083D01*
X1287867Y281583D01*
X1287367Y281167D01*
X1286783Y281000D01*
X1286117Y281167D01*
X1285533Y281667D01*
X1285200Y282417D01*
X1285117Y283250D01*
X1285283Y284333D01*
X1285533Y284917D01*
X1285950Y285500D01*
X1286533Y285917D01*
X1287117Y286000D01*
X1287700Y285833D01*
X1288117Y285417D01*
G01X1291383Y282667D02*
X1293383D01*
G01X1292300Y283750D02*
Y281583D01*
G01X1296400Y280833D02*
X1299400Y286000D01*
G01X1302417Y282667D02*
X1304583D01*
G01X1307267Y281750D02*
X1307767Y281333D01*
X1308350Y281083D01*
X1309100Y281000D01*
X1309850Y281167D01*
X1310433Y281500D01*
X1310850Y282083D01*
X1310933Y282750D01*
X1310767Y283417D01*
X1310350Y283833D01*
X1309767Y284167D01*
X1309183Y284250D01*
X1308600Y284167D01*
X1307850Y283833D01*
X1308100Y286000D01*
X1310350D01*
G01X1312200Y281000D02*
Y284333D01*
G01Y283417D02*
X1312450Y283833D01*
X1312867Y284167D01*
X1313450Y284333D01*
X1314033Y284167D01*
X1314450Y283833D01*
X1314700Y283417D01*
Y281000D01*
G01Y283417D02*
X1314950Y283833D01*
X1315367Y284167D01*
X1315950Y284333D01*
X1316533Y284167D01*
X1316950Y283833D01*
X1317200Y283333D01*
Y281000D01*
G01X1320300Y284333D02*
Y281000D01*
G01Y285667D02*
X1320133Y285750D01*
Y285917D01*
X1320300Y286000D01*
X1320467Y285917D01*
Y285750D01*
X1320300Y285667D01*
G01X1325900Y281000D02*
Y286000D01*
G01X1210333Y218700D02*
Y213700D01*
X1213667D01*
G01X1216350Y217033D02*
X1218850Y213700D01*
G01Y217033D02*
X1216350Y213700D01*
G01X1207333Y260500D02*
Y255500D01*
X1210667D01*
G01X1213183D02*
Y258833D01*
G01Y258000D02*
X1213517Y258417D01*
X1214017Y258750D01*
X1214683Y258833D01*
X1215267Y258750D01*
X1215767Y258417D01*
X1216017Y257833D01*
Y255500D01*
G01X1178750Y315500D02*
Y320500D01*
G01X1182250D02*
Y315500D01*
G01Y318000D02*
X1178750D01*
G01X1186100Y315500D02*
X1185433Y315583D01*
X1184850Y315917D01*
X1184350Y316417D01*
X1184017Y317000D01*
X1183850Y317667D01*
Y318333D01*
X1184017Y319000D01*
X1184350Y319583D01*
X1184850Y320083D01*
X1185433Y320417D01*
X1186100Y320500D01*
X1186767Y320417D01*
X1187350Y320083D01*
X1187850Y319583D01*
X1188183Y319000D01*
X1188350Y318333D01*
Y317667D01*
X1188183Y317000D01*
X1187850Y316417D01*
X1187350Y315917D01*
X1186767Y315583D01*
X1186100Y315500D01*
G01X1190033Y320500D02*
Y315500D01*
X1193367D01*
G01X1198967D02*
X1195633D01*
Y320500D01*
X1198967D01*
G01X1197633Y318083D02*
X1195633D01*
G01X1222800Y315500D02*
Y318833D01*
G01Y317917D02*
X1223050Y318333D01*
X1223467Y318667D01*
X1224050Y318833D01*
X1224633Y318667D01*
X1225050Y318333D01*
X1225300Y317917D01*
Y315500D01*
G01Y317917D02*
X1225550Y318333D01*
X1225967Y318667D01*
X1226550Y318833D01*
X1227133Y318667D01*
X1227550Y318333D01*
X1227800Y317833D01*
Y315500D01*
G01X1230900Y318833D02*
Y315500D01*
G01Y320167D02*
X1230733Y320250D01*
Y320417D01*
X1230900Y320500D01*
X1231067Y320417D01*
Y320250D01*
X1230900Y320167D01*
G01X1236500Y315500D02*
Y320500D01*
G01X1240850Y316083D02*
X1241267Y315750D01*
X1241850Y315500D01*
X1242350D01*
X1242850Y315667D01*
X1243183Y315917D01*
X1243350Y316250D01*
X1243267Y316750D01*
X1242933Y317000D01*
X1241433Y317500D01*
X1241100Y318083D01*
X1241267Y318500D01*
X1241600Y318750D01*
X1242100Y318833D01*
X1242600Y318750D01*
X1243100Y318500D01*
G01X1247283Y313833D02*
X1246450Y314667D01*
X1246033Y315500D01*
Y318833D01*
X1246450Y319667D01*
X1247283Y320500D01*
G01X1251633Y315500D02*
Y320500D01*
X1253633D01*
X1254300Y320250D01*
X1254800Y319667D01*
X1254967Y319000D01*
X1254800Y318333D01*
X1254383Y317833D01*
X1253633Y317583D01*
X1251633D01*
G01X1258900Y320500D02*
Y315500D01*
G01X1256983Y320500D02*
X1260817D01*
G01X1262750Y315500D02*
Y320500D01*
G01X1266250D02*
Y315500D01*
G01Y318000D02*
X1262750D01*
G01X1270517Y313833D02*
X1271350Y314667D01*
X1271767Y315500D01*
Y318833D01*
X1271350Y319667D01*
X1270517Y320500D01*
G01X1180417Y734500D02*
X1182500Y729500D01*
X1184583Y734500D01*
G01X1188100Y729500D02*
X1187433Y729583D01*
X1186850Y729917D01*
X1186350Y730417D01*
X1186017Y731000D01*
X1185850Y731667D01*
Y732333D01*
X1186017Y733000D01*
X1186350Y733583D01*
X1186850Y734083D01*
X1187433Y734417D01*
X1188100Y734500D01*
X1188767Y734417D01*
X1189350Y734083D01*
X1189850Y733583D01*
X1190183Y733000D01*
X1190350Y732333D01*
Y731667D01*
X1190183Y731000D01*
X1189850Y730417D01*
X1189350Y729917D01*
X1188767Y729583D01*
X1188100Y729500D01*
G01X1192033D02*
Y734500D01*
X1194033D01*
X1194700Y734250D01*
X1195200Y733667D01*
X1195367Y733000D01*
X1195200Y732333D01*
X1194783Y731833D01*
X1194033Y731583D01*
X1192033D01*
G01X1241083Y841667D02*
X1243083D01*
G01X1242000Y842750D02*
Y840583D01*
G01X1246100Y839833D02*
X1249100Y845000D01*
G01X1252117Y841667D02*
X1254283D01*
G01X1256967Y840750D02*
X1257467Y840333D01*
X1258050Y840083D01*
X1258800Y840000D01*
X1259550Y840167D01*
X1260133Y840500D01*
X1260550Y841083D01*
X1260633Y841750D01*
X1260467Y842417D01*
X1260050Y842833D01*
X1259467Y843167D01*
X1258883Y843250D01*
X1258300Y843167D01*
X1257550Y842833D01*
X1257800Y845000D01*
X1260050D01*
G01X1261900Y840000D02*
Y843333D01*
G01Y842417D02*
X1262150Y842833D01*
X1262567Y843167D01*
X1263150Y843333D01*
X1263733Y843167D01*
X1264150Y842833D01*
X1264400Y842417D01*
Y840000D01*
G01Y842417D02*
X1264650Y842833D01*
X1265067Y843167D01*
X1265650Y843333D01*
X1266233Y843167D01*
X1266650Y842833D01*
X1266900Y842333D01*
Y840000D01*
G01X1270000Y843333D02*
Y840000D01*
G01Y844667D02*
X1269833Y844750D01*
Y844917D01*
X1270000Y845000D01*
X1270167Y844917D01*
Y844750D01*
X1270000Y844667D01*
G01X1275600Y840000D02*
Y845000D01*
G01X1241083Y826667D02*
X1243083D01*
G01X1242000Y827750D02*
Y825583D01*
G01X1246100Y824833D02*
X1249100Y830000D01*
G01X1252117Y826667D02*
X1254283D01*
G01X1256967Y825750D02*
X1257467Y825333D01*
X1258050Y825083D01*
X1258800Y825000D01*
X1259550Y825167D01*
X1260133Y825500D01*
X1260550Y826083D01*
X1260633Y826750D01*
X1260467Y827417D01*
X1260050Y827833D01*
X1259467Y828167D01*
X1258883Y828250D01*
X1258300Y828167D01*
X1257550Y827833D01*
X1257800Y830000D01*
X1260050D01*
G01X1261900Y825000D02*
Y828333D01*
G01Y827417D02*
X1262150Y827833D01*
X1262567Y828167D01*
X1263150Y828333D01*
X1263733Y828167D01*
X1264150Y827833D01*
X1264400Y827417D01*
Y825000D01*
G01Y827417D02*
X1264650Y827833D01*
X1265067Y828167D01*
X1265650Y828333D01*
X1266233Y828167D01*
X1266650Y827833D01*
X1266900Y827333D01*
Y825000D01*
G01X1270000Y828333D02*
Y825000D01*
G01Y829667D02*
X1269833Y829750D01*
Y829917D01*
X1270000Y830000D01*
X1270167Y829917D01*
Y829750D01*
X1270000Y829667D01*
G01X1275600Y825000D02*
Y830000D01*
G01X1241083Y811667D02*
X1243083D01*
G01X1242000Y812750D02*
Y810583D01*
G01X1246100Y809833D02*
X1249100Y815000D01*
G01X1252117Y811667D02*
X1254283D01*
G01X1257217Y814167D02*
X1257717Y814667D01*
X1258300Y814917D01*
X1258967Y815000D01*
X1259800Y814833D01*
X1260383Y814417D01*
X1260550Y813917D01*
X1260467Y813417D01*
X1260133Y813000D01*
X1258467Y812167D01*
X1257717Y811583D01*
X1257217Y810750D01*
X1257050Y810000D01*
X1260550D01*
G01X1261900D02*
Y813333D01*
G01Y812417D02*
X1262150Y812833D01*
X1262567Y813167D01*
X1263150Y813333D01*
X1263733Y813167D01*
X1264150Y812833D01*
X1264400Y812417D01*
Y810000D01*
G01Y812417D02*
X1264650Y812833D01*
X1265067Y813167D01*
X1265650Y813333D01*
X1266233Y813167D01*
X1266650Y812833D01*
X1266900Y812333D01*
Y810000D01*
G01X1270000Y813333D02*
Y810000D01*
G01Y814667D02*
X1269833Y814750D01*
Y814917D01*
X1270000Y815000D01*
X1270167Y814917D01*
Y814750D01*
X1270000Y814667D01*
G01X1275600Y810000D02*
Y815000D01*
G01X1242793Y785443D02*
X1241960Y786277D01*
X1241543Y787110D01*
Y790443D01*
X1241960Y791277D01*
X1242793Y792110D01*
G01X1248810Y787110D02*
Y792110D01*
X1247810Y791110D01*
G01Y787110D02*
X1249810D01*
G01X1254410Y786943D02*
X1254243Y787027D01*
Y787193D01*
X1254410Y787277D01*
X1254577Y787193D01*
Y787027D01*
X1254410Y786943D01*
G01X1258427Y791277D02*
X1258927Y791777D01*
X1259510Y792027D01*
X1260177Y792110D01*
X1261010Y791943D01*
X1261593Y791527D01*
X1261760Y791027D01*
X1261677Y790527D01*
X1261343Y790110D01*
X1259677Y789277D01*
X1258927Y788693D01*
X1258427Y787860D01*
X1258260Y787110D01*
X1261760D01*
G01X1263110D02*
Y790443D01*
G01Y789527D02*
X1263360Y789943D01*
X1263777Y790277D01*
X1264360Y790443D01*
X1264943Y790277D01*
X1265360Y789943D01*
X1265610Y789527D01*
Y787110D01*
G01Y789527D02*
X1265860Y789943D01*
X1266277Y790277D01*
X1266860Y790443D01*
X1267443Y790277D01*
X1267860Y789943D01*
X1268110Y789443D01*
Y787110D01*
G01X1268710D02*
Y790443D01*
G01Y789527D02*
X1268960Y789943D01*
X1269377Y790277D01*
X1269960Y790443D01*
X1270543Y790277D01*
X1270960Y789943D01*
X1271210Y789527D01*
Y787110D01*
G01Y789527D02*
X1271460Y789943D01*
X1271877Y790277D01*
X1272460Y790443D01*
X1273043Y790277D01*
X1273460Y789943D01*
X1273710Y789443D01*
Y787110D01*
G01X1280243D02*
Y792110D01*
X1282410Y787943D01*
X1284577Y792110D01*
Y787110D01*
G01X1289510D02*
Y790443D01*
G01Y789860D02*
X1289177Y790193D01*
X1288677Y790360D01*
X1288093Y790443D01*
X1287510Y790277D01*
X1287010Y789943D01*
X1286677Y789443D01*
X1286510Y788777D01*
X1286677Y788110D01*
X1287010Y787610D01*
X1287510Y787277D01*
X1288093Y787110D01*
X1288677Y787193D01*
X1289177Y787443D01*
X1289510Y787777D01*
G01X1292360Y790443D02*
X1294860Y787110D01*
G01Y790443D02*
X1292360Y787110D01*
G01X1299627Y785443D02*
X1300460Y786277D01*
X1300877Y787110D01*
Y790443D01*
X1300460Y791277D01*
X1299627Y792110D01*
G01X1244877Y797230D02*
X1241543Y798897D01*
X1244877Y800563D01*
G01X1247727Y798147D02*
X1249893D01*
G01Y799647D02*
X1247727D01*
G01X1254410Y802230D02*
X1253743Y802063D01*
X1253243Y801647D01*
X1252910Y801147D01*
X1252660Y800480D01*
X1252577Y799730D01*
X1252660Y798980D01*
X1252910Y798313D01*
X1253243Y797813D01*
X1253743Y797397D01*
X1254410Y797230D01*
X1255077Y797397D01*
X1255577Y797813D01*
X1255910Y798313D01*
X1256160Y798980D01*
X1256243Y799730D01*
X1256160Y800480D01*
X1255910Y801147D01*
X1255577Y801647D01*
X1255077Y802063D01*
X1254410Y802230D01*
G01X1260010Y797063D02*
X1259843Y797147D01*
Y797313D01*
X1260010Y797397D01*
X1260177Y797313D01*
Y797147D01*
X1260010Y797063D01*
G01X1265443Y797230D02*
X1265610Y798313D01*
X1265860Y799230D01*
X1266193Y800063D01*
X1266610Y800980D01*
X1267277Y802230D01*
X1263943D01*
G01X1269377Y797980D02*
X1269877Y797563D01*
X1270460Y797313D01*
X1271210Y797230D01*
X1271960Y797397D01*
X1272543Y797730D01*
X1272960Y798313D01*
X1273043Y798980D01*
X1272877Y799647D01*
X1272460Y800063D01*
X1271877Y800397D01*
X1271293Y800480D01*
X1270710Y800397D01*
X1269960Y800063D01*
X1270210Y802230D01*
X1272460D01*
G01X1275310Y797063D02*
X1278310Y802230D01*
G01X1275310D02*
X1274810Y802063D01*
X1274560Y801813D01*
X1274393Y801313D01*
X1274560Y800813D01*
X1274810Y800563D01*
X1275310Y800397D01*
X1275810Y800563D01*
X1276060Y800813D01*
X1276227Y801313D01*
X1276060Y801813D01*
X1275810Y802063D01*
X1275310Y802230D01*
G01X1278310Y798897D02*
X1277810Y798730D01*
X1277560Y798480D01*
X1277393Y797980D01*
X1277560Y797480D01*
X1277810Y797230D01*
X1278310Y797063D01*
X1278810Y797230D01*
X1279060Y797480D01*
X1279227Y797980D01*
X1279060Y798480D01*
X1278810Y798730D01*
X1278310Y798897D01*
G01X1234540Y850500D02*
Y782000D01*
G01X1343000Y850610D02*
Y782110D01*
G54D12*
G01X857602Y628479D02*
X872727D01*
G01X857602Y635354D02*
Y628479D01*
G01X865852Y635354D02*
X843852D01*
G01D02*
Y712354D01*
G01X857602Y721979D02*
Y715104D01*
G01X872727Y721979D02*
X857602D01*
G01X843852Y712354D02*
X865852D01*
G01X949727Y628479D02*
Y721979D01*
G01X934602Y628479D02*
X949727D01*
G01X934602Y635354D02*
Y628479D01*
G01X942852Y635354D02*
Y712354D01*
G01X898852D02*
Y635354D01*
G01D02*
X942852D01*
G01X907102Y628479D02*
Y635354D01*
G01X891977Y628479D02*
X907102D01*
G01X891977Y721979D02*
Y628479D01*
G01X865852Y712354D02*
Y635354D01*
G01X872727Y628479D02*
Y721979D01*
G01X934602D02*
Y715104D01*
G01X949727Y721979D02*
X934602D01*
G01X942852Y712354D02*
X898852D01*
G01X907102Y715104D02*
Y721979D01*
G01D02*
X891977D01*
G01X1045977Y628479D02*
X1061102D01*
G01X1045977Y719229D02*
Y628479D01*
G01X1052852Y712354D02*
Y635354D01*
G01D02*
X1096852D01*
G01X1026727Y628479D02*
Y719229D01*
G01X1019852Y635354D02*
Y712354D01*
G01X1011602Y628479D02*
X1026727D01*
G01X1011602Y635354D02*
Y628479D01*
G01X984102D02*
Y635354D01*
G01X975852Y712354D02*
Y635354D01*
G01D02*
X1019852D01*
G01X968977Y628479D02*
X984102D01*
G01X968977Y721979D02*
Y628479D01*
G01X1061102Y719229D02*
X1045977D01*
G01X1096852Y712354D02*
X1052852D01*
G01X1011602Y719229D02*
Y712354D01*
G01X1026727Y719229D02*
X1011602D01*
G01X984102Y715104D02*
Y721979D01*
G01X1019852Y712354D02*
X975852D01*
G01X984102Y721979D02*
X968977D01*
G01X1129852Y712354D02*
Y635354D01*
G01D02*
X1173852D01*
G01X1138102Y628479D02*
Y635354D01*
G01X1122977Y628479D02*
X1138102D01*
G01X1096852Y635354D02*
Y712354D01*
G01X1088602Y628479D02*
X1122977D01*
G01X1088602Y635354D02*
Y628479D01*
G01X1061102D02*
Y635354D01*
G01X1173852Y712354D02*
X1129852D01*
G01X1138102D02*
Y719229D01*
G01D02*
X1103727D01*
G01X1088602D02*
Y712354D01*
G01X1103727Y719229D02*
X1088602D01*
G01X1061102Y712354D02*
Y719229D01*
G01X1215102Y628479D02*
Y635354D01*
G01X1206852Y712354D02*
Y635354D01*
G01D02*
X1250852D01*
G01X1199977Y628479D02*
X1215102D01*
G01X1199977Y719229D02*
Y628479D01*
G01X1180727D02*
Y719229D01*
G01X1165602Y628479D02*
X1180727D01*
G01X1165602Y635354D02*
Y628479D01*
G01X1173852Y635354D02*
Y712354D01*
G01X1215102D02*
Y719229D01*
G01X1250852Y712354D02*
X1206852D01*
G01X1215102Y719229D02*
X1199977D01*
G01X1165602D02*
Y712354D01*
G01X1180727Y719229D02*
X1165602D01*
G01X1250852Y635354D02*
Y712354D01*
G54D13*
G01X341590Y319830D02*
Y303830D01*
G01X303090Y319830D02*
Y303830D01*
G01X352590Y340830D02*
Y357830D01*
G01X292090Y340830D02*
Y357830D01*
G01X356482Y330153D02*
X352452Y324663D01*
X356652Y324643D01*
G01X345680Y327680D02*
G02X350362Y319860I-4190J-7820D01*
G01X348190Y321780D01*
X351420Y321950D01*
X350460Y319850D01*
G01X439562Y301543D02*
X435532Y296053D01*
X439732Y296033D01*
G54D14*
G01X856340Y725829D02*
X872925D01*
G01X868819Y719229D02*
X862219Y725829D01*
G01X866485Y719229D02*
X859885Y725829D01*
G01X864151Y719229D02*
X857551Y725829D01*
G01X861818Y719229D02*
X855779Y725267D01*
G01X859485Y719229D02*
X854613Y724101D01*
G01X857327Y719053D02*
X853752Y722628D01*
G01X857327Y716720D02*
X853752Y720295D01*
G01X857327Y714387D02*
X853752Y717961D01*
G01X856750Y712629D02*
X853752Y715628D01*
G01X854417Y712629D02*
X853752Y713295D01*
G01X855058Y712629D02*
X857327Y714899D01*
G01X861658Y719229D02*
X868258Y725829D01*
G01X853752Y713657D02*
X857327Y717232D01*
G01X859323Y719229D02*
X865923Y725829D01*
G01X853752Y715991D02*
X863590Y725829D01*
G01X853752Y718324D02*
X861257Y725829D01*
G01X853752Y720657D02*
X858923Y725829D01*
G01X853752Y722991D02*
X856590Y725829D01*
G01X853752Y723240D02*
X856340Y725829D01*
G01X853752Y712629D02*
Y723240D01*
G01X857327Y712629D02*
X853752D01*
G01X857327Y719504D02*
Y712629D01*
G01X857602Y719229D02*
X857327Y719504D01*
G01X873002Y719229D02*
X857602D01*
G01X950002Y658233D02*
X968702Y676932D01*
G01X950002Y660566D02*
X968702Y679266D01*
G01X950002Y662899D02*
X968702Y681599D01*
G01X950002Y665234D02*
X968702Y683932D01*
G01Y654348D02*
X950002Y673048D01*
G01X968702Y652014D02*
X950002Y670714D01*
G01X968702Y649681D02*
X950002Y668381D01*
G01X968702Y647348D02*
X950002Y666048D01*
G01X968702Y645013D02*
X950002Y663713D01*
G01X968702Y642680D02*
X950002Y661380D01*
G01X968702Y640347D02*
X950002Y659047D01*
G01X968702Y638014D02*
X950002Y656713D01*
G01X968702Y635680D02*
X950002Y654380D01*
G01X968702Y633347D02*
X950002Y652047D01*
G01X968702Y631014D02*
X950002Y649713D01*
G01X968702Y628679D02*
X950002Y647379D01*
G01Y630232D02*
X968702Y648932D01*
G01X950002Y632565D02*
X968702Y651265D01*
G01X950002Y634898D02*
X968702Y653598D01*
G01X950002Y637232D02*
X968702Y655931D01*
G01X950002Y639565D02*
X968702Y658265D01*
G01X950002Y641898D02*
X968702Y660598D01*
G01X950002Y644232D02*
X968702Y662931D01*
G01X950002Y646565D02*
X968702Y665265D01*
G01X950002Y648899D02*
X968702Y667599D01*
G01X950002Y651233D02*
X968702Y669932D01*
G01X950002Y653566D02*
X968702Y672266D01*
G01X950002Y655899D02*
X968702Y674599D01*
G01X950002Y628204D02*
Y719504D01*
G01X970419Y624629D02*
X950002Y645046D01*
G01X968086Y624629D02*
X950002Y642712D01*
G01X965752Y624629D02*
X950002Y640379D01*
G01X963419Y624629D02*
X950002Y638046D01*
G01X961085Y624629D02*
X950002Y635712D01*
G01X958751Y624629D02*
X950002Y633379D01*
G01X956418Y624629D02*
X950002Y631046D01*
G01X954085Y624629D02*
X950002Y628711D01*
G01X951751Y624629D02*
X948176Y628204D01*
G01X956067Y624629D02*
X968702Y637264D01*
G01X953733Y624629D02*
X968702Y639597D01*
G01X951400Y624629D02*
X968702Y641931D01*
G01X949067Y624629D02*
X968702Y644264D01*
G01X946733Y624629D02*
X968702Y646597D01*
G01X949418Y624629D02*
X945843Y628204D01*
G01X947085Y624629D02*
X943510Y628204D01*
G01X934327Y635053D02*
X934300Y635079D01*
G01X934327Y632720D02*
X931967Y635079D01*
G01X934327Y630387D02*
X930752Y633961D01*
G01X933037Y624933D02*
X936307Y628204D01*
G01X931869Y626100D02*
X934327Y628556D01*
G01X930752Y627315D02*
X934327Y630890D01*
G01X930752Y629649D02*
X934327Y633224D01*
G01X930752Y631983D02*
X933848Y635079D01*
G01X930752Y634316D02*
X931515Y635079D01*
G01X934327Y628204D02*
X950002D01*
G01X934327Y635079D02*
Y628204D01*
G01X930752Y635079D02*
X934327D01*
G01X930752Y627218D02*
Y635079D01*
G01X944750Y624629D02*
X941175Y628204D01*
G01X942417Y624629D02*
X938842Y628204D01*
G01X940084Y624629D02*
X936509Y628204D01*
G01X937750Y624629D02*
X930752Y631627D01*
G01X935417Y624629D02*
X930752Y629294D01*
G01X944400Y624629D02*
X947975Y628204D01*
G01X942066Y624629D02*
X945640Y628203D01*
G01X939733Y624629D02*
X943307Y628204D01*
G01X937399Y624629D02*
X940974Y628203D01*
G01X935066Y624629D02*
X938640Y628203D01*
G01X985362Y624629D02*
X933340D01*
G01D02*
X930752Y627218D01*
G01X968702Y708017D02*
X957613Y719106D01*
G01X968702Y705684D02*
X953567Y720819D01*
G01X951317Y723067D02*
X948556Y725829D01*
G01X968702Y698683D02*
X950002Y717383D01*
G01X968702Y696350D02*
X950002Y715049D01*
G01X968702Y694016D02*
X950002Y712716D01*
G01X968702Y691683D02*
X950002Y710383D01*
G01Y690901D02*
X968702Y709601D01*
G01X950002Y693234D02*
X968702Y711934D01*
G01X950002Y695568D02*
X968702Y714267D01*
G01X950002Y697901D02*
X968702Y716601D01*
G01X950002Y700234D02*
X968702Y718934D01*
G01X950002Y702569D02*
X973262Y725828D01*
G01X950002Y704902D02*
X970929Y725829D01*
G01X950002Y707235D02*
X962112Y719345D01*
G01X950002Y709569D02*
X959386Y718952D01*
G01X950002Y711902D02*
X957273Y719173D01*
G01X950002Y714235D02*
X955499Y719733D01*
G01X950002Y716569D02*
X953974Y720540D01*
G01X950002Y718903D02*
X952657Y721558D01*
G01X948269Y719504D02*
X951539Y722772D01*
G01X949925Y725829D02*
G03X968779I9427J3024D01*
G01X968702Y689350D02*
X950002Y708049D01*
G01X968702Y687016D02*
X950002Y705716D01*
G01X968702Y684683D02*
X950002Y703383D01*
G01X968702Y682350D02*
X950002Y701048D01*
G01X968702Y680015D02*
X950002Y698715D01*
G01X968702Y677682D02*
X950002Y696382D01*
G01X968702Y675349D02*
X950002Y694048D01*
G01X968702Y673015D02*
X950002Y691715D01*
G01X968702Y670682D02*
X950002Y689382D01*
G01X968702Y668349D02*
X950002Y687048D01*
G01X968702Y666015D02*
X950002Y684715D01*
G01X968702Y663681D02*
X950002Y682381D01*
G01X968702Y661348D02*
X950002Y680047D01*
G01X968702Y659014D02*
X950002Y677714D01*
G01Y667567D02*
X968702Y686267D01*
G01X950002Y669900D02*
X968702Y688600D01*
G01X950002Y672234D02*
X968702Y690933D01*
G01X950002Y674567D02*
X968702Y693267D01*
G01X950002Y676900D02*
X968702Y695600D01*
G01X950002Y679233D02*
X968702Y697933D01*
G01X950002Y681567D02*
X968702Y700267D01*
G01X950002Y683901D02*
X968702Y702601D01*
G01X950002Y686234D02*
X968702Y704934D01*
G01X950002Y688568D02*
X968702Y707268D01*
G01Y656681D02*
X950002Y675381D01*
G01X968702Y703350D02*
X946222Y725829D01*
G01X968702Y701017D02*
X943889Y725829D01*
G01X947881Y719504D02*
X941556Y725829D01*
G01X945548Y719504D02*
X939223Y725829D01*
G01X943214Y719504D02*
X936889Y725829D01*
G01X940881Y719504D02*
X934556Y725829D01*
G01X938546Y719504D02*
X932223Y725829D01*
G01X936213Y719504D02*
X929888Y725829D01*
G01X934327Y719058D02*
X927555Y725829D01*
G01X934327Y716725D02*
X925222Y725829D01*
G01X934327Y714390D02*
X922888Y725829D01*
G01X933755Y712629D02*
X920555Y725829D01*
G01X931422Y712629D02*
X918222Y725829D01*
G01X929088Y712629D02*
X915888Y725829D01*
G01X926754Y712629D02*
X913554Y725829D01*
G01X945936Y719504D02*
X950619Y724187D01*
G01X943603Y719504D02*
X949925Y725826D01*
G01X941270Y719504D02*
X947595Y725829D01*
G01X932061Y712629D02*
X934327Y714894D01*
G01X938936Y719504D02*
X945261Y725829D01*
G01X929728Y712629D02*
X934327Y717228D01*
G01X936603Y719504D02*
X942928Y725829D01*
G01X927395Y712629D02*
X940595Y725829D01*
G01X925062Y712629D02*
X938260Y725829D01*
G01X922727Y712629D02*
X935927Y725829D01*
G01X920394Y712629D02*
X933594Y725829D01*
G01X918061Y712629D02*
X931260Y725829D01*
G01X915727Y712629D02*
X928927Y725829D01*
G01X913394Y712629D02*
X926593Y725828D01*
G01X934327Y719504D02*
Y712629D01*
G01X950002Y719504D02*
X934327D01*
G01X924420Y712629D02*
X911221Y725829D01*
G01X891779D02*
X949925D01*
G01X922087Y712629D02*
X908887Y725829D01*
G01X919754Y712629D02*
X906554Y725829D01*
G01X917420Y712629D02*
X904221Y725829D01*
G01X915087Y712629D02*
X901887Y725829D01*
G01X912754Y712629D02*
X907377Y718006D01*
G01X905840Y719543D02*
X899554Y725829D01*
G01X910421Y712629D02*
X907377Y715673D01*
G01X903507Y719543D02*
X897221Y725829D01*
G01X908086Y712629D02*
X907377Y713339D01*
G01X901173Y719543D02*
X894886Y725829D01*
G01X898840Y719543D02*
X892553Y725829D01*
G01X896507Y719543D02*
X891342Y724707D01*
G01X894172Y719543D02*
X890494Y723221D01*
G01X891927Y719455D02*
X889440Y721942D01*
G01X891702Y717347D02*
X888191Y720857D01*
G01X891702Y715014D02*
X886738Y719977D01*
G01X891702Y712680D02*
X885053Y719328D01*
G01X891702Y710347D02*
X883070Y718978D01*
G01X891702Y708014D02*
X880607Y719107D01*
G01X911061Y712629D02*
X924260Y725829D01*
G01X908727Y712629D02*
X921927Y725829D01*
G01X907377Y713613D02*
X919592Y725828D01*
G01X907377Y715946D02*
X917259Y725829D01*
G01X907377Y718280D02*
X914926Y725829D01*
G01X906307Y719543D02*
X912592Y725828D01*
G01X903972Y719543D02*
X910259Y725829D01*
G01X901639Y719543D02*
X907926Y725829D01*
G01X899306Y719543D02*
X905593Y725829D01*
G01X896972Y719543D02*
X903258Y725829D01*
G01X894639Y719543D02*
X900925Y725829D01*
G01X892306Y719543D02*
X898592Y725829D01*
G01X892015Y719543D02*
X891702Y719229D01*
G01X907157Y719543D02*
X892015D01*
G01X907377Y719504D02*
X907157Y719543D01*
G01X907377Y712629D02*
Y719504D01*
G01X934327Y712629D02*
X907377D01*
G01X891702Y675345D02*
X891096Y675951D01*
G01X890957Y676193D02*
X891702Y676936D01*
G01X889988Y677557D02*
X891702Y679270D01*
G01X888823Y678725D02*
X891702Y681604D01*
G01X887462Y679697D02*
X891702Y683937D01*
G01X885887Y680455D02*
X891702Y686270D01*
G01X884054Y680956D02*
X891702Y688604D01*
G01X881854Y681089D02*
X891702Y690937D01*
G01Y674644D02*
X891701Y674645D01*
G01X891702Y719229D02*
Y674644D01*
G01Y705679D02*
X876553Y720829D01*
G01X874327Y723054D02*
X871552Y725829D01*
G01X891702Y703346D02*
X869219Y725829D01*
G01X891702Y701013D02*
X866886Y725829D01*
G01X891702Y698679D02*
X873002Y717379D01*
G01X871152Y719229D02*
X864552Y725829D01*
G01X891702Y696346D02*
X873002Y715046D01*
G01X891702Y694013D02*
X873002Y712712D01*
G01X891702Y691679D02*
X873002Y710379D01*
G01X891702Y689346D02*
X873002Y708046D01*
G01X891702Y687012D02*
X873002Y705711D01*
G01X891702Y684678D02*
X873002Y703378D01*
G01X891702Y682345D02*
X873002Y701045D01*
G01X891702Y680012D02*
X873002Y698711D01*
G01Y690905D02*
X891702Y709604D01*
G01X873002Y693238D02*
X891702Y711938D01*
G01X873002Y695572D02*
X891702Y714272D01*
G01X873002Y697906D02*
X891702Y716605D01*
G01X873002Y700239D02*
X891702Y718939D01*
G01X873002Y702572D02*
X896258Y725829D01*
G01X873002Y704906D02*
X893925Y725829D01*
G01X873002Y707239D02*
X885106Y719344D01*
G01X873002Y709572D02*
X882382Y718952D01*
G01X873002Y711907D02*
X880270Y719174D01*
G01X873002Y714240D02*
X878496Y719734D01*
G01X873002Y716573D02*
X876971Y720542D01*
G01X873002Y718907D02*
X875655Y721560D01*
G01X870991Y719229D02*
X874536Y722775D01*
G01X868658Y719229D02*
X873618Y724189D01*
G01X866324Y719229D02*
X872924Y725829D01*
G01X863991Y719229D02*
X870591Y725829D01*
G01X872925D02*
G03X891779I9427J3024D01*
G01X891702Y677678D02*
X873002Y696378D01*
G01X887198Y679848D02*
X873002Y694045D01*
G01X883703Y681010D02*
X873002Y691711D01*
G01X881330Y681049D02*
X873002Y689377D01*
G01X879392Y680653D02*
X873002Y687044D01*
G01X877738Y679974D02*
X873002Y684711D01*
G01X876310Y679069D02*
X873002Y682377D01*
G01X875080Y677966D02*
X873002Y680044D01*
G01X874045Y676668D02*
X873002Y677711D01*
G01X873215Y675163D02*
X873002Y675377D01*
G01X878929Y680497D02*
X891702Y693270D01*
G01X873002Y676905D02*
X891702Y695603D01*
G01X873002Y679238D02*
X891702Y697938D01*
G01X873002Y681571D02*
X891702Y700271D01*
G01X873002Y683905D02*
X891702Y702604D01*
G01X873002Y686238D02*
X891702Y704938D01*
G01X873002Y688571D02*
X891702Y707271D01*
G01X873002Y674644D02*
Y719229D01*
G01Y674645D02*
Y674644D01*
G01X891701Y674645D02*
G03X873003I-9349J-3541D01*
G01X987952Y632764D02*
X985637Y635078D01*
G01X987952Y630431D02*
X984377Y634006D01*
G01X987952Y628098D02*
X984377Y631673D01*
G01X987225Y626490D02*
X984377Y629338D01*
G01X986058Y625324D02*
X983178Y628204D01*
G01X984377Y629605D02*
X987952Y633180D01*
G01X984377Y631938D02*
X987517Y635079D01*
G01X984377Y634272D02*
X985184Y635079D01*
G01X987952D02*
Y627218D01*
G01X984377Y635079D02*
X987952D01*
G01X984377Y628204D02*
Y635079D01*
G01X984420Y624629D02*
X980845Y628204D01*
G01X984069Y624629D02*
X987952Y628512D01*
G01X981735Y624629D02*
X987952Y630845D01*
G01X979402Y624629D02*
X982977Y628204D01*
G01X987952Y627218D02*
X985362Y624629D01*
G01X982086D02*
X978512Y628204D01*
G01X979752Y624629D02*
X976177Y628204D01*
G01X968702D02*
X984377D01*
G01X968702Y719504D02*
Y628204D01*
G01X977419Y624629D02*
X973844Y628204D01*
G01X975085Y624629D02*
X971511Y628204D01*
G01X972752Y624629D02*
X969177Y628204D01*
G01X977068Y624629D02*
X980642Y628204D01*
G01X974734Y624629D02*
X978309Y628204D01*
G01X972401Y624629D02*
X975976Y628204D01*
G01X970068Y624629D02*
X973643Y628204D01*
G01X967734Y624629D02*
X971309Y628204D01*
G01X965401Y624629D02*
X968976Y628204D01*
G01X963068Y624629D02*
X968702Y630263D01*
G01X960733Y624629D02*
X968702Y632597D01*
G01X958400Y624629D02*
X968702Y634931D01*
G01X987952Y721436D02*
X983558Y725829D01*
G01X987952Y719102D02*
X981224Y725829D01*
G01X987952Y714435D02*
X984377Y718009D01*
G01X987424Y712629D02*
X984377Y715676D01*
G01X985091Y712629D02*
X984377Y713343D01*
G01X985731Y712629D02*
X987952Y714850D01*
G01X984377Y713608D02*
X987952Y717183D01*
G01X984377Y715942D02*
X987952Y719517D01*
G01X984377Y718276D02*
X987952Y721851D01*
G01X983271Y719504D02*
X987480Y723712D01*
G01X980938Y719504D02*
X986313Y724879D01*
G01X984377Y712629D02*
Y719504D01*
G01X987952Y712629D02*
X984377D01*
G01X987952Y723240D02*
Y712629D01*
G01X985362Y725829D02*
X987952Y723240D01*
G01Y716769D02*
X978891Y725829D01*
G01X968779D02*
X985362D01*
G01X982883Y719504D02*
X976558Y725829D01*
G01X980549Y719504D02*
X974224Y725829D01*
G01X978216Y719504D02*
X971891Y725829D01*
G01X975883Y719504D02*
X969558Y725829D01*
G01X973548Y719504D02*
X968343Y724709D01*
G01X971215Y719504D02*
X967496Y723223D01*
G01X968882Y719504D02*
X966442Y721943D01*
G01X968702Y717350D02*
X965193Y720859D01*
G01X968702Y715017D02*
X963741Y719978D01*
G01X968702Y712684D02*
X962057Y719329D01*
G01X968702Y710350D02*
X960073Y718978D01*
G01X978605Y719504D02*
X984930Y725829D01*
G01X976271Y719504D02*
X982596Y725829D01*
G01X973938Y719504D02*
X980263Y725829D01*
G01X971605Y719504D02*
X977930Y725829D01*
G01X969271Y719504D02*
X975596Y725829D01*
G01X984377Y719504D02*
X968702D01*
G01X1120658Y632879D02*
X1122702Y634922D01*
G01X1118325Y632879D02*
X1122702Y637256D01*
G01X1115991Y632879D02*
X1122702Y639589D01*
G01X1113658Y632879D02*
X1122702Y641922D01*
G01X1111325Y632879D02*
X1122702Y644257D01*
G01Y714829D02*
Y632879D01*
G01X1104002Y658224D02*
X1122702Y676924D01*
G01X1104002Y660559D02*
X1122702Y679259D01*
G01X1104002Y662892D02*
X1122702Y681592D01*
G01X1104002Y665225D02*
X1122702Y683925D01*
G01Y663689D02*
X1104002Y682389D01*
G01X1122702Y661356D02*
X1104002Y680056D01*
G01X1122702Y659023D02*
X1104002Y677722D01*
G01X1122702Y656689D02*
X1104002Y675389D01*
G01X1122702Y654356D02*
X1104002Y673056D01*
G01X1122702Y652023D02*
X1104002Y670721D01*
G01X1122702Y649688D02*
X1104002Y668388D01*
G01X1122702Y647355D02*
X1104002Y666055D01*
G01X1108990Y632879D02*
X1122702Y646590D01*
G01X1106657Y632879D02*
X1122702Y648923D01*
G01X1104324Y632879D02*
X1122702Y651257D01*
G01X1104002Y634890D02*
X1122702Y653590D01*
G01X1104002Y637224D02*
X1122702Y655923D01*
G01X1104002Y639557D02*
X1122702Y658257D01*
G01X1104002Y641890D02*
X1122702Y660590D01*
G01X1104002Y644225D02*
X1122702Y662924D01*
G01X1104002Y646558D02*
X1122702Y665258D01*
G01X1104002Y648891D02*
X1122702Y667591D01*
G01X1104002Y651225D02*
X1122702Y669924D01*
G01X1104002Y653558D02*
X1122702Y672258D01*
G01X1104002Y655891D02*
X1122702Y674591D01*
G01Y645022D02*
X1104002Y663721D01*
G01X1122702Y642688D02*
X1104002Y661388D01*
G01X1122702Y640355D02*
X1104002Y659055D01*
G01X1122702Y638022D02*
X1104002Y656721D01*
G01X1122702Y635688D02*
X1104002Y654388D01*
G01X1122702Y633354D02*
X1104002Y652054D01*
G01X1120844Y632879D02*
X1104002Y649720D01*
G01X1118510Y632879D02*
X1104002Y647387D01*
G01X1116177Y632879D02*
X1104002Y645054D01*
G01X1113844Y632879D02*
X1104002Y642720D01*
G01X1111509Y632879D02*
X1104002Y640387D01*
G01X1109176Y632879D02*
X1104002Y638054D01*
G01X1106843Y632879D02*
X1104002Y635721D01*
G01X1104509Y632879D02*
X1104002Y633386D01*
G01X1122702Y632879D02*
X1104002D01*
G01D02*
Y714829D01*
G01X1122702Y712692D02*
X1120565Y714829D01*
G01X1122702Y710359D02*
X1118231Y714829D01*
G01X1122702Y708025D02*
X1115897Y714829D01*
G01X1122702Y705692D02*
X1113564Y714829D01*
G01X1104002Y690893D02*
X1122702Y709593D01*
G01X1104002Y693226D02*
X1122702Y711926D01*
G01X1104002Y695561D02*
X1122702Y714259D01*
G01X1104002Y697894D02*
X1120937Y714829D01*
G01X1104002Y700227D02*
X1118604Y714829D01*
G01X1104002Y702561D02*
X1116270Y714829D01*
G01X1104002Y704894D02*
X1113937Y714829D01*
G01X1104002Y707227D02*
X1111604Y714829D01*
G01X1104002Y709561D02*
X1109270Y714829D01*
G01X1104002Y711894D02*
X1106937Y714829D01*
G01X1104002Y714228D02*
X1104604Y714829D01*
G01X1122702Y703358D02*
X1111231Y714829D01*
G01X1122702Y701024D02*
X1108897Y714829D01*
G01X1122702Y698691D02*
X1106564Y714829D01*
G01X1122702Y696358D02*
X1104231Y714829D01*
G01X1122702Y694024D02*
X1104002Y712724D01*
G01X1122702Y691691D02*
X1104002Y710391D01*
G01X1122702Y689358D02*
X1104002Y708057D01*
G01X1122702Y687023D02*
X1104002Y705723D01*
G01X1122702Y684690D02*
X1104002Y703390D01*
G01X1122702Y682357D02*
X1104002Y701056D01*
G01X1122702Y680023D02*
X1104002Y698723D01*
G01Y714829D02*
X1122702D01*
G01X1104002Y667559D02*
X1122702Y686258D01*
G01X1104002Y669892D02*
X1122702Y688592D01*
G01X1104002Y672225D02*
X1122702Y690925D01*
G01X1104002Y674559D02*
X1122702Y693258D01*
G01X1104002Y676892D02*
X1122702Y695592D01*
G01X1104002Y679226D02*
X1122702Y697926D01*
G01X1104002Y681560D02*
X1122702Y700259D01*
G01X1104002Y683893D02*
X1122702Y702593D01*
G01X1104002Y686226D02*
X1122702Y704926D01*
G01X1104002Y688560D02*
X1122702Y707259D01*
G01Y677690D02*
X1104002Y696390D01*
G01X1122702Y675357D02*
X1104002Y694057D01*
G01X1122702Y673023D02*
X1104002Y691723D01*
G01X1122702Y670690D02*
X1104002Y689390D01*
G01X1122702Y668356D02*
X1104002Y687056D01*
G01X1122702Y666022D02*
X1104002Y684722D01*
G01X1181002Y658221D02*
X1199702Y676921D01*
G01X1181002Y660554D02*
X1199702Y679254D01*
G01X1181002Y662888D02*
X1199702Y681587D01*
G01X1181002Y665221D02*
X1199702Y683921D01*
G01Y663694D02*
X1181002Y682392D01*
G01X1199702Y661359D02*
X1181002Y680059D01*
G01X1199702Y659026D02*
X1181002Y677726D01*
G01X1197662Y632879D02*
X1199702Y634919D01*
G01X1195328Y632879D02*
X1199702Y637252D01*
G01X1192995Y632879D02*
X1199702Y639586D01*
G01X1190662Y632879D02*
X1199702Y641919D01*
G01X1188328Y632879D02*
X1199702Y644252D01*
G01X1185995Y632879D02*
X1199702Y646585D01*
G01X1183662Y632879D02*
X1199702Y648919D01*
G01X1181327Y632879D02*
X1199702Y651253D01*
G01X1181002Y634887D02*
X1199702Y653586D01*
G01X1181002Y637220D02*
X1199702Y655920D01*
G01X1181002Y639553D02*
X1199702Y658253D01*
G01X1181002Y641887D02*
X1199702Y660586D01*
G01X1181002Y644220D02*
X1199702Y662920D01*
G01X1181002Y646553D02*
X1199702Y665253D01*
G01X1181002Y648888D02*
X1199702Y667586D01*
G01X1181002Y651221D02*
X1199702Y669921D01*
G01X1181002Y653554D02*
X1199702Y672254D01*
G01X1181002Y655888D02*
X1199702Y674587D01*
G01Y656693D02*
X1181002Y675393D01*
G01X1199702Y654359D02*
X1181002Y673059D01*
G01X1199702Y652026D02*
X1181002Y670726D01*
G01X1199702Y649693D02*
X1181002Y668393D01*
G01X1199702Y647360D02*
X1181002Y666059D01*
G01X1199702Y645025D02*
X1181002Y663725D01*
G01X1199702Y642692D02*
X1181002Y661392D01*
G01X1199702Y640359D02*
X1181002Y659058D01*
G01X1199702Y638025D02*
X1181002Y656725D01*
G01X1199702Y635692D02*
X1181002Y654392D01*
G01X1199702Y633359D02*
X1181002Y652058D01*
G01X1197847Y632879D02*
X1181002Y649725D01*
G01X1195514Y632879D02*
X1181002Y647392D01*
G01X1193181Y632879D02*
X1181002Y645057D01*
G01X1190847Y632879D02*
X1181002Y642724D01*
G01X1188514Y632879D02*
X1181002Y640391D01*
G01X1186181Y632879D02*
X1181002Y638057D01*
G01X1183846Y632879D02*
X1181002Y635724D01*
G01X1181513Y632879D02*
X1181002Y633391D01*
G01X1199702Y632879D02*
X1181002D01*
G01X1199702Y714829D02*
Y632879D01*
G01X1181002D02*
Y714829D01*
G01Y690889D02*
X1199702Y709589D01*
G01X1181002Y693223D02*
X1199702Y711922D01*
G01X1181002Y695556D02*
X1199702Y714256D01*
G01X1181002Y697889D02*
X1197941Y714829D01*
G01X1181002Y700223D02*
X1195608Y714829D01*
G01X1181002Y702557D02*
X1193275Y714829D01*
G01X1181002Y704890D02*
X1190940Y714829D01*
G01X1181002Y707224D02*
X1188607Y714829D01*
G01X1181002Y709557D02*
X1186274Y714829D01*
G01X1181002Y711890D02*
X1183940Y714829D01*
G01X1181002Y714224D02*
X1181607Y714829D01*
G01X1199702Y712695D02*
X1197568Y714829D01*
G01X1199702Y710362D02*
X1195235Y714829D01*
G01X1199702Y708029D02*
X1192902Y714829D01*
G01X1199702Y705696D02*
X1190569Y714829D01*
G01X1199702Y703362D02*
X1188234Y714829D01*
G01X1199702Y701029D02*
X1185901Y714829D01*
G01X1199702Y698696D02*
X1183568Y714829D01*
G01X1199702Y696361D02*
X1181234Y714829D01*
G01X1199702Y694028D02*
X1181002Y712728D01*
G01X1199702Y691695D02*
X1181002Y710394D01*
G01Y714829D02*
X1199702D01*
G01X1181002Y667555D02*
X1199702Y686255D01*
G01X1181002Y669888D02*
X1199702Y688588D01*
G01X1181002Y672222D02*
X1199702Y690922D01*
G01X1181002Y674555D02*
X1199702Y693255D01*
G01X1181002Y676888D02*
X1199702Y695588D01*
G01X1181002Y679222D02*
X1199702Y697922D01*
G01X1181002Y681555D02*
X1199702Y700255D01*
G01X1181002Y683888D02*
X1199702Y702588D01*
G01X1181002Y686223D02*
X1199702Y704922D01*
G01X1181002Y688556D02*
X1199702Y707256D01*
G01Y689361D02*
X1181002Y708061D01*
G01X1199702Y687028D02*
X1181002Y705728D01*
G01X1199702Y684695D02*
X1181002Y703394D01*
G01X1199702Y682361D02*
X1181002Y701061D01*
G01X1199702Y680027D02*
X1181002Y698727D01*
G01X1199702Y677694D02*
X1181002Y696393D01*
G01X1199702Y675360D02*
X1181002Y694060D01*
G01X1199702Y673027D02*
X1181002Y691727D01*
G01X1199702Y670694D02*
X1181002Y689393D01*
G01X1199702Y668360D02*
X1181002Y687060D01*
G01X1199702Y666027D02*
X1181002Y684727D01*
M02*
